FILE_TYPE=EXPANDEDPARTLIST;
{ Packager-XL run on 16-Jun-2017 AT 17:50:48 }
DIRECTIVES
 PST_VERSION='PST_HDL_CENTRIC_VERSION_0';
 ROOT_DRAWING='BASEBOARD_FAB2';
 POST_TIME='16-Jun-2017 AT 17:50:48';
 SOURCE_TOOL='PACKAGER_XL';
END_DIRECTIVES;

PART_NAME
 BT8G1 'BATTERY_PLCLF-202168-001':
 ROOM='SB_VRD';

SECTION_NUMBER -1
 '@BASEBOARD_FAB2_LIB.BASEBOARD_FAB2(SCH_1):PAGE196_I47@MSTR_MISC.BATTERY(CHIPS)':
 C_PATH='@baseboard_fab2_lib.baseboard_fab2(sch_1):page196_i47@mstr_misc.battery~
(chips)',
 P_PATH='@baseboard_fab2_lib.baseboard_fab2(sch_1):page196_i47@mstr_misc.battery~
(chips)',
 PATH='I47',
 DRAWING='@BASEBOARD_FAB2_LIB.BASEBOARD_FAB2(SCH_1):PAGE196',
 BOM_COST='SB',
 PHYS_PAGE='196',
 XY='(-4375,4200)',
 ROT='0',
 VER='1',
 PACK_TYPE='PLCLF',
 PART_NUMBER='202168-001',
 LOCATION='BT8G1',
 ROOM='SB_VRD',
 CDS_LIB='mstr_misc',
 CDS_PART_NAME='BATTERY_PLCLF-202168-001',
 PRIM_FILE='./archive_libs/mstr_misc/battery/chips/chips.prt';

PART_NAME
 C1A1 'CAP_0805LF-22UF,4V,20%,X6S,C95A':
 GROUP='PWR_MLCC_CAP',
 ROOM='VDDQ_KLM_PWR_VR';

SECTION_NUMBER 1
 '@BASEBOARD_FAB2_LIB.BASEBOARD_FAB2(SCH_1):PAGE227_I68@MSTR_DISCRETE.CAP(CHIPS)':
 C_PATH='@baseboard_fab2_lib.baseboard_fab2(sch_1):page227_i68@mstr_discrete.cap~
(chips)',
 P_PATH='@baseboard_fab2_lib.baseboard_fab2(sch_1):page227_i68@mstr_discrete.cap~
(chips)',
 PATH='I68',
 DRAWING='@BASEBOARD_FAB2_LIB.BASEBOARD_FAB2(SCH_1):PAGE227',
 BOM_SS='NOPOP',
 TOLERANCE='20%',
 SEC_TYPE='0805LF',
 MATERIAL='X6S',
 BOM_COST='VDDQ_KLM_PWR_VR',
 PHYS_PAGE='227',
 XY='(4375,-475)',
 ROT='0',
 VER='1',
 VALUE='22UF',
 PACK_TYPE='0805LF',
 PART_NUMBER='C95333-002',
 LOCATION='C1A1',
 ROOM='VDDQ_KLM_PWR_VR',
 GROUP='PWR_MLCC_CAP',
 SEC='1',
 CDS_LIB='mstr_discrete',
 CDS_PART_NAME='CAP_0805LF-22UF,4V,20%,X6S,C95A',
 VOLTAGE='4V',
 PRIM_FILE='./archive_libs/mstr_discrete/cap/chips/chips.prt';

PART_NAME
 C1A2 'SC1U10V2KX-4-GP_SMD-BCG6-SC1U1A':;

SECTION_NUMBER 1
 '@BASEBOARD_FAB2_LIB.BASEBOARD_FAB2(SCH_1):PAGE227_I148@W_HDL.SC1U10V2KX-4-GP(CHIPS)':
 C_PATH='@baseboard_fab2_lib.baseboard_fab2(sch_1):page227_i148@w_hdl.\sc1u10v2k~
x-4-gp\(chips)',
 P_PATH='@baseboard_fab2_lib.baseboard_fab2(sch_1):page227_i148@w_hdl.\sc1u10v2k~
x-4-gp\(chips)',
 PATH='I148',
 DRAWING='@BASEBOARD_FAB2_LIB.BASEBOARD_FAB2(SCH_1):PAGE227',
 PACK_SIZE='0402',
 RATED='10V',
 ATTRIBUTE='1UF',
 TOLERANCE='10%',
 SEC_TYPE='SMD-BCG6',
 PHYS_PAGE='227',
 XY='(-475,2475)',
 ROT='0',
 VER='1',
 VALUE='SC1U10V2KX-4-GP',
 PACK_TYPE='SMD-BCG6',
 PART_NUMBER='78.10523.8FL',
 LOCATION='C1A2',
 SEC='1',
 CDS_LIB='w_hdl',
 CDS_PART_NAME='SC1U10V2KX-4-GP_SMD-BCG6-SC1U1A',
 PRIM_FILE='C:/<user>/w_hdl/sc1u10v2kx#2d4#2dgp/chips/chips.prt';

PART_NAME
 C1A4 'CAP_0805-10UF,16V,10%,X7R,G106A':
 ROOM='PVDDQ_KLM_PWR_VR';

SECTION_NUMBER 1
 '@BASEBOARD_FAB2_LIB.BASEBOARD_FAB2(SCH_1):PAGE197_I60@MSTR_DISCRETE.CAP(CHIPS)':
 C_PATH='@baseboard_fab2_lib.baseboard_fab2(sch_1):page197_i60@mstr_discrete.cap~
(chips)',
 P_PATH='@baseboard_fab2_lib.baseboard_fab2(sch_1):page197_i60@mstr_discrete.cap~
(chips)',
 PATH='I60',
 DRAWING='@BASEBOARD_FAB2_LIB.BASEBOARD_FAB2(SCH_1):PAGE197',
 TOLERANCE='10%',
 MATERIAL='X7R',
 PHYS_PAGE='197',
 XY='(2175,1275)',
 ROT='0',
 VER='1',
 VALUE='10UF',
 PACK_TYPE='0805',
 PART_NUMBER='G10601-001',
 LOCATION='C1A4',
 ROOM='PVDDQ_KLM_PWR_VR',
 CDS_LIB='mstr_discrete',
 CDS_PART_NAME='CAP_0805-10UF,16V,10%,X7R,G106A',
 VOLTAGE='16V',
 PRIM_FILE='./archive_libs/mstr_discrete/cap/chips/chips.prt';

PART_NAME
 C1A5 'CAP_A_0402V-0.01UF,25V,10%,X7RA':
 ROOM='DDR4_CH_M';

SECTION_NUMBER 1
 '@BASEBOARD_FAB2_LIB.BASEBOARD_FAB2(SCH_1):PAGE87_I178@DEV_DISCRETE.CAP_A(CHIPS)':
 C_PATH='@baseboard_fab2_lib.baseboard_fab2(sch_1):page87_i178@dev_discrete.cap_~
a(chips)',
 P_PATH='@baseboard_fab2_lib.baseboard_fab2(sch_1):page87_i178@dev_discrete.cap_~
a(chips)',
 PATH='I178',
 DRAWING='@BASEBOARD_FAB2_LIB.BASEBOARD_FAB2(SCH_1):PAGE87',
 TOLERANCE='10%',
 SEC_TYPE='0402V',
 MATERIAL='X7R',
 BOM_COST='MEM',
 PHYS_PAGE='87',
 XY='(-4650,1550)',
 ROT='2',
 VER='1',
 VALUE='0.01UF',
 PACK_TYPE='0402V',
 PART_NUMBER='A36096-045',
 LOCATION='C1A5',
 ROOM='DDR4_CH_M',
 SEC='1',
 CDS_LIB='dev_discrete',
 CDS_PART_NAME='CAP_A_0402V-0.01UF,25V,10%,X7RA',
 VOLTAGE='25V',
 PRIM_FILE='./archive_libs/discrete/cap_a/chips/chips.prt';

PART_NAME
 C1A6 'CAP_0402-1.0UF,16V,10%,X6S,D97A':
 ROOM='VDDQ_KLM_PWR_VR';

SECTION_NUMBER 1
 '@BASEBOARD_FAB2_LIB.BASEBOARD_FAB2(SCH_1):PAGE227_I77@MSTR_DISCRETE.CAP(CHIPS)':
 C_PATH='@baseboard_fab2_lib.baseboard_fab2(sch_1):page227_i77@mstr_discrete.cap~
(chips)',
 P_PATH='@baseboard_fab2_lib.baseboard_fab2(sch_1):page227_i77@mstr_discrete.cap~
(chips)',
 PATH='I77',
 DRAWING='@BASEBOARD_FAB2_LIB.BASEBOARD_FAB2(SCH_1):PAGE227',
 BOM_SS='NOPOP',
 TOLERANCE='10%',
 SEC_TYPE='0402',
 MATERIAL='X6S',
 PHYS_PAGE='227',
 XY='(-825,250)',
 ROT='0',
 VER='1',
 VALUE='1.0UF',
 PACK_TYPE='0402',
 PART_NUMBER='D97712-011',
 LOCATION='C1A6',
 ROOM='VDDQ_KLM_PWR_VR',
 SEC='1',
 CDS_LIB='mstr_discrete',
 CDS_PART_NAME='CAP_0402-1.0UF,16V,10%,X6S,D97A',
 VOLTAGE='16V',
 PRIM_FILE='./archive_libs/mstr_discrete/cap/chips/chips.prt';

PART_NAME
 C1A8 'CAP_0402-0.220UF,16V,10%,X7R,AA':
 ROOM='VDDQ_KLM_PWR_VR';

SECTION_NUMBER 1
 '@BASEBOARD_FAB2_LIB.BASEBOARD_FAB2(SCH_1):PAGE227_I75@MSTR_DISCRETE.CAP(CHIPS)':
 C_PATH='@baseboard_fab2_lib.baseboard_fab2(sch_1):page227_i75@mstr_discrete.cap~
(chips)',
 P_PATH='@baseboard_fab2_lib.baseboard_fab2(sch_1):page227_i75@mstr_discrete.cap~
(chips)',
 PATH='I75',
 DRAWING='@BASEBOARD_FAB2_LIB.BASEBOARD_FAB2(SCH_1):PAGE227',
 BOM_SS='NOPOP',
 SPOF='TRUE',
 TOLERANCE='10%',
 SEC_TYPE='0402',
 MATERIAL='X7R',
 PHYS_PAGE='227',
 XY='(-775,-350)',
 ROT='2',
 VER='1',
 VALUE='0.220UF',
 PACK_TYPE='0402',
 PART_NUMBER='A36096-104',
 LOCATION='C1A8',
 ROOM='VDDQ_KLM_PWR_VR',
 SEC='1',
 CDS_LIB='mstr_discrete',
 CDS_PART_NAME='CAP_0402-0.220UF,16V,10%,X7R,AA',
 VOLTAGE='16V',
 PRIM_FILE='./archive_libs/mstr_discrete/cap/chips/chips.prt';

PART_NAME
 C1A9 'CAP_0402-1.0UF,16V,10%,X6S,D97A':
 ROOM='VDDQ_KLM_PWR_VR';

SECTION_NUMBER 1
 '@BASEBOARD_FAB2_LIB.BASEBOARD_FAB2(SCH_1):PAGE227_I79@MSTR_DISCRETE.CAP(CHIPS)':
 C_PATH='@baseboard_fab2_lib.baseboard_fab2(sch_1):page227_i79@mstr_discrete.cap~
(chips)',
 P_PATH='@baseboard_fab2_lib.baseboard_fab2(sch_1):page227_i79@mstr_discrete.cap~
(chips)',
 PATH='I79',
 DRAWING='@BASEBOARD_FAB2_LIB.BASEBOARD_FAB2(SCH_1):PAGE227',
 TOLERANCE='10%',
 SEC_TYPE='0402',
 MATERIAL='X6S',
 PHYS_PAGE='227',
 XY='(-1350,250)',
 ROT='0',
 VER='1',
 VALUE='1.0UF',
 PACK_TYPE='0402',
 PART_NUMBER='D97712-011',
 LOCATION='C1A9',
 ROOM='VDDQ_KLM_PWR_VR',
 SEC='1',
 CDS_LIB='mstr_discrete',
 CDS_PART_NAME='CAP_0402-1.0UF,16V,10%,X6S,D97A',
 VOLTAGE='16V',
 PRIM_FILE='./archive_libs/mstr_discrete/cap/chips/chips.prt';

PART_NAME
 C1A10 'CAP_A_0402V-0.1UF,16V,10%,X7R,A':
 ROOM='VDDQ_KLM_PWR_VR';

SECTION_NUMBER 1
 '@BASEBOARD_FAB2_LIB.BASEBOARD_FAB2(SCH_1):PAGE227_I51@DEV_DISCRETE.CAP_A(CHIPS)':
 C_PATH='@baseboard_fab2_lib.baseboard_fab2(sch_1):page227_i51@dev_discrete.cap_~
a(chips)',
 P_PATH='@baseboard_fab2_lib.baseboard_fab2(sch_1):page227_i51@dev_discrete.cap_~
a(chips)',
 PATH='I51',
 DRAWING='@BASEBOARD_FAB2_LIB.BASEBOARD_FAB2(SCH_1):PAGE227',
 TOLERANCE='10%',
 SEC_TYPE='0402V',
 MATERIAL='X7R',
 PHYS_PAGE='227',
 XY='(-1175,2475)',
 ROT='0',
 VER='1',
 VALUE='0.1UF',
 PACK_TYPE='0402V',
 PART_NUMBER='A36096-030',
 LOCATION='C1A10',
 ROOM='VDDQ_KLM_PWR_VR',
 SEC='1',
 CDS_LIB='dev_discrete',
 CDS_PART_NAME='CAP_A_0402V-0.1UF,16V,10%,X7R,A',
 VOLTAGE='16V',
 PRIM_FILE='./archive_libs/discrete/cap_a/chips/chips.prt';

PART_NAME
 C1A11 'SC1U10V2KX-4-GP_SMD-BCG6-SC1U1A':;

SECTION_NUMBER 1
 '@BASEBOARD_FAB2_LIB.BASEBOARD_FAB2(SCH_1):PAGE227_I147@W_HDL.SC1U10V2KX-4-GP(CHIPS)':
 C_PATH='@baseboard_fab2_lib.baseboard_fab2(sch_1):page227_i147@w_hdl.\sc1u10v2k~
x-4-gp\(chips)',
 P_PATH='@baseboard_fab2_lib.baseboard_fab2(sch_1):page227_i147@w_hdl.\sc1u10v2k~
x-4-gp\(chips)',
 PATH='I147',
 DRAWING='@BASEBOARD_FAB2_LIB.BASEBOARD_FAB2(SCH_1):PAGE227',
 PACK_SIZE='0402',
 RATED='10V',
 ATTRIBUTE='1UF',
 BOM_SS='NOPOP',
 TOLERANCE='10%',
 SEC_TYPE='SMD-BCG6',
 PHYS_PAGE='227',
 XY='(-425,225)',
 ROT='0',
 VER='1',
 VALUE='SC1U10V2KX-4-GP',
 PACK_TYPE='SMD-BCG6',
 PART_NUMBER='78.10523.8FL',
 LOCATION='C1A11',
 SEC='1',
 CDS_LIB='w_hdl',
 CDS_PART_NAME='SC1U10V2KX-4-GP_SMD-BCG6-SC1U1A',
 PRIM_FILE='C:/<user>/w_hdl/sc1u10v2kx#2d4#2dgp/chips/chips.prt';

PART_NAME
 C1A12 'CAP_0805LF-22UF,4V,20%,X6S,C95A':
 GROUP='PWR_MLCC_CAP',
 ROOM='VDDQ_KLM_PWR_VR';

SECTION_NUMBER 1
 '@BASEBOARD_FAB2_LIB.BASEBOARD_FAB2(SCH_1):PAGE227_I6@MSTR_DISCRETE.CAP(CHIPS)':
 C_PATH='@baseboard_fab2_lib.baseboard_fab2(sch_1):page227_i6@mstr_discrete.cap(~
chips)',
 P_PATH='@baseboard_fab2_lib.baseboard_fab2(sch_1):page227_i6@mstr_discrete.cap(~
chips)',
 PATH='I6',
 DRAWING='@BASEBOARD_FAB2_LIB.BASEBOARD_FAB2(SCH_1):PAGE227',
 TOLERANCE='20%',
 SEC_TYPE='0805LF',
 MATERIAL='X6S',
 BOM_COST='VDDQ_KLM_PWR_VR',
 PHYS_PAGE='227',
 XY='(4350,1775)',
 ROT='0',
 VER='1',
 VALUE='22UF',
 PACK_TYPE='0805LF',
 PART_NUMBER='C95333-002',
 LOCATION='C1A12',
 ROOM='VDDQ_KLM_PWR_VR',
 GROUP='PWR_MLCC_CAP',
 SEC='1',
 CDS_LIB='mstr_discrete',
 CDS_PART_NAME='CAP_0805LF-22UF,4V,20%,X6S,C95A',
 VOLTAGE='4V',
 PRIM_FILE='./archive_libs/mstr_discrete/cap/chips/chips.prt';

PART_NAME
 C1A13 'CAP_0402-0.22UF,16V,10%,X7R,A3A':
 ROOM='VDDQ_KLM_PWR_VR';

SECTION_NUMBER 1
 '@BASEBOARD_FAB2_LIB.BASEBOARD_FAB2(SCH_1):PAGE227_I72@MSTR_DISCRETE.CAP(CHIPS)':
 C_PATH='@baseboard_fab2_lib.baseboard_fab2(sch_1):page227_i72@mstr_discrete.cap~
(chips)',
 P_PATH='@baseboard_fab2_lib.baseboard_fab2(sch_1):page227_i72@mstr_discrete.cap~
(chips)',
 PATH='I72',
 DRAWING='@BASEBOARD_FAB2_LIB.BASEBOARD_FAB2(SCH_1):PAGE227',
 BOM_SS='NOPOP',
 TOLERANCE='10%',
 SEC_TYPE='0402',
 MATERIAL='X7R',
 PHYS_PAGE='227',
 XY='(-75,250)',
 ROT='0',
 VER='1',
 VALUE='0.22UF',
 PACK_TYPE='0402',
 PART_NUMBER='A36096-155',
 LOCATION='C1A13',
 ROOM='VDDQ_KLM_PWR_VR',
 SEC='1',
 CDS_LIB='mstr_discrete',
 CDS_PART_NAME='CAP_0402-0.22UF,16V,10%,X7R,A3A',
 VOLTAGE='16V',
 PRIM_FILE='./archive_libs/mstr_discrete/cap/chips/chips.prt';

PART_NAME
 C1A16 'CAP_0805-10UF,16V,10%,X7R,G106A':
 ROOM='PVDDQ_KLM_PWR_VR';

SECTION_NUMBER 1
 '@BASEBOARD_FAB2_LIB.BASEBOARD_FAB2(SCH_1):PAGE197_I75@MSTR_DISCRETE.CAP(CHIPS)':
 C_PATH='@baseboard_fab2_lib.baseboard_fab2(sch_1):page197_i75@mstr_discrete.cap~
(chips)',
 P_PATH='@baseboard_fab2_lib.baseboard_fab2(sch_1):page197_i75@mstr_discrete.cap~
(chips)',
 PATH='I75',
 DRAWING='@BASEBOARD_FAB2_LIB.BASEBOARD_FAB2(SCH_1):PAGE197',
 TOLERANCE='10%',
 MATERIAL='X7R',
 PHYS_PAGE='197',
 XY='(2175,2500)',
 ROT='0',
 VER='1',
 VALUE='10UF',
 PACK_TYPE='0805',
 PART_NUMBER='G10601-001',
 LOCATION='C1A16',
 ROOM='PVDDQ_KLM_PWR_VR',
 CDS_LIB='mstr_discrete',
 CDS_PART_NAME='CAP_0805-10UF,16V,10%,X7R,G106A',
 VOLTAGE='16V',
 PRIM_FILE='./archive_libs/mstr_discrete/cap/chips/chips.prt';

PART_NAME
 C1A17 'CAP_A_0402V-0.01UF,25V,10%,X7RA':
 ROOM='DDR4_CH_D';

SECTION_NUMBER 1
 '@BASEBOARD_FAB2_LIB.BASEBOARD_FAB2(SCH_1):PAGE86_I182@DEV_DISCRETE.CAP_A(CHIPS)':
 C_PATH='@baseboard_fab2_lib.baseboard_fab2(sch_1):page86_i182@dev_discrete.cap_~
a(chips)',
 P_PATH='@baseboard_fab2_lib.baseboard_fab2(sch_1):page86_i182@dev_discrete.cap_~
a(chips)',
 PATH='I182',
 DRAWING='@BASEBOARD_FAB2_LIB.BASEBOARD_FAB2(SCH_1):PAGE86',
 TOLERANCE='10%',
 MATERIAL='X7R',
 BOM_COST='MEM',
 PHYS_PAGE='86',
 XY='(-3025,1225)',
 ROT='2',
 VER='1',
 VALUE='0.01UF',
 PACK_TYPE='0402V',
 PART_NUMBER='A36096-045',
 LOCATION='C1A17',
 ROOM='DDR4_CH_D',
 CDS_LIB='dev_discrete',
 CDS_PART_NAME='CAP_A_0402V-0.01UF,25V,10%,X7RA',
 VOLTAGE='25V',
 PRIM_FILE='./archive_libs/discrete/cap_a/chips/chips.prt';

PART_NAME
 C1A18 'CAP_0402-0.220UF,16V,10%,X7R,AA':
 ROOM='VDDQ_KLM_PWR_VR';

SECTION_NUMBER 1
 '@BASEBOARD_FAB2_LIB.BASEBOARD_FAB2(SCH_1):PAGE227_I44@MSTR_DISCRETE.CAP(CHIPS)':
 C_PATH='@baseboard_fab2_lib.baseboard_fab2(sch_1):page227_i44@mstr_discrete.cap~
(chips)',
 P_PATH='@baseboard_fab2_lib.baseboard_fab2(sch_1):page227_i44@mstr_discrete.cap~
(chips)',
 PATH='I44',
 DRAWING='@BASEBOARD_FAB2_LIB.BASEBOARD_FAB2(SCH_1):PAGE227',
 SPOF='TRUE',
 TOLERANCE='10%',
 SEC_TYPE='0402',
 MATERIAL='X7R',
 PHYS_PAGE='227',
 XY='(-825,1925)',
 ROT='2',
 VER='1',
 VALUE='0.220UF',
 PACK_TYPE='0402',
 PART_NUMBER='A36096-104',
 LOCATION='C1A18',
 ROOM='VDDQ_KLM_PWR_VR',
 SEC='1',
 CDS_LIB='mstr_discrete',
 CDS_PART_NAME='CAP_0402-0.220UF,16V,10%,X7R,AA',
 VOLTAGE='16V',
 PRIM_FILE='./archive_libs/mstr_discrete/cap/chips/chips.prt';

PART_NAME
 C1A19 'CAP_0402-1.0UF,16V,10%,X6S,D97A':
 ROOM='VDDQ_KLM_PWR_VR';

SECTION_NUMBER 1
 '@BASEBOARD_FAB2_LIB.BASEBOARD_FAB2(SCH_1):PAGE227_I48@MSTR_DISCRETE.CAP(CHIPS)':
 C_PATH='@baseboard_fab2_lib.baseboard_fab2(sch_1):page227_i48@mstr_discrete.cap~
(chips)',
 P_PATH='@baseboard_fab2_lib.baseboard_fab2(sch_1):page227_i48@mstr_discrete.cap~
(chips)',
 PATH='I48',
 DRAWING='@BASEBOARD_FAB2_LIB.BASEBOARD_FAB2(SCH_1):PAGE227',
 TOLERANCE='10%',
 SEC_TYPE='0402',
 MATERIAL='X6S',
 PHYS_PAGE='227',
 XY='(-1425,2475)',
 ROT='0',
 VER='1',
 VALUE='1.0UF',
 PACK_TYPE='0402',
 PART_NUMBER='D97712-011',
 LOCATION='C1A19',
 ROOM='VDDQ_KLM_PWR_VR',
 SEC='1',
 CDS_LIB='mstr_discrete',
 CDS_PART_NAME='CAP_0402-1.0UF,16V,10%,X6S,D97A',
 VOLTAGE='16V',
 PRIM_FILE='./archive_libs/mstr_discrete/cap/chips/chips.prt';

PART_NAME
 C1A20 'CAP_A_0402V-0.1UF,16V,10%,X7R,A':
 ROOM='VDDQ_KLM_PWR_VR';

SECTION_NUMBER 1
 '@BASEBOARD_FAB2_LIB.BASEBOARD_FAB2(SCH_1):PAGE227_I78@DEV_DISCRETE.CAP_A(CHIPS)':
 C_PATH='@baseboard_fab2_lib.baseboard_fab2(sch_1):page227_i78@dev_discrete.cap_~
a(chips)',
 P_PATH='@baseboard_fab2_lib.baseboard_fab2(sch_1):page227_i78@dev_discrete.cap_~
a(chips)',
 PATH='I78',
 DRAWING='@BASEBOARD_FAB2_LIB.BASEBOARD_FAB2(SCH_1):PAGE227',
 TOLERANCE='10%',
 SEC_TYPE='0402V',
 MATERIAL='X7R',
 PHYS_PAGE='227',
 XY='(-1075,250)',
 ROT='0',
 VER='1',
 VALUE='0.1UF',
 PACK_TYPE='0402V',
 PART_NUMBER='A36096-030',
 LOCATION='C1A20',
 ROOM='VDDQ_KLM_PWR_VR',
 SEC='1',
 CDS_LIB='dev_discrete',
 CDS_PART_NAME='CAP_A_0402V-0.1UF,16V,10%,X7R,A',
 VOLTAGE='16V',
 PRIM_FILE='./archive_libs/discrete/cap_a/chips/chips.prt';

PART_NAME
 C1B2 'CAP_A_0402V-0.1UF,16V,10%,X7R,A':
 ROOM='VDDQ_KLM_PWR_VR';

SECTION_NUMBER 1
 '@BASEBOARD_FAB2_LIB.BASEBOARD_FAB2(SCH_1):PAGE226_I44@DEV_DISCRETE.CAP_A(CHIPS)':
 C_PATH='@baseboard_fab2_lib.baseboard_fab2(sch_1):page226_i44@dev_discrete.cap_~
a(chips)',
 P_PATH='@baseboard_fab2_lib.baseboard_fab2(sch_1):page226_i44@dev_discrete.cap_~
a(chips)',
 PATH='I44',
 DRAWING='@BASEBOARD_FAB2_LIB.BASEBOARD_FAB2(SCH_1):PAGE226',
 TOLERANCE='10%',
 SEC_TYPE='0402V',
 MATERIAL='X7R',
 PHYS_PAGE='226',
 XY='(3100,-525)',
 ROT='0',
 VER='1',
 VALUE='0.1UF',
 PACK_TYPE='0402V',
 PART_NUMBER='A36096-030',
 LOCATION='C1B2',
 ROOM='VDDQ_KLM_PWR_VR',
 SEC='1',
 CDS_LIB='dev_discrete',
 CDS_PART_NAME='CAP_A_0402V-0.1UF,16V,10%,X7R,A',
 VOLTAGE='16V',
 PRIM_FILE='./archive_libs/discrete/cap_a/chips/chips.prt';

PART_NAME
 C1B3 'CAP_A_0402V-1.0UF,6.3V,10%,X6SA':
 ROOM='VDDQ_KLM_PWR_VR';

SECTION_NUMBER 1
 '@BASEBOARD_FAB2_LIB.BASEBOARD_FAB2(SCH_1):PAGE226_I45@DEV_DISCRETE.CAP_A(CHIPS)':
 C_PATH='@baseboard_fab2_lib.baseboard_fab2(sch_1):page226_i45@dev_discrete.cap_~
a(chips)',
 P_PATH='@baseboard_fab2_lib.baseboard_fab2(sch_1):page226_i45@dev_discrete.cap_~
a(chips)',
 PATH='I45',
 DRAWING='@BASEBOARD_FAB2_LIB.BASEBOARD_FAB2(SCH_1):PAGE226',
 TOLERANCE='10%',
 SEC_TYPE='0402V',
 MATERIAL='X6S',
 PHYS_PAGE='226',
 XY='(3500,-525)',
 ROT='0',
 VER='1',
 VALUE='1.0UF',
 PACK_TYPE='0402V',
 PART_NUMBER='D97712-004',
 LOCATION='C1B3',
 ROOM='VDDQ_KLM_PWR_VR',
 SEC='1',
 CDS_LIB='dev_discrete',
 CDS_PART_NAME='CAP_A_0402V-1.0UF,6.3V,10%,X6SA',
 VOLTAGE='6.3V',
 PRIM_FILE='./archive_libs/discrete/cap_a/chips/chips.prt';

PART_NAME
 C1B4 'CAP_0402LF-1000PF,50V,10%,X7R,A':
 ROOM='VDDQ_KLM_PWR_VR';

SECTION_NUMBER 1
 '@BASEBOARD_FAB2_LIB.BASEBOARD_FAB2(SCH_1):PAGE226_I40@MSTR_DISCRETE.CAP(CHIPS)':
 C_PATH='@baseboard_fab2_lib.baseboard_fab2(sch_1):page226_i40@mstr_discrete.cap~
(chips)',
 P_PATH='@baseboard_fab2_lib.baseboard_fab2(sch_1):page226_i40@mstr_discrete.cap~
(chips)',
 PATH='I40',
 DRAWING='@BASEBOARD_FAB2_LIB.BASEBOARD_FAB2(SCH_1):PAGE226',
 TOLERANCE='10%',
 SEC_TYPE='0402LF',
 MATERIAL='X7R',
 PHYS_PAGE='226',
 XY='(2650,275)',
 ROT='0',
 VER='1',
 VALUE='1000PF',
 PACK_TYPE='0402LF',
 PART_NUMBER='A36096-046',
 LOCATION='C1B4',
 ROOM='VDDQ_KLM_PWR_VR',
 SEC='1',
 CDS_LIB='mstr_discrete',
 CDS_PART_NAME='CAP_0402LF-1000PF,50V,10%,X7R,A',
 VOLTAGE='50V',
 PRIM_FILE='./archive_libs/mstr_discrete/cap/chips/chips.prt';

PART_NAME
 C1B5 'CAP_A_0402V-0.1UF,16V,10%,X7R,A':
 ROOM='VDDQ_KLM_PWR_VR';

SECTION_NUMBER 1
 '@BASEBOARD_FAB2_LIB.BASEBOARD_FAB2(SCH_1):PAGE226_I32@DEV_DISCRETE.CAP_A(CHIPS)':
 C_PATH='@baseboard_fab2_lib.baseboard_fab2(sch_1):page226_i32@dev_discrete.cap_~
a(chips)',
 P_PATH='@baseboard_fab2_lib.baseboard_fab2(sch_1):page226_i32@dev_discrete.cap_~
a(chips)',
 PATH='I32',
 DRAWING='@BASEBOARD_FAB2_LIB.BASEBOARD_FAB2(SCH_1):PAGE226',
 TOLERANCE='10%',
 SEC_TYPE='0402V',
 MATERIAL='X7R',
 PHYS_PAGE='226',
 XY='(675,2375)',
 ROT='0',
 VER='1',
 VALUE='0.1UF',
 PACK_TYPE='0402V',
 PART_NUMBER='A36096-030',
 LOCATION='C1B5',
 ROOM='VDDQ_KLM_PWR_VR',
 SEC='1',
 CDS_LIB='dev_discrete',
 CDS_PART_NAME='CAP_A_0402V-0.1UF,16V,10%,X7R,A',
 VOLTAGE='16V',
 PRIM_FILE='./archive_libs/discrete/cap_a/chips/chips.prt';

PART_NAME
 C1B6 'CAP_A_0402V-1.0UF,6.3V,10%,X6SA':
 ROOM='VDDQ_KLM_PWR_VR';

SECTION_NUMBER 1
 '@BASEBOARD_FAB2_LIB.BASEBOARD_FAB2(SCH_1):PAGE226_I38@DEV_DISCRETE.CAP_A(CHIPS)':
 C_PATH='@baseboard_fab2_lib.baseboard_fab2(sch_1):page226_i38@dev_discrete.cap_~
a(chips)',
 P_PATH='@baseboard_fab2_lib.baseboard_fab2(sch_1):page226_i38@dev_discrete.cap_~
a(chips)',
 PATH='I38',
 DRAWING='@BASEBOARD_FAB2_LIB.BASEBOARD_FAB2(SCH_1):PAGE226',
 TOLERANCE='10%',
 SEC_TYPE='0402V',
 MATERIAL='X6S',
 PHYS_PAGE='226',
 XY='(1275,2375)',
 ROT='0',
 VER='1',
 VALUE='1.0UF',
 PACK_TYPE='0402V',
 PART_NUMBER='D97712-004',
 LOCATION='C1B6',
 ROOM='VDDQ_KLM_PWR_VR',
 SEC='1',
 CDS_LIB='dev_discrete',
 CDS_PART_NAME='CAP_A_0402V-1.0UF,6.3V,10%,X6SA',
 VOLTAGE='6.3V',
 PRIM_FILE='./archive_libs/discrete/cap_a/chips/chips.prt';

PART_NAME
 C1B7 'CAP_0805-10UF,16V,10%,X7R,G106A':
 ROOM='PVDDQ_KLM_PWR_VR';

SECTION_NUMBER 1
 '@BASEBOARD_FAB2_LIB.BASEBOARD_FAB2(SCH_1):PAGE197_I72@MSTR_DISCRETE.CAP(CHIPS)':
 C_PATH='@baseboard_fab2_lib.baseboard_fab2(sch_1):page197_i72@mstr_discrete.cap~
(chips)',
 P_PATH='@baseboard_fab2_lib.baseboard_fab2(sch_1):page197_i72@mstr_discrete.cap~
(chips)',
 PATH='I72',
 DRAWING='@BASEBOARD_FAB2_LIB.BASEBOARD_FAB2(SCH_1):PAGE197',
 TOLERANCE='10%',
 MATERIAL='X7R',
 PHYS_PAGE='197',
 XY='(2175,1850)',
 ROT='0',
 VER='1',
 VALUE='10UF',
 PACK_TYPE='0805',
 PART_NUMBER='G10601-001',
 LOCATION='C1B7',
 ROOM='PVDDQ_KLM_PWR_VR',
 CDS_LIB='mstr_discrete',
 CDS_PART_NAME='CAP_0805-10UF,16V,10%,X7R,G106A',
 VOLTAGE='16V',
 PRIM_FILE='./archive_libs/mstr_discrete/cap/chips/chips.prt';

PART_NAME
 C1B9 'CAP_A_0402V-0.01UF,25V,10%,X7RA':
 ROOM='DDR4_CH_K';

SECTION_NUMBER 1
 '@BASEBOARD_FAB2_LIB.BASEBOARD_FAB2(SCH_1):PAGE83_I176@DEV_DISCRETE.CAP_A(CHIPS)':
 C_PATH='@baseboard_fab2_lib.baseboard_fab2(sch_1):page83_i176@dev_discrete.cap_~
a(chips)',
 P_PATH='@baseboard_fab2_lib.baseboard_fab2(sch_1):page83_i176@dev_discrete.cap_~
a(chips)',
 PATH='I176',
 DRAWING='@BASEBOARD_FAB2_LIB.BASEBOARD_FAB2(SCH_1):PAGE83',
 TOLERANCE='10%',
 MATERIAL='X7R',
 BOM_COST='MEM',
 PHYS_PAGE='83',
 XY='(-4600,1500)',
 ROT='2',
 VER='1',
 VALUE='0.01UF',
 PACK_TYPE='0402V',
 PART_NUMBER='A36096-045',
 LOCATION='C1B9',
 ROOM='DDR4_CH_K',
 CDS_LIB='dev_discrete',
 CDS_PART_NAME='CAP_A_0402V-0.01UF,25V,10%,X7RA',
 VOLTAGE='25V',
 PRIM_FILE='./archive_libs/discrete/cap_a/chips/chips.prt';

PART_NAME
 C1B10 'CAPP_2626-270UF,16V,20%,OSCON,A':
 ROOM='VDDQ_KLM_PWR_VR';

SECTION_NUMBER 1
 '@BASEBOARD_FAB2_LIB.BASEBOARD_FAB2(SCH_1):PAGE228_I175@MSTR_DISCRETE.CAPP(CHIPS)':
 C_PATH='@baseboard_fab2_lib.baseboard_fab2(sch_1):page228_i175@mstr_discrete.ca~
pp(chips)',
 P_PATH='@baseboard_fab2_lib.baseboard_fab2(sch_1):page228_i175@mstr_discrete.ca~
pp(chips)',
 PATH='I175',
 DRAWING='@BASEBOARD_FAB2_LIB.BASEBOARD_FAB2(SCH_1):PAGE228',
 TOLERANCE='20%',
 SEC_TYPE='2626',
 MATERIAL='OSCON',
 PHYS_PAGE='228',
 XY='(-675,900)',
 ROT='0',
 VER='1',
 VALUE='270UF',
 PACK_TYPE='2626',
 PART_NUMBER='A31228-047',
 LOCATION='C1B10',
 ROOM='VDDQ_KLM_PWR_VR',
 SEC='1',
 CDS_LIB='mstr_discrete',
 CDS_PART_NAME='CAPP_2626-270UF,16V,20%,OSCON,A',
 VOLTAGE='16V',
 PRIM_FILE='./archive_libs/mstr_discrete/capp/chips/chips.prt';

PART_NAME
 C1B11 'CAP_0402LF-220PF,50V,10%,X7R,AA':
 ROOM='VDDQ_KLM_PWR_VR';

SECTION_NUMBER 1
 '@BASEBOARD_FAB2_LIB.BASEBOARD_FAB2(SCH_1):PAGE226_I23@MSTR_DISCRETE.CAP(CHIPS)':
 C_PATH='@baseboard_fab2_lib.baseboard_fab2(sch_1):page226_i23@mstr_discrete.cap~
(chips)',
 P_PATH='@baseboard_fab2_lib.baseboard_fab2(sch_1):page226_i23@mstr_discrete.cap~
(chips)',
 PATH='I23',
 DRAWING='@BASEBOARD_FAB2_LIB.BASEBOARD_FAB2(SCH_1):PAGE226',
 TOLERANCE='10%',
 SEC_TYPE='0402LF',
 MATERIAL='X7R',
 PHYS_PAGE='226',
 XY='(-225,25)',
 ROT='2',
 VER='1',
 VALUE='220PF',
 PACK_TYPE='0402LF',
 PART_NUMBER='A36096-050',
 LOCATION='C1B11',
 ROOM='VDDQ_KLM_PWR_VR',
 SEC='1',
 CDS_LIB='mstr_discrete',
 CDS_PART_NAME='CAP_0402LF-220PF,50V,10%,X7R,AA',
 VOLTAGE='50V',
 PRIM_FILE='./archive_libs/mstr_discrete/cap/chips/chips.prt';

PART_NAME
 C1B12 'CAP_0402LF-220PF,50V,10%,X7R,AA':
 ROOM='VDDQ_KLM_PWR_VR',
 NO_XNET_CONNECTION='1';

SECTION_NUMBER 1
 '@BASEBOARD_FAB2_LIB.BASEBOARD_FAB2(SCH_1):PAGE226_I12@MSTR_DISCRETE.CAP(CHIPS)':
 C_PATH='@baseboard_fab2_lib.baseboard_fab2(sch_1):page226_i12@mstr_discrete.cap~
(chips)',
 P_PATH='@baseboard_fab2_lib.baseboard_fab2(sch_1):page226_i12@mstr_discrete.cap~
(chips)',
 PATH='I12',
 DRAWING='@BASEBOARD_FAB2_LIB.BASEBOARD_FAB2(SCH_1):PAGE226',
 TOLERANCE='10%',
 SEC_TYPE='0402LF',
 MATERIAL='X7R',
 NO_XNET_CONNECTION='1',
 PHYS_PAGE='226',
 XY='(-1750,325)',
 ROT='0',
 VER='1',
 VALUE='220PF',
 PACK_TYPE='0402LF',
 PART_NUMBER='A36096-050',
 LOCATION='C1B12',
 ROOM='VDDQ_KLM_PWR_VR',
 SEC='1',
 CDS_LIB='mstr_discrete',
 CDS_PART_NAME='CAP_0402LF-220PF,50V,10%,X7R,AA',
 VOLTAGE='50V',
 PRIM_FILE='./archive_libs/mstr_discrete/cap/chips/chips.prt';

PART_NAME
 C1B14 'CAPP_4040LF-470UF,16V,20%,ALUMA':;

SECTION_NUMBER 1
 '@BASEBOARD_FAB2_LIB.BASEBOARD_FAB2(SCH_1):PAGE195_I84@MSTR_DISCRETE.CAPP(CHIPS)':
 C_PATH='@baseboard_fab2_lib.baseboard_fab2(sch_1):page195_i84@mstr_discrete.cap~
p(chips)',
 P_PATH='@baseboard_fab2_lib.baseboard_fab2(sch_1):page195_i84@mstr_discrete.cap~
p(chips)',
 PATH='I84',
 DRAWING='@BASEBOARD_FAB2_LIB.BASEBOARD_FAB2(SCH_1):PAGE195',
 TOLERANCE='20%',
 MATERIAL='ALUM',
 PHYS_PAGE='195',
 XY='(-6150,2925)',
 ROT='0',
 VER='1',
 VALUE='470UF',
 PACK_TYPE='4040LF',
 PART_NUMBER='A93539-036',
 LOCATION='C1B14',
 CDS_LIB='mstr_discrete',
 CDS_PART_NAME='CAPP_4040LF-470UF,16V,20%,ALUMA',
 VOLTAGE='16V',
 PRIM_FILE='./archive_libs/mstr_discrete/capp/chips/chips.prt';

PART_NAME
 C1B15 'CAP_A_0402V-0.01UF,25V,10%,X7RA':
 ROOM='CPU_FANS';

SECTION_NUMBER 1
 '@BASEBOARD_FAB2_LIB.BASEBOARD_FAB2(SCH_1):PAGE161_I68@DEV_DISCRETE.CAP_A(CHIPS)':
 C_PATH='@baseboard_fab2_lib.baseboard_fab2(sch_1):page161_i68@dev_discrete.cap_~
a(chips)',
 P_PATH='@baseboard_fab2_lib.baseboard_fab2(sch_1):page161_i68@dev_discrete.cap_~
a(chips)',
 PATH='I68',
 DRAWING='@BASEBOARD_FAB2_LIB.BASEBOARD_FAB2(SCH_1):PAGE161',
 TOLERANCE='10%',
 SEC_TYPE='0402V',
 MATERIAL='X7R',
 BOM_COST='SM_THERM',
 PHYS_PAGE='161',
 XY='(-2925,1550)',
 ROT='2',
 VER='1',
 VALUE='0.01UF',
 PACK_TYPE='0402V',
 PART_NUMBER='A36096-045',
 LOCATION='C1B15',
 ROOM='CPU_FANS',
 SEC='1',
 CDS_LIB='dev_discrete',
 CDS_PART_NAME='CAP_A_0402V-0.01UF,25V,10%,X7RA',
 VOLTAGE='25V',
 PRIM_FILE='./archive_libs/discrete/cap_a/chips/chips.prt';

PART_NAME
 C1B18 'CAP_0805-10UF,16V,10%,X6S,C953A':
 ROOM='P12V_FAN_PWR_SWITCH';

SECTION_NUMBER 1
 '@BASEBOARD_FAB2_LIB.BASEBOARD_FAB2(SCH_1):PAGE198_I61@MSTR_DISCRETE.CAP(CHIPS)':
 C_PATH='@baseboard_fab2_lib.baseboard_fab2(sch_1):page198_i61@mstr_discrete.cap~
(chips)',
 P_PATH='@baseboard_fab2_lib.baseboard_fab2(sch_1):page198_i61@mstr_discrete.cap~
(chips)',
 PATH='I61',
 DRAWING='@BASEBOARD_FAB2_LIB.BASEBOARD_FAB2(SCH_1):PAGE198',
 TOLERANCE='10%',
 SEC_TYPE='0805',
 MATERIAL='X6S',
 PHYS_PAGE='198',
 XY='(-1175,1225)',
 ROT='0',
 VER='1',
 VALUE='10UF',
 PACK_TYPE='0805',
 PART_NUMBER='C95333-007',
 LOCATION='C1B18',
 ROOM='P12V_FAN_PWR_SWITCH',
 SEC='1',
 CDS_LIB='mstr_discrete',
 CDS_PART_NAME='CAP_0805-10UF,16V,10%,X6S,C953A',
 VOLTAGE='16V',
 PRIM_FILE='./archive_libs/mstr_discrete/cap/chips/chips.prt';

PART_NAME
 C1B19 'CAP_A_0402V-0.1UF,16V,10%,X7R,A':
 ROOM='P12V_FAN_PWR_SWITCH';

SECTION_NUMBER 1
 '@BASEBOARD_FAB2_LIB.BASEBOARD_FAB2(SCH_1):PAGE198_I64@DEV_DISCRETE.CAP_A(CHIPS)':
 C_PATH='@baseboard_fab2_lib.baseboard_fab2(sch_1):page198_i64@dev_discrete.cap_~
a(chips)',
 P_PATH='@baseboard_fab2_lib.baseboard_fab2(sch_1):page198_i64@dev_discrete.cap_~
a(chips)',
 PATH='I64',
 DRAWING='@BASEBOARD_FAB2_LIB.BASEBOARD_FAB2(SCH_1):PAGE198',
 TOLERANCE='10%',
 SEC_TYPE='0402V',
 MATERIAL='X7R',
 BOM_COST='PWR_SWITCH',
 PHYS_PAGE='198',
 XY='(-725,1225)',
 ROT='0',
 VER='1',
 VALUE='0.1UF',
 PACK_TYPE='0402V',
 PART_NUMBER='A36096-030',
 LOCATION='C1B19',
 ROOM='P12V_FAN_PWR_SWITCH',
 SEC='1',
 CDS_LIB='dev_discrete',
 CDS_PART_NAME='CAP_A_0402V-0.1UF,16V,10%,X7R,A',
 VOLTAGE='16V',
 PRIM_FILE='./archive_libs/discrete/cap_a/chips/chips.prt';

PART_NAME
 C1B20 'CAP_0402-1.0UF,16V,10%,X6S,D97A':
 ROOM='VDDQ_KLM_PWR_VR';

SECTION_NUMBER 1
 '@BASEBOARD_FAB2_LIB.BASEBOARD_FAB2(SCH_1):PAGE227_I50@MSTR_DISCRETE.CAP(CHIPS)':
 C_PATH='@baseboard_fab2_lib.baseboard_fab2(sch_1):page227_i50@mstr_discrete.cap~
(chips)',
 P_PATH='@baseboard_fab2_lib.baseboard_fab2(sch_1):page227_i50@mstr_discrete.cap~
(chips)',
 PATH='I50',
 DRAWING='@BASEBOARD_FAB2_LIB.BASEBOARD_FAB2(SCH_1):PAGE227',
 TOLERANCE='10%',
 SEC_TYPE='0402',
 MATERIAL='X6S',
 PHYS_PAGE='227',
 XY='(-900,2500)',
 ROT='0',
 VER='1',
 VALUE='1.0UF',
 PACK_TYPE='0402',
 PART_NUMBER='D97712-011',
 LOCATION='C1B20',
 ROOM='VDDQ_KLM_PWR_VR',
 SEC='1',
 CDS_LIB='mstr_discrete',
 CDS_PART_NAME='CAP_0402-1.0UF,16V,10%,X6S,D97A',
 VOLTAGE='16V',
 PRIM_FILE='./archive_libs/mstr_discrete/cap/chips/chips.prt';

PART_NAME
 C1B21 'CAP_0402-0.22UF,16V,10%,X7R,A3A':
 ROOM='VDDQ_KLM_PWR_VR';

SECTION_NUMBER 1
 '@BASEBOARD_FAB2_LIB.BASEBOARD_FAB2(SCH_1):PAGE227_I54@MSTR_DISCRETE.CAP(CHIPS)':
 C_PATH='@baseboard_fab2_lib.baseboard_fab2(sch_1):page227_i54@mstr_discrete.cap~
(chips)',
 P_PATH='@baseboard_fab2_lib.baseboard_fab2(sch_1):page227_i54@mstr_discrete.cap~
(chips)',
 PATH='I54',
 DRAWING='@BASEBOARD_FAB2_LIB.BASEBOARD_FAB2(SCH_1):PAGE227',
 TOLERANCE='10%',
 SEC_TYPE='0402',
 MATERIAL='X7R',
 PHYS_PAGE='227',
 XY='(-100,2475)',
 ROT='0',
 VER='1',
 VALUE='0.22UF',
 PACK_TYPE='0402',
 PART_NUMBER='A36096-155',
 LOCATION='C1B21',
 ROOM='VDDQ_KLM_PWR_VR',
 SEC='1',
 CDS_LIB='mstr_discrete',
 CDS_PART_NAME='CAP_0402-0.22UF,16V,10%,X7R,A3A',
 VOLTAGE='16V',
 PRIM_FILE='./archive_libs/mstr_discrete/cap/chips/chips.prt';

PART_NAME
 C1C1 'CAPP_2626-270UF,16V,20%,OSCON,A':
 ROOM='PVCCIN_CPU1_FILTER_VR';

SECTION_NUMBER 1
 '@BASEBOARD_FAB2_LIB.BASEBOARD_FAB2(SCH_1):PAGE209_I35@MSTR_DISCRETE.CAPP(CHIPS)':
 C_PATH='@baseboard_fab2_lib.baseboard_fab2(sch_1):page209_i35@mstr_discrete.cap~
p(chips)',
 P_PATH='@baseboard_fab2_lib.baseboard_fab2(sch_1):page209_i35@mstr_discrete.cap~
p(chips)',
 PATH='I35',
 DRAWING='@BASEBOARD_FAB2_LIB.BASEBOARD_FAB2(SCH_1):PAGE209',
 TOLERANCE='20%',
 SEC_TYPE='2626',
 MATERIAL='OSCON',
 PHYS_PAGE='209',
 XY='(-1425,2075)',
 ROT='0',
 VER='1',
 VALUE='270UF',
 PACK_TYPE='2626',
 PART_NUMBER='A31228-047',
 LOCATION='C1C1',
 ROOM='PVCCIN_CPU1_FILTER_VR',
 SEC='1',
 CDS_LIB='mstr_discrete',
 CDS_PART_NAME='CAPP_2626-270UF,16V,20%,OSCON,A',
 VOLTAGE='16V',
 PRIM_FILE='./archive_libs/mstr_discrete/capp/chips/chips.prt';

PART_NAME
 C1C2 'CAPP_2626-270UF,16V,20%,OSCON,A':
 ROOM='PVCCIN_CPU1_FILTER_VR';

SECTION_NUMBER 1
 '@BASEBOARD_FAB2_LIB.BASEBOARD_FAB2(SCH_1):PAGE209_I38@MSTR_DISCRETE.CAPP(CHIPS)':
 C_PATH='@baseboard_fab2_lib.baseboard_fab2(sch_1):page209_i38@mstr_discrete.cap~
p(chips)',
 P_PATH='@baseboard_fab2_lib.baseboard_fab2(sch_1):page209_i38@mstr_discrete.cap~
p(chips)',
 PATH='I38',
 DRAWING='@BASEBOARD_FAB2_LIB.BASEBOARD_FAB2(SCH_1):PAGE209',
 TOLERANCE='20%',
 SEC_TYPE='2626',
 MATERIAL='OSCON',
 PHYS_PAGE='209',
 XY='(-600,2050)',
 ROT='0',
 VER='1',
 VALUE='270UF',
 PACK_TYPE='2626',
 PART_NUMBER='A31228-047',
 LOCATION='C1C2',
 ROOM='PVCCIN_CPU1_FILTER_VR',
 SEC='1',
 CDS_LIB='mstr_discrete',
 CDS_PART_NAME='CAPP_2626-270UF,16V,20%,OSCON,A',
 VOLTAGE='16V',
 PRIM_FILE='./archive_libs/mstr_discrete/capp/chips/chips.prt';

PART_NAME
 C1C3 'SC1U10V2KX-4-GP_SMD-BCG6-SC1U1A':;

SECTION_NUMBER 1
 '@BASEBOARD_FAB2_LIB.BASEBOARD_FAB2(SCH_1):PAGE210_I73@W_HDL.SC1U10V2KX-4-GP(CHIPS)':
 C_PATH='@baseboard_fab2_lib.baseboard_fab2(sch_1):page210_i73@w_hdl.\sc1u10v2kx~
-4-gp\(chips)',
 P_PATH='@baseboard_fab2_lib.baseboard_fab2(sch_1):page210_i73@w_hdl.\sc1u10v2kx~
-4-gp\(chips)',
 PATH='I73',
 DRAWING='@BASEBOARD_FAB2_LIB.BASEBOARD_FAB2(SCH_1):PAGE210',
 PACK_SIZE='0402',
 RATED='10V',
 ATTRIBUTE='1UF',
 TOLERANCE='10%',
 SEC_TYPE='SMD-BCG6',
 PHYS_PAGE='210',
 XY='(-5475,3850)',
 ROT='0',
 VER='1',
 VALUE='SC1U10V2KX-4-GP',
 PACK_TYPE='SMD-BCG6',
 PART_NUMBER='78.10523.8FL',
 LOCATION='C1C3',
 SEC='1',
 CDS_LIB='w_hdl',
 CDS_PART_NAME='SC1U10V2KX-4-GP_SMD-BCG6-SC1U1A',
 PRIM_FILE='C:/<user>/w_hdl/sc1u10v2kx#2d4#2dgp/chips/chips.prt';

PART_NAME
 C1C4 'CAP_0402-0.22UF,16V,10%,X7R,A3A':
 ROOM='PVSA_CPU1_PWR_VR';

SECTION_NUMBER 1
 '@BASEBOARD_FAB2_LIB.BASEBOARD_FAB2(SCH_1):PAGE210_I22@MSTR_DISCRETE.CAP(CHIPS)':
 C_PATH='@baseboard_fab2_lib.baseboard_fab2(sch_1):page210_i22@mstr_discrete.cap~
(chips)',
 P_PATH='@baseboard_fab2_lib.baseboard_fab2(sch_1):page210_i22@mstr_discrete.cap~
(chips)',
 PATH='I22',
 DRAWING='@BASEBOARD_FAB2_LIB.BASEBOARD_FAB2(SCH_1):PAGE210',
 TOLERANCE='10%',
 SEC_TYPE='0402',
 MATERIAL='X7R',
 PHYS_PAGE='210',
 XY='(-5200,3850)',
 ROT='0',
 VER='1',
 VALUE='0.22UF',
 PACK_TYPE='0402',
 PART_NUMBER='A36096-155',
 LOCATION='C1C4',
 ROOM='PVSA_CPU1_PWR_VR',
 SEC='1',
 CDS_LIB='mstr_discrete',
 CDS_PART_NAME='CAP_0402-0.22UF,16V,10%,X7R,A3A',
 VOLTAGE='16V',
 PRIM_FILE='./archive_libs/mstr_discrete/cap/chips/chips.prt';

PART_NAME
 C1C5 'CAP_0402-1.0UF,16V,10%,X6S,D97A':
 ROOM='PVSA_CPU1_PWR_VR';

SECTION_NUMBER 1
 '@BASEBOARD_FAB2_LIB.BASEBOARD_FAB2(SCH_1):PAGE210_I26@MSTR_DISCRETE.CAP(CHIPS)':
 C_PATH='@baseboard_fab2_lib.baseboard_fab2(sch_1):page210_i26@mstr_discrete.cap~
(chips)',
 P_PATH='@baseboard_fab2_lib.baseboard_fab2(sch_1):page210_i26@mstr_discrete.cap~
(chips)',
 PATH='I26',
 DRAWING='@BASEBOARD_FAB2_LIB.BASEBOARD_FAB2(SCH_1):PAGE210',
 TOLERANCE='10%',
 SEC_TYPE='0402',
 MATERIAL='X6S',
 PHYS_PAGE='210',
 XY='(-5875,3825)',
 ROT='0',
 VER='1',
 VALUE='1.0UF',
 PACK_TYPE='0402',
 PART_NUMBER='D97712-011',
 LOCATION='C1C5',
 ROOM='PVSA_CPU1_PWR_VR',
 SEC='1',
 CDS_LIB='mstr_discrete',
 CDS_PART_NAME='CAP_0402-1.0UF,16V,10%,X6S,D97A',
 VOLTAGE='16V',
 PRIM_FILE='./archive_libs/mstr_discrete/cap/chips/chips.prt';

PART_NAME
 C1C7 'CAP_A_0402V-1.0UF,6.3V,10%,X6SA':
 ROOM='PVCCIN_CPU1_VR';

SECTION_NUMBER 1
 '@BASEBOARD_FAB2_LIB.BASEBOARD_FAB2(SCH_1):PAGE206_I41@DEV_DISCRETE.CAP_A(CHIPS)':
 C_PATH='@baseboard_fab2_lib.baseboard_fab2(sch_1):page206_i41@dev_discrete.cap_~
a(chips)',
 P_PATH='@baseboard_fab2_lib.baseboard_fab2(sch_1):page206_i41@dev_discrete.cap_~
a(chips)',
 PATH='I41',
 DRAWING='@BASEBOARD_FAB2_LIB.BASEBOARD_FAB2(SCH_1):PAGE206',
 TOLERANCE='10%',
 MATERIAL='X6S',
 PHYS_PAGE='206',
 XY='(-3650,3925)',
 ROT='0',
 VER='1',
 VALUE='1.0UF',
 PACK_TYPE='0402V',
 PART_NUMBER='D97712-004',
 LOCATION='C1C7',
 ROOM='PVCCIN_CPU1_VR',
 CDS_LIB='dev_discrete',
 CDS_PART_NAME='CAP_A_0402V-1.0UF,6.3V,10%,X6SA',
 VOLTAGE='6.3V',
 PRIM_FILE='./archive_libs/discrete/cap_a/chips/chips.prt';

PART_NAME
 C1C8 'CAP_A_0402V-0.1UF,16V,10%,X7R,A':
 ROOM='CPU_FANS';

SECTION_NUMBER 1
 '@BASEBOARD_FAB2_LIB.BASEBOARD_FAB2(SCH_1):PAGE206_I156@DEV_DISCRETE.CAP_A(CHIPS)':
 C_PATH='@baseboard_fab2_lib.baseboard_fab2(sch_1):page206_i156@dev_discrete.cap~
_a(chips)',
 P_PATH='@baseboard_fab2_lib.baseboard_fab2(sch_1):page206_i156@dev_discrete.cap~
_a(chips)',
 PATH='I156',
 DRAWING='@BASEBOARD_FAB2_LIB.BASEBOARD_FAB2(SCH_1):PAGE206',
 TOLERANCE='10%',
 SEC_TYPE='0402V',
 MATERIAL='X7R',
 BOM_COST='SM_THERM',
 PHYS_PAGE='206',
 XY='(-6750,4200)',
 ROT='0',
 VER='1',
 VALUE='0.1UF',
 PACK_TYPE='0402V',
 PART_NUMBER='A36096-030',
 LOCATION='C1C8',
 ROOM='CPU_FANS',
 SEC='1',
 CDS_LIB='dev_discrete',
 CDS_PART_NAME='CAP_A_0402V-0.1UF,16V,10%,X7R,A',
 VOLTAGE='16V',
 PRIM_FILE='./archive_libs/discrete/cap_a/chips/chips.prt';

PART_NAME
 C1C9 'CAP_A_0402V-0.1UF,16V,10%,X7R,A':
 ROOM='PVCCIN_CPU1_VR';

SECTION_NUMBER 1
 '@BASEBOARD_FAB2_LIB.BASEBOARD_FAB2(SCH_1):PAGE206_I42@DEV_DISCRETE.CAP_A(CHIPS)':
 C_PATH='@baseboard_fab2_lib.baseboard_fab2(sch_1):page206_i42@dev_discrete.cap_~
a(chips)',
 P_PATH='@baseboard_fab2_lib.baseboard_fab2(sch_1):page206_i42@dev_discrete.cap_~
a(chips)',
 PATH='I42',
 DRAWING='@BASEBOARD_FAB2_LIB.BASEBOARD_FAB2(SCH_1):PAGE206',
 TOLERANCE='10%',
 SEC_TYPE='0402V',
 MATERIAL='X7R',
 PHYS_PAGE='206',
 XY='(-4050,3925)',
 ROT='0',
 VER='1',
 VALUE='0.1UF',
 PACK_TYPE='0402V',
 PART_NUMBER='A36096-030',
 LOCATION='C1C9',
 ROOM='PVCCIN_CPU1_VR',
 SEC='1',
 CDS_LIB='dev_discrete',
 CDS_PART_NAME='CAP_A_0402V-0.1UF,16V,10%,X7R,A',
 VOLTAGE='16V',
 PRIM_FILE='./archive_libs/discrete/cap_a/chips/chips.prt';

PART_NAME
 C1C10 'CAP_0402LF-220PF,50V,10%,X7R,AA':
 ROOM='PVCCIN_CPU1_VR';

SECTION_NUMBER 1
 '@BASEBOARD_FAB2_LIB.BASEBOARD_FAB2(SCH_1):PAGE206_I69@MSTR_DISCRETE.CAP(CHIPS)':
 C_PATH='@baseboard_fab2_lib.baseboard_fab2(sch_1):page206_i69@mstr_discrete.cap~
(chips)',
 P_PATH='@baseboard_fab2_lib.baseboard_fab2(sch_1):page206_i69@mstr_discrete.cap~
(chips)',
 PATH='I69',
 DRAWING='@BASEBOARD_FAB2_LIB.BASEBOARD_FAB2(SCH_1):PAGE206',
 TOLERANCE='10%',
 SEC_TYPE='0402LF',
 MATERIAL='X7R',
 PHYS_PAGE='206',
 XY='(-5925,1275)',
 ROT='0',
 VER='1',
 VALUE='220PF',
 PACK_TYPE='0402LF',
 PART_NUMBER='A36096-050',
 LOCATION='C1C10',
 ROOM='PVCCIN_CPU1_VR',
 SEC='1',
 CDS_LIB='mstr_discrete',
 CDS_PART_NAME='CAP_0402LF-220PF,50V,10%,X7R,AA',
 VOLTAGE='50V',
 PRIM_FILE='./archive_libs/mstr_discrete/cap/chips/chips.prt';

PART_NAME
 C1C11 'CAP_0402LF-220PF,50V,10%,X7R,AA':
 ROOM='PVCCIN_CPU1_VR';

SECTION_NUMBER 1
 '@BASEBOARD_FAB2_LIB.BASEBOARD_FAB2(SCH_1):PAGE206_I71@MSTR_DISCRETE.CAP(CHIPS)':
 C_PATH='@baseboard_fab2_lib.baseboard_fab2(sch_1):page206_i71@mstr_discrete.cap~
(chips)',
 P_PATH='@baseboard_fab2_lib.baseboard_fab2(sch_1):page206_i71@mstr_discrete.cap~
(chips)',
 PATH='I71',
 DRAWING='@BASEBOARD_FAB2_LIB.BASEBOARD_FAB2(SCH_1):PAGE206',
 TOLERANCE='10%',
 SEC_TYPE='0402LF',
 MATERIAL='X7R',
 PHYS_PAGE='206',
 XY='(-6150,650)',
 ROT='2',
 VER='1',
 VALUE='220PF',
 PACK_TYPE='0402LF',
 PART_NUMBER='A36096-050',
 LOCATION='C1C11',
 ROOM='PVCCIN_CPU1_VR',
 SEC='1',
 CDS_LIB='mstr_discrete',
 CDS_PART_NAME='CAP_0402LF-220PF,50V,10%,X7R,AA',
 VOLTAGE='50V',
 PRIM_FILE='./archive_libs/mstr_discrete/cap/chips/chips.prt';

PART_NAME
 C1C12 'CAP_0402-0.220UF,16V,10%,X7R,AA':
 ROOM='PVSA_CPU1_PWR_VR';

SECTION_NUMBER 1
 '@BASEBOARD_FAB2_LIB.BASEBOARD_FAB2(SCH_1):PAGE210_I24@MSTR_DISCRETE.CAP(CHIPS)':
 C_PATH='@baseboard_fab2_lib.baseboard_fab2(sch_1):page210_i24@mstr_discrete.cap~
(chips)',
 P_PATH='@baseboard_fab2_lib.baseboard_fab2(sch_1):page210_i24@mstr_discrete.cap~
(chips)',
 PATH='I24',
 DRAWING='@BASEBOARD_FAB2_LIB.BASEBOARD_FAB2(SCH_1):PAGE210',
 SPOF='TRUE',
 TOLERANCE='10%',
 SEC_TYPE='0402',
 MATERIAL='X7R',
 PHYS_PAGE='210',
 XY='(-6125,3250)',
 ROT='2',
 VER='1',
 VALUE='0.220UF',
 PACK_TYPE='0402',
 PART_NUMBER='A36096-104',
 LOCATION='C1C12',
 ROOM='PVSA_CPU1_PWR_VR',
 SEC='1',
 CDS_LIB='mstr_discrete',
 CDS_PART_NAME='CAP_0402-0.220UF,16V,10%,X7R,AA',
 VOLTAGE='16V',
 PRIM_FILE='./archive_libs/mstr_discrete/cap/chips/chips.prt';

PART_NAME
 C1C13 'CAP_A_0402V-1.0UF,6.3V,10%,X6SA':
 ROOM='PVCCIN_CPU1_VR';

SECTION_NUMBER 1
 '@BASEBOARD_FAB2_LIB.BASEBOARD_FAB2(SCH_1):PAGE206_I29@DEV_DISCRETE.CAP_A(CHIPS)':
 C_PATH='@baseboard_fab2_lib.baseboard_fab2(sch_1):page206_i29@dev_discrete.cap_~
a(chips)',
 P_PATH='@baseboard_fab2_lib.baseboard_fab2(sch_1):page206_i29@dev_discrete.cap_~
a(chips)',
 PATH='I29',
 DRAWING='@BASEBOARD_FAB2_LIB.BASEBOARD_FAB2(SCH_1):PAGE206',
 TOLERANCE='10%',
 SEC_TYPE='0402V',
 MATERIAL='X6S',
 PHYS_PAGE='206',
 XY='(-1575,1000)',
 ROT='0',
 VER='1',
 VALUE='1.0UF',
 PACK_TYPE='0402V',
 PART_NUMBER='D97712-004',
 LOCATION='C1C13',
 ROOM='PVCCIN_CPU1_VR',
 SEC='1',
 CDS_LIB='dev_discrete',
 CDS_PART_NAME='CAP_A_0402V-1.0UF,6.3V,10%,X6SA',
 VOLTAGE='6.3V',
 PRIM_FILE='./archive_libs/discrete/cap_a/chips/chips.prt';

PART_NAME
 C1C14 'CAP_A_0402V-0.1UF,16V,10%,X7R,A':
 ROOM='PVCCIN_CPU1_VR';

SECTION_NUMBER 1
 '@BASEBOARD_FAB2_LIB.BASEBOARD_FAB2(SCH_1):PAGE206_I31@DEV_DISCRETE.CAP_A(CHIPS)':
 C_PATH='@baseboard_fab2_lib.baseboard_fab2(sch_1):page206_i31@dev_discrete.cap_~
a(chips)',
 P_PATH='@baseboard_fab2_lib.baseboard_fab2(sch_1):page206_i31@dev_discrete.cap_~
a(chips)',
 PATH='I31',
 DRAWING='@BASEBOARD_FAB2_LIB.BASEBOARD_FAB2(SCH_1):PAGE206',
 TOLERANCE='10%',
 SEC_TYPE='0402V',
 MATERIAL='X7R',
 PHYS_PAGE='206',
 XY='(-1975,1000)',
 ROT='0',
 VER='1',
 VALUE='0.1UF',
 PACK_TYPE='0402V',
 PART_NUMBER='A36096-030',
 LOCATION='C1C14',
 ROOM='PVCCIN_CPU1_VR',
 SEC='1',
 CDS_LIB='dev_discrete',
 CDS_PART_NAME='CAP_A_0402V-0.1UF,16V,10%,X7R,A',
 VOLTAGE='16V',
 PRIM_FILE='./archive_libs/discrete/cap_a/chips/chips.prt';

PART_NAME
 C1C15 'CAP_0402-1.0UF,16V,10%,X6S,D97A':
 ROOM='PVSA_CPU1_PWR_VR';

SECTION_NUMBER 1
 '@BASEBOARD_FAB2_LIB.BASEBOARD_FAB2(SCH_1):PAGE210_I28@MSTR_DISCRETE.CAP(CHIPS)':
 C_PATH='@baseboard_fab2_lib.baseboard_fab2(sch_1):page210_i28@mstr_discrete.cap~
(chips)',
 P_PATH='@baseboard_fab2_lib.baseboard_fab2(sch_1):page210_i28@mstr_discrete.cap~
(chips)',
 PATH='I28',
 DRAWING='@BASEBOARD_FAB2_LIB.BASEBOARD_FAB2(SCH_1):PAGE210',
 TOLERANCE='10%',
 SEC_TYPE='0402',
 MATERIAL='X6S',
 PHYS_PAGE='210',
 XY='(-6375,3825)',
 ROT='0',
 VER='1',
 VALUE='1.0UF',
 PACK_TYPE='0402',
 PART_NUMBER='D97712-011',
 LOCATION='C1C15',
 ROOM='PVSA_CPU1_PWR_VR',
 SEC='1',
 CDS_LIB='mstr_discrete',
 CDS_PART_NAME='CAP_0402-1.0UF,16V,10%,X6S,D97A',
 VOLTAGE='16V',
 PRIM_FILE='./archive_libs/mstr_discrete/cap/chips/chips.prt';

PART_NAME
 C1C16 'CAP_0402LF-220PF,50V,10%,X7R,AA':
 ROOM='PVCCIN_CPU1_VR',
 NO_XNET_CONNECTION='1';

SECTION_NUMBER 1
 '@BASEBOARD_FAB2_LIB.BASEBOARD_FAB2(SCH_1):PAGE206_I68@MSTR_DISCRETE.CAP(CHIPS)':
 C_PATH='@baseboard_fab2_lib.baseboard_fab2(sch_1):page206_i68@mstr_discrete.cap~
(chips)',
 P_PATH='@baseboard_fab2_lib.baseboard_fab2(sch_1):page206_i68@mstr_discrete.cap~
(chips)',
 PATH='I68',
 DRAWING='@BASEBOARD_FAB2_LIB.BASEBOARD_FAB2(SCH_1):PAGE206',
 TOLERANCE='10%',
 SEC_TYPE='0402LF',
 MATERIAL='X7R',
 NO_XNET_CONNECTION='1',
 PHYS_PAGE='206',
 XY='(-5650,2075)',
 ROT='0',
 VER='1',
 VALUE='220PF',
 PACK_TYPE='0402LF',
 PART_NUMBER='A36096-050',
 LOCATION='C1C16',
 ROOM='PVCCIN_CPU1_VR',
 SEC='1',
 CDS_LIB='mstr_discrete',
 CDS_PART_NAME='CAP_0402LF-220PF,50V,10%,X7R,AA',
 VOLTAGE='50V',
 PRIM_FILE='./archive_libs/mstr_discrete/cap/chips/chips.prt';

PART_NAME
 C1C17 'CAP_A_0402V-0.1UF,16V,10%,X7R,A':
 ROOM='PVSA_CPU1_PWR_VR';

SECTION_NUMBER 1
 '@BASEBOARD_FAB2_LIB.BASEBOARD_FAB2(SCH_1):PAGE210_I27@DEV_DISCRETE.CAP_A(CHIPS)':
 C_PATH='@baseboard_fab2_lib.baseboard_fab2(sch_1):page210_i27@dev_discrete.cap_~
a(chips)',
 P_PATH='@baseboard_fab2_lib.baseboard_fab2(sch_1):page210_i27@dev_discrete.cap_~
a(chips)',
 PATH='I27',
 DRAWING='@BASEBOARD_FAB2_LIB.BASEBOARD_FAB2(SCH_1):PAGE210',
 TOLERANCE='10%',
 SEC_TYPE='0402V',
 MATERIAL='X7R',
 PHYS_PAGE='210',
 XY='(-6125,3850)',
 ROT='0',
 VER='1',
 VALUE='0.1UF',
 PACK_TYPE='0402V',
 PART_NUMBER='A36096-030',
 LOCATION='C1C17',
 ROOM='PVSA_CPU1_PWR_VR',
 SEC='1',
 CDS_LIB='dev_discrete',
 CDS_PART_NAME='CAP_A_0402V-0.1UF,16V,10%,X7R,A',
 VOLTAGE='16V',
 PRIM_FILE='./archive_libs/discrete/cap_a/chips/chips.prt';

PART_NAME
 C1C18 'SC1U10V2KX-4-GP_SMD-BCG6-SC1U1A':;

SECTION_NUMBER 1
 '@BASEBOARD_FAB2_LIB.BASEBOARD_FAB2(SCH_1):PAGE209_I89@W_HDL.SC1U10V2KX-4-GP(CHIPS)':
 C_PATH='@baseboard_fab2_lib.baseboard_fab2(sch_1):page209_i89@w_hdl.\sc1u10v2kx~
-4-gp\(chips)',
 P_PATH='@baseboard_fab2_lib.baseboard_fab2(sch_1):page209_i89@w_hdl.\sc1u10v2kx~
-4-gp\(chips)',
 PATH='I89',
 DRAWING='@BASEBOARD_FAB2_LIB.BASEBOARD_FAB2(SCH_1):PAGE209',
 PACK_SIZE='0402',
 RATED='10V',
 ATTRIBUTE='1UF',
 TOLERANCE='10%',
 SEC_TYPE='SMD-BCG6',
 PHYS_PAGE='209',
 XY='(-5125,4025)',
 ROT='0',
 VER='1',
 VALUE='SC1U10V2KX-4-GP',
 PACK_TYPE='SMD-BCG6',
 PART_NUMBER='78.10523.8FL',
 LOCATION='C1C18',
 SEC='1',
 CDS_LIB='w_hdl',
 CDS_PART_NAME='SC1U10V2KX-4-GP_SMD-BCG6-SC1U1A',
 PRIM_FILE='C:/<user>/w_hdl/sc1u10v2kx#2d4#2dgp/chips/chips.prt';

PART_NAME
 C1C19 'CAP_A_0603V-22.0UF,4V,20%,X6S,A':
 GROUP='PWR_MLCC_CAP',
 ROOM='PVSA_CPU1_PWR_VR';

SECTION_NUMBER 1
 '@BASEBOARD_FAB2_LIB.BASEBOARD_FAB2(SCH_1):PAGE210_I8@DEV_DISCRETE.CAP_A(CHIPS)':
 C_PATH='@baseboard_fab2_lib.baseboard_fab2(sch_1):page210_i8@dev_discrete.cap_a~
(chips)',
 P_PATH='@baseboard_fab2_lib.baseboard_fab2(sch_1):page210_i8@dev_discrete.cap_a~
(chips)',
 PATH='I8',
 DRAWING='@BASEBOARD_FAB2_LIB.BASEBOARD_FAB2(SCH_1):PAGE210',
 TOLERANCE='20%',
 SEC_TYPE='0603V',
 MATERIAL='X6S',
 BOM_COST='PROC_VRD_VCCIN_CPU0',
 PHYS_PAGE='210',
 XY='(-1300,3100)',
 ROT='0',
 VER='1',
 VALUE='22.0UF',
 PACK_TYPE='0603V',
 PART_NUMBER='E15431-004',
 LOCATION='C1C19',
 ROOM='PVSA_CPU1_PWR_VR',
 GROUP='PWR_MLCC_CAP',
 SEC='1',
 CDS_LIB='dev_discrete',
 CDS_PART_NAME='CAP_A_0603V-22.0UF,4V,20%,X6S,A',
 VOLTAGE='4V',
 PRIM_FILE='./archive_libs/discrete/cap_a/chips/chips.prt';

PART_NAME
 C1C23 'CAP_0402LF-1000PF,50V,10%,X7R,A':
 ROOM='PVCCIN_CPU1_VR';

SECTION_NUMBER 1
 '@BASEBOARD_FAB2_LIB.BASEBOARD_FAB2(SCH_1):PAGE206_I114@MSTR_DISCRETE.CAP(CHIPS)':
 C_PATH='@baseboard_fab2_lib.baseboard_fab2(sch_1):page206_i114@mstr_discrete.ca~
p(chips)',
 P_PATH='@baseboard_fab2_lib.baseboard_fab2(sch_1):page206_i114@mstr_discrete.ca~
p(chips)',
 PATH='I114',
 DRAWING='@BASEBOARD_FAB2_LIB.BASEBOARD_FAB2(SCH_1):PAGE206',
 TOLERANCE='10%',
 SEC_TYPE='0402LF',
 MATERIAL='X7R',
 PHYS_PAGE='206',
 XY='(-1450,2150)',
 ROT='0',
 VER='1',
 VALUE='1000PF',
 PACK_TYPE='0402LF',
 PART_NUMBER='A36096-046',
 LOCATION='C1C23',
 ROOM='PVCCIN_CPU1_VR',
 SEC='1',
 CDS_LIB='mstr_discrete',
 CDS_PART_NAME='CAP_0402LF-1000PF,50V,10%,X7R,A',
 VOLTAGE='50V',
 PRIM_FILE='./archive_libs/mstr_discrete/cap/chips/chips.prt';

PART_NAME
 C1C24 'CAP_0402-0.220UF,16V,10%,X7R,AA':
 ROOM='PVCCIN_CPU1_PWR_VR',
 NO_XNET_CONNECTION='1';

SECTION_NUMBER 1
 '@BASEBOARD_FAB2_LIB.BASEBOARD_FAB2(SCH_1):PAGE209_I20@MSTR_DISCRETE.CAP(CHIPS)':
 C_PATH='@baseboard_fab2_lib.baseboard_fab2(sch_1):page209_i20@mstr_discrete.cap~
(chips)',
 P_PATH='@baseboard_fab2_lib.baseboard_fab2(sch_1):page209_i20@mstr_discrete.cap~
(chips)',
 PATH='I20',
 DRAWING='@BASEBOARD_FAB2_LIB.BASEBOARD_FAB2(SCH_1):PAGE209',
 SPOF='TRUE',
 TOLERANCE='10%',
 SEC_TYPE='0402',
 MATERIAL='X7R',
 NO_XNET_CONNECTION='1',
 PHYS_PAGE='209',
 XY='(-5900,3450)',
 ROT='2',
 VER='1',
 VALUE='0.220UF',
 PACK_TYPE='0402',
 PART_NUMBER='A36096-104',
 LOCATION='C1C24',
 ROOM='PVCCIN_CPU1_PWR_VR',
 SEC='1',
 CDS_LIB='mstr_discrete',
 CDS_PART_NAME='CAP_0402-0.220UF,16V,10%,X7R,AA',
 VOLTAGE='16V',
 PRIM_FILE='./archive_libs/mstr_discrete/cap/chips/chips.prt';

PART_NAME
 C1C25 'CAP_A_0402V-0.1UF,16V,10%,X7R,A':
 ROOM='PVCCIN_CPU1_PWR_VR';

SECTION_NUMBER 1
 '@BASEBOARD_FAB2_LIB.BASEBOARD_FAB2(SCH_1):PAGE209_I17@DEV_DISCRETE.CAP_A(CHIPS)':
 C_PATH='@baseboard_fab2_lib.baseboard_fab2(sch_1):page209_i17@dev_discrete.cap_~
a(chips)',
 P_PATH='@baseboard_fab2_lib.baseboard_fab2(sch_1):page209_i17@dev_discrete.cap_~
a(chips)',
 PATH='I17',
 DRAWING='@BASEBOARD_FAB2_LIB.BASEBOARD_FAB2(SCH_1):PAGE209',
 TOLERANCE='10%',
 SEC_TYPE='0402V',
 MATERIAL='X7R',
 PHYS_PAGE='209',
 XY='(-5925,4025)',
 ROT='0',
 VER='1',
 VALUE='0.1UF',
 PACK_TYPE='0402V',
 PART_NUMBER='A36096-030',
 LOCATION='C1C25',
 ROOM='PVCCIN_CPU1_PWR_VR',
 SEC='1',
 CDS_LIB='dev_discrete',
 CDS_PART_NAME='CAP_A_0402V-0.1UF,16V,10%,X7R,A',
 VOLTAGE='16V',
 PRIM_FILE='./archive_libs/discrete/cap_a/chips/chips.prt';

PART_NAME
 C1C26 'CAP_0402-1.0UF,16V,10%,X6S,D97A':
 ROOM='PVCCIN_CPU1_PWR_VR';

SECTION_NUMBER 1
 '@BASEBOARD_FAB2_LIB.BASEBOARD_FAB2(SCH_1):PAGE209_I16@MSTR_DISCRETE.CAP(CHIPS)':
 C_PATH='@baseboard_fab2_lib.baseboard_fab2(sch_1):page209_i16@mstr_discrete.cap~
(chips)',
 P_PATH='@baseboard_fab2_lib.baseboard_fab2(sch_1):page209_i16@mstr_discrete.cap~
(chips)',
 PATH='I16',
 DRAWING='@BASEBOARD_FAB2_LIB.BASEBOARD_FAB2(SCH_1):PAGE209',
 TOLERANCE='10%',
 SEC_TYPE='0402',
 MATERIAL='X6S',
 PHYS_PAGE='209',
 XY='(-6225,4025)',
 ROT='0',
 VER='1',
 VALUE='1.0UF',
 PACK_TYPE='0402',
 PART_NUMBER='D97712-011',
 LOCATION='C1C26',
 ROOM='PVCCIN_CPU1_PWR_VR',
 SEC='1',
 CDS_LIB='mstr_discrete',
 CDS_PART_NAME='CAP_0402-1.0UF,16V,10%,X6S,D97A',
 VOLTAGE='16V',
 PRIM_FILE='./archive_libs/mstr_discrete/cap/chips/chips.prt';

PART_NAME
 C1D1 'CAP_0402LF-220PF,50V,10%,X7R,AA':
 ROOM='PVCCIN_CPU1_VR',
 NO_XNET_CONNECTION='1';

SECTION_NUMBER 1
 '@BASEBOARD_FAB2_LIB.BASEBOARD_FAB2(SCH_1):PAGE206_I78@MSTR_DISCRETE.CAP(CHIPS)':
 C_PATH='@baseboard_fab2_lib.baseboard_fab2(sch_1):page206_i78@mstr_discrete.cap~
(chips)',
 P_PATH='@baseboard_fab2_lib.baseboard_fab2(sch_1):page206_i78@mstr_discrete.cap~
(chips)',
 PATH='I78',
 DRAWING='@BASEBOARD_FAB2_LIB.BASEBOARD_FAB2(SCH_1):PAGE206',
 TOLERANCE='10%',
 SEC_TYPE='0402LF',
 MATERIAL='X7R',
 NO_XNET_CONNECTION='1',
 PHYS_PAGE='206',
 XY='(-6550,2375)',
 ROT='0',
 VER='1',
 VALUE='220PF',
 PACK_TYPE='0402LF',
 PART_NUMBER='A36096-050',
 LOCATION='C1D1',
 ROOM='PVCCIN_CPU1_VR',
 SEC='1',
 CDS_LIB='mstr_discrete',
 CDS_PART_NAME='CAP_0402LF-220PF,50V,10%,X7R,AA',
 VOLTAGE='50V',
 PRIM_FILE='./archive_libs/mstr_discrete/cap/chips/chips.prt';

PART_NAME
 C1D3 'CAP_A_0603V-22.0UF,4V,20%,X6S,A':
 GROUP='PWR_MLCC_CAP',
 ROOM='PVCCIN_CPU1_PWR_VR';

SECTION_NUMBER 1
 '@BASEBOARD_FAB2_LIB.BASEBOARD_FAB2(SCH_1):PAGE208_I22@DEV_DISCRETE.CAP_A(CHIPS)':
 C_PATH='@baseboard_fab2_lib.baseboard_fab2(sch_1):page208_i22@dev_discrete.cap_~
a(chips)',
 P_PATH='@baseboard_fab2_lib.baseboard_fab2(sch_1):page208_i22@dev_discrete.cap_~
a(chips)',
 PATH='I22',
 DRAWING='@BASEBOARD_FAB2_LIB.BASEBOARD_FAB2(SCH_1):PAGE208',
 TOLERANCE='20%',
 SEC_TYPE='0603V',
 MATERIAL='X6S',
 BOM_COST='PROC_VRD_VCCIN_CPU0',
 PHYS_PAGE='208',
 XY='(-700,800)',
 ROT='0',
 VER='1',
 VALUE='22.0UF',
 PACK_TYPE='0603V',
 PART_NUMBER='E15431-004',
 LOCATION='C1D3',
 ROOM='PVCCIN_CPU1_PWR_VR',
 GROUP='PWR_MLCC_CAP',
 SEC='1',
 CDS_LIB='dev_discrete',
 CDS_PART_NAME='CAP_A_0603V-22.0UF,4V,20%,X6S,A',
 VOLTAGE='4V',
 PRIM_FILE='./archive_libs/discrete/cap_a/chips/chips.prt';

PART_NAME
 C1D5 'SC1U10V2KX-4-GP_SMD-BCG6-SC1U1A':;

SECTION_NUMBER 1
 '@BASEBOARD_FAB2_LIB.BASEBOARD_FAB2(SCH_1):PAGE208_I119@W_HDL.SC1U10V2KX-4-GP(CHIPS)':
 C_PATH='@baseboard_fab2_lib.baseboard_fab2(sch_1):page208_i119@w_hdl.\sc1u10v2k~
x-4-gp\(chips)',
 P_PATH='@baseboard_fab2_lib.baseboard_fab2(sch_1):page208_i119@w_hdl.\sc1u10v2k~
x-4-gp\(chips)',
 PATH='I119',
 DRAWING='@BASEBOARD_FAB2_LIB.BASEBOARD_FAB2(SCH_1):PAGE208',
 PACK_SIZE='0402',
 RATED='10V',
 ATTRIBUTE='1UF',
 TOLERANCE='10%',
 SEC_TYPE='SMD-BCG6',
 PHYS_PAGE='208',
 XY='(-5200,1550)',
 ROT='0',
 VER='1',
 VALUE='SC1U10V2KX-4-GP',
 PACK_TYPE='SMD-BCG6',
 PART_NUMBER='78.10523.8FL',
 LOCATION='C1D5',
 SEC='1',
 CDS_LIB='w_hdl',
 CDS_PART_NAME='SC1U10V2KX-4-GP_SMD-BCG6-SC1U1A',
 PRIM_FILE='C:/<user>/w_hdl/sc1u10v2kx#2d4#2dgp/chips/chips.prt';

PART_NAME
 C1D6 'CAP_0402-0.22UF,16V,10%,X7R,A3A':
 ROOM='PVCCIN_CPU1_PWR_VR';

SECTION_NUMBER 1
 '@BASEBOARD_FAB2_LIB.BASEBOARD_FAB2(SCH_1):PAGE208_I46@MSTR_DISCRETE.CAP(CHIPS)':
 C_PATH='@baseboard_fab2_lib.baseboard_fab2(sch_1):page208_i46@mstr_discrete.cap~
(chips)',
 P_PATH='@baseboard_fab2_lib.baseboard_fab2(sch_1):page208_i46@mstr_discrete.cap~
(chips)',
 PATH='I46',
 DRAWING='@BASEBOARD_FAB2_LIB.BASEBOARD_FAB2(SCH_1):PAGE208',
 TOLERANCE='10%',
 SEC_TYPE='0402',
 MATERIAL='X7R',
 PHYS_PAGE='208',
 XY='(-4800,1575)',
 ROT='0',
 VER='1',
 VALUE='0.22UF',
 PACK_TYPE='0402',
 PART_NUMBER='A36096-155',
 LOCATION='C1D6',
 ROOM='PVCCIN_CPU1_PWR_VR',
 SEC='1',
 CDS_LIB='mstr_discrete',
 CDS_PART_NAME='CAP_0402-0.22UF,16V,10%,X7R,A3A',
 VOLTAGE='16V',
 PRIM_FILE='./archive_libs/mstr_discrete/cap/chips/chips.prt';

PART_NAME
 C1D7 'CAP_0402-1.0UF,16V,10%,X6S,D97A':
 ROOM='PVCCIN_CPU1_PWR_VR';

SECTION_NUMBER 1
 '@BASEBOARD_FAB2_LIB.BASEBOARD_FAB2(SCH_1):PAGE208_I50@MSTR_DISCRETE.CAP(CHIPS)':
 C_PATH='@baseboard_fab2_lib.baseboard_fab2(sch_1):page208_i50@mstr_discrete.cap~
(chips)',
 P_PATH='@baseboard_fab2_lib.baseboard_fab2(sch_1):page208_i50@mstr_discrete.cap~
(chips)',
 PATH='I50',
 DRAWING='@BASEBOARD_FAB2_LIB.BASEBOARD_FAB2(SCH_1):PAGE208',
 TOLERANCE='10%',
 SEC_TYPE='0402',
 MATERIAL='X6S',
 PHYS_PAGE='208',
 XY='(-5700,1575)',
 ROT='0',
 VER='1',
 VALUE='1.0UF',
 PACK_TYPE='0402',
 PART_NUMBER='D97712-011',
 LOCATION='C1D7',
 ROOM='PVCCIN_CPU1_PWR_VR',
 SEC='1',
 CDS_LIB='mstr_discrete',
 CDS_PART_NAME='CAP_0402-1.0UF,16V,10%,X6S,D97A',
 VOLTAGE='16V',
 PRIM_FILE='./archive_libs/mstr_discrete/cap/chips/chips.prt';

PART_NAME
 C1D9 'CAP_A_0402V-0.1UF,16V,10%,X7R,A':
 ROOM='HOT_SWAP';

SECTION_NUMBER 1
 '@BASEBOARD_FAB2_LIB.BASEBOARD_FAB2(SCH_1):PAGE200_I187@DEV_DISCRETE.CAP_A(CHIPS)':
 C_PATH='@baseboard_fab2_lib.baseboard_fab2(sch_1):page200_i187@dev_discrete.cap~
_a(chips)',
 P_PATH='@baseboard_fab2_lib.baseboard_fab2(sch_1):page200_i187@dev_discrete.cap~
_a(chips)',
 PATH='I187',
 DRAWING='@BASEBOARD_FAB2_LIB.BASEBOARD_FAB2(SCH_1):PAGE200',
 TOLERANCE='10%',
 SEC_TYPE='0402V',
 MATERIAL='X7R',
 PHYS_PAGE='200',
 XY='(-3800,3425)',
 ROT='2',
 VER='1',
 VALUE='0.1UF',
 PACK_TYPE='0402V',
 PART_NUMBER='A36096-030',
 LOCATION='C1D9',
 ROOM='HOT_SWAP',
 SEC='1',
 CDS_LIB='dev_discrete',
 CDS_PART_NAME='CAP_A_0402V-0.1UF,16V,10%,X7R,A',
 VOLTAGE='16V',
 PRIM_FILE='./archive_libs/discrete/cap_a/chips/chips.prt';

PART_NAME
 C1D10 'CAP_0402-0.220UF,16V,10%,X7R,AA':
 ROOM='PVCCIN_CPU1_PWR_VR',
 NO_XNET_CONNECTION='1';

SECTION_NUMBER 1
 '@BASEBOARD_FAB2_LIB.BASEBOARD_FAB2(SCH_1):PAGE208_I48@MSTR_DISCRETE.CAP(CHIPS)':
 C_PATH='@baseboard_fab2_lib.baseboard_fab2(sch_1):page208_i48@mstr_discrete.cap~
(chips)',
 P_PATH='@baseboard_fab2_lib.baseboard_fab2(sch_1):page208_i48@mstr_discrete.cap~
(chips)',
 PATH='I48',
 DRAWING='@BASEBOARD_FAB2_LIB.BASEBOARD_FAB2(SCH_1):PAGE208',
 SPOF='TRUE',
 TOLERANCE='10%',
 SEC_TYPE='0402',
 MATERIAL='X7R',
 NO_XNET_CONNECTION='1',
 PHYS_PAGE='208',
 XY='(-5975,900)',
 ROT='2',
 VER='1',
 VALUE='0.220UF',
 PACK_TYPE='0402',
 PART_NUMBER='A36096-104',
 LOCATION='C1D10',
 ROOM='PVCCIN_CPU1_PWR_VR',
 SEC='1',
 CDS_LIB='mstr_discrete',
 CDS_PART_NAME='CAP_0402-0.220UF,16V,10%,X7R,AA',
 VOLTAGE='16V',
 PRIM_FILE='./archive_libs/mstr_discrete/cap/chips/chips.prt';

PART_NAME
 C1D11 'CAP_A_0402V-0.1UF,16V,10%,X7R,A':
 ROOM='HOT_SWAP';

SECTION_NUMBER 1
 '@BASEBOARD_FAB2_LIB.BASEBOARD_FAB2(SCH_1):PAGE199_I53@DEV_DISCRETE.CAP_A(CHIPS)':
 C_PATH='@baseboard_fab2_lib.baseboard_fab2(sch_1):page199_i53@dev_discrete.cap_~
a(chips)',
 P_PATH='@baseboard_fab2_lib.baseboard_fab2(sch_1):page199_i53@dev_discrete.cap_~
a(chips)',
 PATH='I53',
 DRAWING='@BASEBOARD_FAB2_LIB.BASEBOARD_FAB2(SCH_1):PAGE199',
 TOLERANCE='10%',
 SEC_TYPE='0402V',
 MATERIAL='X7R',
 PHYS_PAGE='199',
 XY='(-7025,2175)',
 ROT='2',
 VER='1',
 VALUE='0.1UF',
 PACK_TYPE='0402V',
 PART_NUMBER='A36096-030',
 LOCATION='C1D11',
 ROOM='HOT_SWAP',
 SEC='1',
 CDS_LIB='dev_discrete',
 CDS_PART_NAME='CAP_A_0402V-0.1UF,16V,10%,X7R,A',
 VOLTAGE='16V',
 PRIM_FILE='./archive_libs/discrete/cap_a/chips/chips.prt';

PART_NAME
 C1D12 'CAP_0402-1.0UF,16V,10%,X6S,D97A':
 ROOM='PVCCIN_CPU1_PWR_VR';

SECTION_NUMBER 1
 '@BASEBOARD_FAB2_LIB.BASEBOARD_FAB2(SCH_1):PAGE208_I52@MSTR_DISCRETE.CAP(CHIPS)':
 C_PATH='@baseboard_fab2_lib.baseboard_fab2(sch_1):page208_i52@mstr_discrete.cap~
(chips)',
 P_PATH='@baseboard_fab2_lib.baseboard_fab2(sch_1):page208_i52@mstr_discrete.cap~
(chips)',
 PATH='I52',
 DRAWING='@BASEBOARD_FAB2_LIB.BASEBOARD_FAB2(SCH_1):PAGE208',
 TOLERANCE='10%',
 SEC_TYPE='0402',
 MATERIAL='X6S',
 PHYS_PAGE='208',
 XY='(-6250,1575)',
 ROT='0',
 VER='1',
 VALUE='1.0UF',
 PACK_TYPE='0402',
 PART_NUMBER='D97712-011',
 LOCATION='C1D12',
 ROOM='PVCCIN_CPU1_PWR_VR',
 SEC='1',
 CDS_LIB='mstr_discrete',
 CDS_PART_NAME='CAP_0402-1.0UF,16V,10%,X6S,D97A',
 VOLTAGE='16V',
 PRIM_FILE='./archive_libs/mstr_discrete/cap/chips/chips.prt';

PART_NAME
 C1D13 'CAP_A_0402V-0.1UF,16V,10%,X7R,A':
 ROOM='PVCCIN_CPU1_PWR_VR';

SECTION_NUMBER 1
 '@BASEBOARD_FAB2_LIB.BASEBOARD_FAB2(SCH_1):PAGE208_I51@DEV_DISCRETE.CAP_A(CHIPS)':
 C_PATH='@baseboard_fab2_lib.baseboard_fab2(sch_1):page208_i51@dev_discrete.cap_~
a(chips)',
 P_PATH='@baseboard_fab2_lib.baseboard_fab2(sch_1):page208_i51@dev_discrete.cap_~
a(chips)',
 PATH='I51',
 DRAWING='@BASEBOARD_FAB2_LIB.BASEBOARD_FAB2(SCH_1):PAGE208',
 TOLERANCE='10%',
 SEC_TYPE='0402V',
 MATERIAL='X7R',
 PHYS_PAGE='208',
 XY='(-5950,1575)',
 ROT='0',
 VER='1',
 VALUE='0.1UF',
 PACK_TYPE='0402V',
 PART_NUMBER='A36096-030',
 LOCATION='C1D13',
 ROOM='PVCCIN_CPU1_PWR_VR',
 SEC='1',
 CDS_LIB='dev_discrete',
 CDS_PART_NAME='CAP_A_0402V-0.1UF,16V,10%,X7R,A',
 VOLTAGE='16V',
 PRIM_FILE='./archive_libs/discrete/cap_a/chips/chips.prt';

PART_NAME
 C1D14 'CAP_A_0603V-22.0UF,4V,20%,X6S,A':
 GROUP='PWR_MLCC_CAP',
 ROOM='PVCCIN_CPU1_PWR_VR';

SECTION_NUMBER 1
 '@BASEBOARD_FAB2_LIB.BASEBOARD_FAB2(SCH_1):PAGE208_I9@DEV_DISCRETE.CAP_A(CHIPS)':
 C_PATH='@baseboard_fab2_lib.baseboard_fab2(sch_1):page208_i9@dev_discrete.cap_a~
(chips)',
 P_PATH='@baseboard_fab2_lib.baseboard_fab2(sch_1):page208_i9@dev_discrete.cap_a~
(chips)',
 PATH='I9',
 DRAWING='@BASEBOARD_FAB2_LIB.BASEBOARD_FAB2(SCH_1):PAGE208',
 TOLERANCE='20%',
 SEC_TYPE='0603V',
 MATERIAL='X6S',
 BOM_COST='PROC_VRD_VCCIN_CPU0',
 PHYS_PAGE='208',
 XY='(-800,3400)',
 ROT='0',
 VER='1',
 VALUE='22.0UF',
 PACK_TYPE='0603V',
 PART_NUMBER='E15431-004',
 LOCATION='C1D14',
 ROOM='PVCCIN_CPU1_PWR_VR',
 GROUP='PWR_MLCC_CAP',
 SEC='1',
 CDS_LIB='dev_discrete',
 CDS_PART_NAME='CAP_A_0603V-22.0UF,4V,20%,X6S,A',
 VOLTAGE='4V',
 PRIM_FILE='./archive_libs/discrete/cap_a/chips/chips.prt';

PART_NAME
 C1D15 'SC1U10V2KX-4-GP_SMD-BCG6-SC1U1A':;

SECTION_NUMBER 1
 '@BASEBOARD_FAB2_LIB.BASEBOARD_FAB2(SCH_1):PAGE208_I118@W_HDL.SC1U10V2KX-4-GP(CHIPS)':
 C_PATH='@baseboard_fab2_lib.baseboard_fab2(sch_1):page208_i118@w_hdl.\sc1u10v2k~
x-4-gp\(chips)',
 P_PATH='@baseboard_fab2_lib.baseboard_fab2(sch_1):page208_i118@w_hdl.\sc1u10v2k~
x-4-gp\(chips)',
 PATH='I118',
 DRAWING='@BASEBOARD_FAB2_LIB.BASEBOARD_FAB2(SCH_1):PAGE208',
 PACK_SIZE='0402',
 RATED='10V',
 ATTRIBUTE='1UF',
 TOLERANCE='10%',
 SEC_TYPE='SMD-BCG6',
 PHYS_PAGE='208',
 XY='(-5100,4200)',
 ROT='0',
 VER='1',
 VALUE='SC1U10V2KX-4-GP',
 PACK_TYPE='SMD-BCG6',
 PART_NUMBER='78.10523.8FL',
 LOCATION='C1D15',
 SEC='1',
 CDS_LIB='w_hdl',
 CDS_PART_NAME='SC1U10V2KX-4-GP_SMD-BCG6-SC1U1A',
 PRIM_FILE='C:/<user>/w_hdl/sc1u10v2kx#2d4#2dgp/chips/chips.prt';

PART_NAME
 C1D16 'CAP_0402-0.22UF,16V,10%,X7R,A3A':
 ROOM='PVCCIN_CPU1_PWR_VR';

SECTION_NUMBER 1
 '@BASEBOARD_FAB2_LIB.BASEBOARD_FAB2(SCH_1):PAGE208_I38@MSTR_DISCRETE.CAP(CHIPS)':
 C_PATH='@baseboard_fab2_lib.baseboard_fab2(sch_1):page208_i38@mstr_discrete.cap~
(chips)',
 P_PATH='@baseboard_fab2_lib.baseboard_fab2(sch_1):page208_i38@mstr_discrete.cap~
(chips)',
 PATH='I38',
 DRAWING='@BASEBOARD_FAB2_LIB.BASEBOARD_FAB2(SCH_1):PAGE208',
 TOLERANCE='10%',
 SEC_TYPE='0402',
 MATERIAL='X7R',
 PHYS_PAGE='208',
 XY='(-4775,4200)',
 ROT='0',
 VER='1',
 VALUE='0.22UF',
 PACK_TYPE='0402',
 PART_NUMBER='A36096-155',
 LOCATION='C1D16',
 ROOM='PVCCIN_CPU1_PWR_VR',
 SEC='1',
 CDS_LIB='mstr_discrete',
 CDS_PART_NAME='CAP_0402-0.22UF,16V,10%,X7R,A3A',
 VOLTAGE='16V',
 PRIM_FILE='./archive_libs/mstr_discrete/cap/chips/chips.prt';

PART_NAME
 C1D17 'CAP_0402-1.0UF,16V,10%,X6S,D97A':
 ROOM='PVCCIN_CPU1_PWR_VR';

SECTION_NUMBER 1
 '@BASEBOARD_FAB2_LIB.BASEBOARD_FAB2(SCH_1):PAGE208_I43@MSTR_DISCRETE.CAP(CHIPS)':
 C_PATH='@baseboard_fab2_lib.baseboard_fab2(sch_1):page208_i43@mstr_discrete.cap~
(chips)',
 P_PATH='@baseboard_fab2_lib.baseboard_fab2(sch_1):page208_i43@mstr_discrete.cap~
(chips)',
 PATH='I43',
 DRAWING='@BASEBOARD_FAB2_LIB.BASEBOARD_FAB2(SCH_1):PAGE208',
 TOLERANCE='10%',
 SEC_TYPE='0402',
 MATERIAL='X6S',
 PHYS_PAGE='208',
 XY='(-5500,4150)',
 ROT='0',
 VER='1',
 VALUE='1.0UF',
 PACK_TYPE='0402',
 PART_NUMBER='D97712-011',
 LOCATION='C1D17',
 ROOM='PVCCIN_CPU1_PWR_VR',
 SEC='1',
 CDS_LIB='mstr_discrete',
 CDS_PART_NAME='CAP_0402-1.0UF,16V,10%,X6S,D97A',
 VOLTAGE='16V',
 PRIM_FILE='./archive_libs/mstr_discrete/cap/chips/chips.prt';

PART_NAME
 C1D19 'CAP_0402-1.0UF,16V,10%,X6S,D97A':
 ROOM='HOT_SWAP';

SECTION_NUMBER 1
 '@BASEBOARD_FAB2_LIB.BASEBOARD_FAB2(SCH_1):PAGE199_I119@MSTR_DISCRETE.CAP(CHIPS)':
 C_PATH='@baseboard_fab2_lib.baseboard_fab2(sch_1):page199_i119@mstr_discrete.ca~
p(chips)',
 P_PATH='@baseboard_fab2_lib.baseboard_fab2(sch_1):page199_i119@mstr_discrete.ca~
p(chips)',
 PATH='I119',
 DRAWING='@BASEBOARD_FAB2_LIB.BASEBOARD_FAB2(SCH_1):PAGE199',
 TOLERANCE='10%',
 SEC_TYPE='0402',
 MATERIAL='X6S',
 PHYS_PAGE='199',
 XY='(-5650,2000)',
 ROT='0',
 VER='1',
 VALUE='1.0UF',
 PACK_TYPE='0402',
 PART_NUMBER='D97712-011',
 LOCATION='C1D19',
 ROOM='HOT_SWAP',
 SEC='1',
 CDS_LIB='mstr_discrete',
 CDS_PART_NAME='CAP_0402-1.0UF,16V,10%,X6S,D97A',
 VOLTAGE='16V',
 PRIM_FILE='./archive_libs/mstr_discrete/cap/chips/chips.prt';

PART_NAME
 C1D20 'CAP_0402-0.220UF,16V,10%,X7R,AA':
 ROOM='PVCCIN_CPU1_PWR_VR',
 NO_XNET_CONNECTION='1';

SECTION_NUMBER 1
 '@BASEBOARD_FAB2_LIB.BASEBOARD_FAB2(SCH_1):PAGE208_I40@MSTR_DISCRETE.CAP(CHIPS)':
 C_PATH='@baseboard_fab2_lib.baseboard_fab2(sch_1):page208_i40@mstr_discrete.cap~
(chips)',
 P_PATH='@baseboard_fab2_lib.baseboard_fab2(sch_1):page208_i40@mstr_discrete.cap~
(chips)',
 PATH='I40',
 DRAWING='@BASEBOARD_FAB2_LIB.BASEBOARD_FAB2(SCH_1):PAGE208',
 SPOF='TRUE',
 TOLERANCE='10%',
 SEC_TYPE='0402',
 MATERIAL='X7R',
 NO_XNET_CONNECTION='1',
 PHYS_PAGE='208',
 XY='(-5975,3575)',
 ROT='2',
 VER='1',
 VALUE='0.220UF',
 PACK_TYPE='0402',
 PART_NUMBER='A36096-104',
 LOCATION='C1D20',
 ROOM='PVCCIN_CPU1_PWR_VR',
 SEC='1',
 CDS_LIB='mstr_discrete',
 CDS_PART_NAME='CAP_0402-0.220UF,16V,10%,X7R,AA',
 VOLTAGE='16V',
 PRIM_FILE='./archive_libs/mstr_discrete/cap/chips/chips.prt';

PART_NAME
 C1D21 'CAP_A_0402V-0.1UF,16V,10%,X7R,A':
 ROOM='HOT_SWAP';

SECTION_NUMBER 1
 '@BASEBOARD_FAB2_LIB.BASEBOARD_FAB2(SCH_1):PAGE199_I121@DEV_DISCRETE.CAP_A(CHIPS)':
 C_PATH='@baseboard_fab2_lib.baseboard_fab2(sch_1):page199_i121@dev_discrete.cap~
_a(chips)',
 P_PATH='@baseboard_fab2_lib.baseboard_fab2(sch_1):page199_i121@dev_discrete.cap~
_a(chips)',
 PATH='I121',
 DRAWING='@BASEBOARD_FAB2_LIB.BASEBOARD_FAB2(SCH_1):PAGE199',
 TOLERANCE='10%',
 SEC_TYPE='0402V',
 MATERIAL='X7R',
 PHYS_PAGE='199',
 XY='(-5000,425)',
 ROT='2',
 VER='1',
 VALUE='0.1UF',
 PACK_TYPE='0402V',
 PART_NUMBER='A36096-030',
 LOCATION='C1D21',
 ROOM='HOT_SWAP',
 SEC='1',
 CDS_LIB='dev_discrete',
 CDS_PART_NAME='CAP_A_0402V-0.1UF,16V,10%,X7R,A',
 VOLTAGE='16V',
 PRIM_FILE='./archive_libs/discrete/cap_a/chips/chips.prt';

PART_NAME
 C1D22 'CAP_A_0402V-0.1UF,16V,10%,EMPTA':
 ROOM='HOT_SWAP';

SECTION_NUMBER 1
 '@BASEBOARD_FAB2_LIB.BASEBOARD_FAB2(SCH_1):PAGE200_I42@DEV_DISCRETE.CAP_A(CHIPS)':
 C_PATH='@baseboard_fab2_lib.baseboard_fab2(sch_1):page200_i42@dev_discrete.cap_~
a(chips)',
 P_PATH='@baseboard_fab2_lib.baseboard_fab2(sch_1):page200_i42@dev_discrete.cap_~
a(chips)',
 PATH='I42',
 DRAWING='@BASEBOARD_FAB2_LIB.BASEBOARD_FAB2(SCH_1):PAGE200',
 TOLERANCE='10%',
 MATERIAL='EMPTY',
 PHYS_PAGE='200',
 XY='(-175,3425)',
 ROT='0',
 VER='1',
 VALUE='0.1UF',
 PACK_TYPE='0402V',
 PART_NUMBER='A36096-030',
 LOCATION='C1D22',
 ROOM='HOT_SWAP',
 CDS_LIB='dev_discrete',
 CDS_PART_NAME='CAP_A_0402V-0.1UF,16V,10%,EMPTA',
 VOLTAGE='16V',
 PRIM_FILE='./archive_libs/discrete/cap_a/chips/chips.prt';

PART_NAME
 C1D23 'CAP_0402-1.0UF,16V,10%,X6S,D97A':
 ROOM='PVCCIN_CPU1_PWR_VR';

SECTION_NUMBER 1
 '@BASEBOARD_FAB2_LIB.BASEBOARD_FAB2(SCH_1):PAGE208_I45@MSTR_DISCRETE.CAP(CHIPS)':
 C_PATH='@baseboard_fab2_lib.baseboard_fab2(sch_1):page208_i45@mstr_discrete.cap~
(chips)',
 P_PATH='@baseboard_fab2_lib.baseboard_fab2(sch_1):page208_i45@mstr_discrete.cap~
(chips)',
 PATH='I45',
 DRAWING='@BASEBOARD_FAB2_LIB.BASEBOARD_FAB2(SCH_1):PAGE208',
 TOLERANCE='10%',
 SEC_TYPE='0402',
 MATERIAL='X6S',
 PHYS_PAGE='208',
 XY='(-6025,4150)',
 ROT='0',
 VER='1',
 VALUE='1.0UF',
 PACK_TYPE='0402',
 PART_NUMBER='D97712-011',
 LOCATION='C1D23',
 ROOM='PVCCIN_CPU1_PWR_VR',
 SEC='1',
 CDS_LIB='mstr_discrete',
 CDS_PART_NAME='CAP_0402-1.0UF,16V,10%,X6S,D97A',
 VOLTAGE='16V',
 PRIM_FILE='./archive_libs/mstr_discrete/cap/chips/chips.prt';

PART_NAME
 C1D24 'CAP_A_0603V-22.0UF,4V,20%,X6S,A':
 GROUP='PWR_MLCC_CAP',
 ROOM='PVCCIN_CPU1_PWR_VR';

SECTION_NUMBER 1
 '@BASEBOARD_FAB2_LIB.BASEBOARD_FAB2(SCH_1):PAGE209_I42@DEV_DISCRETE.CAP_A(CHIPS)':
 C_PATH='@baseboard_fab2_lib.baseboard_fab2(sch_1):page209_i42@dev_discrete.cap_~
a(chips)',
 P_PATH='@baseboard_fab2_lib.baseboard_fab2(sch_1):page209_i42@dev_discrete.cap_~
a(chips)',
 PATH='I42',
 DRAWING='@BASEBOARD_FAB2_LIB.BASEBOARD_FAB2(SCH_1):PAGE209',
 TOLERANCE='20%',
 SEC_TYPE='0603V',
 MATERIAL='X6S',
 BOM_COST='PROC_VRD_VCCIN_CPU0',
 PHYS_PAGE='209',
 XY='(-750,3250)',
 ROT='0',
 VER='1',
 VALUE='22.0UF',
 PACK_TYPE='0603V',
 PART_NUMBER='E15431-004',
 LOCATION='C1D24',
 ROOM='PVCCIN_CPU1_PWR_VR',
 GROUP='PWR_MLCC_CAP',
 SEC='1',
 CDS_LIB='dev_discrete',
 CDS_PART_NAME='CAP_A_0603V-22.0UF,4V,20%,X6S,A',
 VOLTAGE='4V',
 PRIM_FILE='./archive_libs/discrete/cap_a/chips/chips.prt';

PART_NAME
 C1D25 'CAP_0402-1.0UF,16V,10%,X6S,D97A':
 ROOM='HOT_SWAP';

SECTION_NUMBER 1
 '@BASEBOARD_FAB2_LIB.BASEBOARD_FAB2(SCH_1):PAGE199_I3@MSTR_DISCRETE.CAP(CHIPS)':
 C_PATH='@baseboard_fab2_lib.baseboard_fab2(sch_1):page199_i3@mstr_discrete.cap(~
chips)',
 P_PATH='@baseboard_fab2_lib.baseboard_fab2(sch_1):page199_i3@mstr_discrete.cap(~
chips)',
 PATH='I3',
 DRAWING='@BASEBOARD_FAB2_LIB.BASEBOARD_FAB2(SCH_1):PAGE199',
 TOLERANCE='10%',
 SEC_TYPE='0402',
 MATERIAL='X6S',
 PHYS_PAGE='199',
 XY='(-5525,3600)',
 ROT='0',
 VER='1',
 VALUE='1.0UF',
 PACK_TYPE='0402',
 PART_NUMBER='D97712-011',
 LOCATION='C1D25',
 ROOM='HOT_SWAP',
 SEC='1',
 CDS_LIB='mstr_discrete',
 CDS_PART_NAME='CAP_0402-1.0UF,16V,10%,X6S,D97A',
 VOLTAGE='16V',
 PRIM_FILE='./archive_libs/mstr_discrete/cap/chips/chips.prt';

PART_NAME
 C1D26 'CAP_A_0402V-0.1UF,16V,10%,X7R,A':
 ROOM='HOT_SWAP';

SECTION_NUMBER 1
 '@BASEBOARD_FAB2_LIB.BASEBOARD_FAB2(SCH_1):PAGE199_I107@DEV_DISCRETE.CAP_A(CHIPS)':
 C_PATH='@baseboard_fab2_lib.baseboard_fab2(sch_1):page199_i107@dev_discrete.cap~
_a(chips)',
 P_PATH='@baseboard_fab2_lib.baseboard_fab2(sch_1):page199_i107@dev_discrete.cap~
_a(chips)',
 PATH='I107',
 DRAWING='@BASEBOARD_FAB2_LIB.BASEBOARD_FAB2(SCH_1):PAGE199',
 TOLERANCE='10%',
 SEC_TYPE='0402V',
 MATERIAL='X7R',
 PHYS_PAGE='199',
 XY='(-6075,3575)',
 ROT='2',
 VER='1',
 VALUE='0.1UF',
 PACK_TYPE='0402V',
 PART_NUMBER='A36096-030',
 LOCATION='C1D26',
 ROOM='HOT_SWAP',
 SEC='1',
 CDS_LIB='dev_discrete',
 CDS_PART_NAME='CAP_A_0402V-0.1UF,16V,10%,X7R,A',
 VOLTAGE='16V',
 PRIM_FILE='./archive_libs/discrete/cap_a/chips/chips.prt';

PART_NAME
 C1D27 'CAP_A_0402V-0.1UF,16V,10%,X7R,A':
 ROOM='HOT_SWAP';

SECTION_NUMBER 1
 '@BASEBOARD_FAB2_LIB.BASEBOARD_FAB2(SCH_1):PAGE199_I7@DEV_DISCRETE.CAP_A(CHIPS)':
 C_PATH='@baseboard_fab2_lib.baseboard_fab2(sch_1):page199_i7@dev_discrete.cap_a~
(chips)',
 P_PATH='@baseboard_fab2_lib.baseboard_fab2(sch_1):page199_i7@dev_discrete.cap_a~
(chips)',
 PATH='I7',
 DRAWING='@BASEBOARD_FAB2_LIB.BASEBOARD_FAB2(SCH_1):PAGE199',
 TOLERANCE='10%',
 SEC_TYPE='0402V',
 MATERIAL='X7R',
 PHYS_PAGE='199',
 XY='(-6775,3575)',
 ROT='2',
 VER='1',
 VALUE='0.1UF',
 PACK_TYPE='0402V',
 PART_NUMBER='A36096-030',
 LOCATION='C1D27',
 ROOM='HOT_SWAP',
 SEC='1',
 CDS_LIB='dev_discrete',
 CDS_PART_NAME='CAP_A_0402V-0.1UF,16V,10%,X7R,A',
 VOLTAGE='16V',
 PRIM_FILE='./archive_libs/discrete/cap_a/chips/chips.prt';

PART_NAME
 C1D28 'CAP_A_0402V-0.1UF,16V,10%,X7R,A':
 ROOM='PVCCIN_CPU1_PWR_VR';

SECTION_NUMBER 1
 '@BASEBOARD_FAB2_LIB.BASEBOARD_FAB2(SCH_1):PAGE208_I44@DEV_DISCRETE.CAP_A(CHIPS)':
 C_PATH='@baseboard_fab2_lib.baseboard_fab2(sch_1):page208_i44@dev_discrete.cap_~
a(chips)',
 P_PATH='@baseboard_fab2_lib.baseboard_fab2(sch_1):page208_i44@dev_discrete.cap_~
a(chips)',
 PATH='I44',
 DRAWING='@BASEBOARD_FAB2_LIB.BASEBOARD_FAB2(SCH_1):PAGE208',
 TOLERANCE='10%',
 SEC_TYPE='0402V',
 MATERIAL='X7R',
 PHYS_PAGE='208',
 XY='(-5775,4150)',
 ROT='0',
 VER='1',
 VALUE='0.1UF',
 PACK_TYPE='0402V',
 PART_NUMBER='A36096-030',
 LOCATION='C1D28',
 ROOM='PVCCIN_CPU1_PWR_VR',
 SEC='1',
 CDS_LIB='dev_discrete',
 CDS_PART_NAME='CAP_A_0402V-0.1UF,16V,10%,X7R,A',
 VOLTAGE='16V',
 PRIM_FILE='./archive_libs/discrete/cap_a/chips/chips.prt';

PART_NAME
 C1D32 'CAP_0402-1.0UF,16V,10%,X6S,D97A':
 ROOM='PVCCIN_CPU1_PWR_VR';

SECTION_NUMBER 1
 '@BASEBOARD_FAB2_LIB.BASEBOARD_FAB2(SCH_1):PAGE209_I18@MSTR_DISCRETE.CAP(CHIPS)':
 C_PATH='@baseboard_fab2_lib.baseboard_fab2(sch_1):page209_i18@mstr_discrete.cap~
(chips)',
 P_PATH='@baseboard_fab2_lib.baseboard_fab2(sch_1):page209_i18@mstr_discrete.cap~
(chips)',
 PATH='I18',
 DRAWING='@BASEBOARD_FAB2_LIB.BASEBOARD_FAB2(SCH_1):PAGE209',
 TOLERANCE='10%',
 SEC_TYPE='0402',
 MATERIAL='X6S',
 PHYS_PAGE='209',
 XY='(-5625,4025)',
 ROT='0',
 VER='1',
 VALUE='1.0UF',
 PACK_TYPE='0402',
 PART_NUMBER='D97712-011',
 LOCATION='C1D32',
 ROOM='PVCCIN_CPU1_PWR_VR',
 SEC='1',
 CDS_LIB='mstr_discrete',
 CDS_PART_NAME='CAP_0402-1.0UF,16V,10%,X6S,D97A',
 VOLTAGE='16V',
 PRIM_FILE='./archive_libs/mstr_discrete/cap/chips/chips.prt';

PART_NAME
 C1D33 'CAP_0402-0.22UF,16V,10%,X7R,A3A':
 ROOM='PVCCIN_CPU1_PWR_VR';

SECTION_NUMBER 1
 '@BASEBOARD_FAB2_LIB.BASEBOARD_FAB2(SCH_1):PAGE209_I22@MSTR_DISCRETE.CAP(CHIPS)':
 C_PATH='@baseboard_fab2_lib.baseboard_fab2(sch_1):page209_i22@mstr_discrete.cap~
(chips)',
 P_PATH='@baseboard_fab2_lib.baseboard_fab2(sch_1):page209_i22@mstr_discrete.cap~
(chips)',
 PATH='I22',
 DRAWING='@BASEBOARD_FAB2_LIB.BASEBOARD_FAB2(SCH_1):PAGE209',
 TOLERANCE='10%',
 SEC_TYPE='0402',
 MATERIAL='X7R',
 PHYS_PAGE='209',
 XY='(-4800,4025)',
 ROT='0',
 VER='1',
 VALUE='0.22UF',
 PACK_TYPE='0402',
 PART_NUMBER='A36096-155',
 LOCATION='C1D33',
 ROOM='PVCCIN_CPU1_PWR_VR',
 SEC='1',
 CDS_LIB='mstr_discrete',
 CDS_PART_NAME='CAP_0402-0.22UF,16V,10%,X7R,A3A',
 VOLTAGE='16V',
 PRIM_FILE='./archive_libs/mstr_discrete/cap/chips/chips.prt';

PART_NAME
 C1D34 'CAP_A_0402V-0.1UF,16V,10%,X7R,A':
 ROOM='PVCCIN_CPU1_PWR_VR';

SECTION_NUMBER 1
 '@BASEBOARD_FAB2_LIB.BASEBOARD_FAB2(SCH_1):PAGE207_I41@DEV_DISCRETE.CAP_A(CHIPS)':
 C_PATH='@baseboard_fab2_lib.baseboard_fab2(sch_1):page207_i41@dev_discrete.cap_~
a(chips)',
 P_PATH='@baseboard_fab2_lib.baseboard_fab2(sch_1):page207_i41@dev_discrete.cap_~
a(chips)',
 PATH='I41',
 DRAWING='@BASEBOARD_FAB2_LIB.BASEBOARD_FAB2(SCH_1):PAGE207',
 TOLERANCE='10%',
 SEC_TYPE='0402V',
 MATERIAL='X7R',
 PHYS_PAGE='207',
 XY='(-5725,1525)',
 ROT='0',
 VER='1',
 VALUE='0.1UF',
 PACK_TYPE='0402V',
 PART_NUMBER='A36096-030',
 LOCATION='C1D34',
 ROOM='PVCCIN_CPU1_PWR_VR',
 SEC='1',
 CDS_LIB='dev_discrete',
 CDS_PART_NAME='CAP_A_0402V-0.1UF,16V,10%,X7R,A',
 VOLTAGE='16V',
 PRIM_FILE='./archive_libs/discrete/cap_a/chips/chips.prt';

PART_NAME
 C1D35 'CAP_0402-1.0UF,16V,10%,X6S,D97A':
 ROOM='PVCCIN_CPU1_PWR_VR';

SECTION_NUMBER 1
 '@BASEBOARD_FAB2_LIB.BASEBOARD_FAB2(SCH_1):PAGE207_I42@MSTR_DISCRETE.CAP(CHIPS)':
 C_PATH='@baseboard_fab2_lib.baseboard_fab2(sch_1):page207_i42@mstr_discrete.cap~
(chips)',
 P_PATH='@baseboard_fab2_lib.baseboard_fab2(sch_1):page207_i42@mstr_discrete.cap~
(chips)',
 PATH='I42',
 DRAWING='@BASEBOARD_FAB2_LIB.BASEBOARD_FAB2(SCH_1):PAGE207',
 TOLERANCE='10%',
 SEC_TYPE='0402',
 MATERIAL='X6S',
 PHYS_PAGE='207',
 XY='(-6025,1550)',
 ROT='0',
 VER='1',
 VALUE='1.0UF',
 PACK_TYPE='0402',
 PART_NUMBER='D97712-011',
 LOCATION='C1D35',
 ROOM='PVCCIN_CPU1_PWR_VR',
 SEC='1',
 CDS_LIB='mstr_discrete',
 CDS_PART_NAME='CAP_0402-1.0UF,16V,10%,X6S,D97A',
 VOLTAGE='16V',
 PRIM_FILE='./archive_libs/mstr_discrete/cap/chips/chips.prt';

PART_NAME
 C1D36 'CAP_0402-0.220UF,16V,10%,X7R,AA':
 ROOM='PVCCIN_CPU1_PWR_VR',
 NO_XNET_CONNECTION='1';

SECTION_NUMBER 1
 '@BASEBOARD_FAB2_LIB.BASEBOARD_FAB2(SCH_1):PAGE207_I38@MSTR_DISCRETE.CAP(CHIPS)':
 C_PATH='@baseboard_fab2_lib.baseboard_fab2(sch_1):page207_i38@mstr_discrete.cap~
(chips)',
 P_PATH='@baseboard_fab2_lib.baseboard_fab2(sch_1):page207_i38@mstr_discrete.cap~
(chips)',
 PATH='I38',
 DRAWING='@BASEBOARD_FAB2_LIB.BASEBOARD_FAB2(SCH_1):PAGE207',
 SPOF='TRUE',
 TOLERANCE='10%',
 SEC_TYPE='0402',
 MATERIAL='X7R',
 NO_XNET_CONNECTION='1',
 PHYS_PAGE='207',
 XY='(-5550,875)',
 ROT='2',
 VER='1',
 VALUE='0.220UF',
 PACK_TYPE='0402',
 PART_NUMBER='A36096-104',
 LOCATION='C1D36',
 ROOM='PVCCIN_CPU1_PWR_VR',
 SEC='1',
 CDS_LIB='mstr_discrete',
 CDS_PART_NAME='CAP_0402-0.220UF,16V,10%,X7R,AA',
 VOLTAGE='16V',
 PRIM_FILE='./archive_libs/mstr_discrete/cap/chips/chips.prt';

PART_NAME
 C1E2 'CAP_1206-0.068UF,50V,20%,X7R,1A':;

SECTION_NUMBER 1
 '@BASEBOARD_FAB2_LIB.BASEBOARD_FAB2(SCH_1):PAGE200_I155@MSTR_DISCRETE.CAP(CHIPS)':
 C_PATH='@baseboard_fab2_lib.baseboard_fab2(sch_1):page200_i155@mstr_discrete.ca~
p(chips)',
 P_PATH='@baseboard_fab2_lib.baseboard_fab2(sch_1):page200_i155@mstr_discrete.ca~
p(chips)',
 PATH='I155',
 DRAWING='@BASEBOARD_FAB2_LIB.BASEBOARD_FAB2(SCH_1):PAGE200',
 TOLERANCE='20%',
 SEC_TYPE='1206',
 MATERIAL='X7R',
 PHYS_PAGE='200',
 XY='(900,1675)',
 ROT='0',
 VER='1',
 VALUE='0.068UF',
 PACK_TYPE='1206',
 PART_NUMBER='108427-047',
 LOCATION='C1E2',
 SEC='1',
 CDS_LIB='mstr_discrete',
 CDS_PART_NAME='CAP_1206-0.068UF,50V,20%,X7R,1A',
 VOLTAGE='50V',
 PRIM_FILE='./archive_libs/mstr_discrete/cap/chips/chips.prt';

PART_NAME
 C1E3 'CAP_A_0603V-22.0UF,4V,20%,X6S,A':
 GROUP='PWR_MLCC_CAP',
 ROOM='PVCCIN_CPU1_PWR_VR';

SECTION_NUMBER 1
 '@BASEBOARD_FAB2_LIB.BASEBOARD_FAB2(SCH_1):PAGE207_I18@DEV_DISCRETE.CAP_A(CHIPS)':
 C_PATH='@baseboard_fab2_lib.baseboard_fab2(sch_1):page207_i18@dev_discrete.cap_~
a(chips)',
 P_PATH='@baseboard_fab2_lib.baseboard_fab2(sch_1):page207_i18@dev_discrete.cap_~
a(chips)',
 PATH='I18',
 DRAWING='@BASEBOARD_FAB2_LIB.BASEBOARD_FAB2(SCH_1):PAGE207',
 TOLERANCE='20%',
 SEC_TYPE='0603V',
 MATERIAL='X6S',
 BOM_COST='PROC_VRD_VCCIN_CPU0',
 PHYS_PAGE='207',
 XY='(-1100,750)',
 ROT='0',
 VER='1',
 VALUE='22.0UF',
 PACK_TYPE='0603V',
 PART_NUMBER='E15431-004',
 LOCATION='C1E3',
 ROOM='PVCCIN_CPU1_PWR_VR',
 GROUP='PWR_MLCC_CAP',
 SEC='1',
 CDS_LIB='dev_discrete',
 CDS_PART_NAME='CAP_A_0603V-22.0UF,4V,20%,X6S,A',
 VOLTAGE='4V',
 PRIM_FILE='./archive_libs/discrete/cap_a/chips/chips.prt';

PART_NAME
 C1E6 'SC1U10V2KX-4-GP_SMD-BCG6-SC1U1A':;

SECTION_NUMBER 1
 '@BASEBOARD_FAB2_LIB.BASEBOARD_FAB2(SCH_1):PAGE207_I110@W_HDL.SC1U10V2KX-4-GP(CHIPS)':
 C_PATH='@baseboard_fab2_lib.baseboard_fab2(sch_1):page207_i110@w_hdl.\sc1u10v2k~
x-4-gp\(chips)',
 P_PATH='@baseboard_fab2_lib.baseboard_fab2(sch_1):page207_i110@w_hdl.\sc1u10v2k~
x-4-gp\(chips)',
 PATH='I110',
 DRAWING='@BASEBOARD_FAB2_LIB.BASEBOARD_FAB2(SCH_1):PAGE207',
 PACK_SIZE='0402',
 RATED='10V',
 ATTRIBUTE='1UF',
 TOLERANCE='10%',
 SEC_TYPE='SMD-BCG6',
 PHYS_PAGE='207',
 XY='(-5100,4125)',
 ROT='0',
 VER='1',
 VALUE='SC1U10V2KX-4-GP',
 PACK_TYPE='SMD-BCG6',
 PART_NUMBER='78.10523.8FL',
 LOCATION='C1E6',
 SEC='1',
 CDS_LIB='w_hdl',
 CDS_PART_NAME='SC1U10V2KX-4-GP_SMD-BCG6-SC1U1A',
 PRIM_FILE='C:/<user>/w_hdl/sc1u10v2kx#2d4#2dgp/chips/chips.prt';

PART_NAME
 C1E7 'CAP_0402-0.22UF,16V,10%,X7R,A3A':
 ROOM='PVCCIN_CPU1_PWR_VR';

SECTION_NUMBER 1
 '@BASEBOARD_FAB2_LIB.BASEBOARD_FAB2(SCH_1):PAGE207_I28@MSTR_DISCRETE.CAP(CHIPS)':
 C_PATH='@baseboard_fab2_lib.baseboard_fab2(sch_1):page207_i28@mstr_discrete.cap~
(chips)',
 P_PATH='@baseboard_fab2_lib.baseboard_fab2(sch_1):page207_i28@mstr_discrete.cap~
(chips)',
 PATH='I28',
 DRAWING='@BASEBOARD_FAB2_LIB.BASEBOARD_FAB2(SCH_1):PAGE207',
 TOLERANCE='10%',
 SEC_TYPE='0402',
 MATERIAL='X7R',
 PHYS_PAGE='207',
 XY='(-4725,4150)',
 ROT='0',
 VER='1',
 VALUE='0.22UF',
 PACK_TYPE='0402',
 PART_NUMBER='A36096-155',
 LOCATION='C1E7',
 ROOM='PVCCIN_CPU1_PWR_VR',
 SEC='1',
 CDS_LIB='mstr_discrete',
 CDS_PART_NAME='CAP_0402-0.22UF,16V,10%,X7R,A3A',
 VOLTAGE='16V',
 PRIM_FILE='./archive_libs/mstr_discrete/cap/chips/chips.prt';

PART_NAME
 C1E8 'CAP_0402-1.0UF,16V,10%,X6S,D97A':
 ROOM='PVCCIN_CPU1_PWR_VR';

SECTION_NUMBER 1
 '@BASEBOARD_FAB2_LIB.BASEBOARD_FAB2(SCH_1):PAGE207_I32@MSTR_DISCRETE.CAP(CHIPS)':
 C_PATH='@baseboard_fab2_lib.baseboard_fab2(sch_1):page207_i32@mstr_discrete.cap~
(chips)',
 P_PATH='@baseboard_fab2_lib.baseboard_fab2(sch_1):page207_i32@mstr_discrete.cap~
(chips)',
 PATH='I32',
 DRAWING='@BASEBOARD_FAB2_LIB.BASEBOARD_FAB2(SCH_1):PAGE207',
 TOLERANCE='10%',
 SEC_TYPE='0402',
 MATERIAL='X6S',
 PHYS_PAGE='207',
 XY='(-5550,4100)',
 ROT='0',
 VER='1',
 VALUE='1.0UF',
 PACK_TYPE='0402',
 PART_NUMBER='D97712-011',
 LOCATION='C1E8',
 ROOM='PVCCIN_CPU1_PWR_VR',
 SEC='1',
 CDS_LIB='mstr_discrete',
 CDS_PART_NAME='CAP_0402-1.0UF,16V,10%,X6S,D97A',
 VOLTAGE='16V',
 PRIM_FILE='./archive_libs/mstr_discrete/cap/chips/chips.prt';

PART_NAME
 C1E9 'CAP_A_0603V-22.0UF,4V,20%,X6S,A':
 GROUP='PWR_MLCC_CAP';

SECTION_NUMBER 1
 '@BASEBOARD_FAB2_LIB.BASEBOARD_FAB2(SCH_1):PAGE207_I58@DEV_DISCRETE.CAP_A(CHIPS)':
 C_PATH='@baseboard_fab2_lib.baseboard_fab2(sch_1):page207_i58@dev_discrete.cap_~
a(chips)',
 P_PATH='@baseboard_fab2_lib.baseboard_fab2(sch_1):page207_i58@dev_discrete.cap_~
a(chips)',
 PATH='I58',
 DRAWING='@BASEBOARD_FAB2_LIB.BASEBOARD_FAB2(SCH_1):PAGE207',
 TOLERANCE='20%',
 SEC_TYPE='0603V',
 MATERIAL='X6S',
 PHYS_PAGE='207',
 XY='(-650,3350)',
 ROT='0',
 VER='1',
 VALUE='22.0UF',
 PACK_TYPE='0603V',
 PART_NUMBER='E15431-004',
 LOCATION='C1E9',
 GROUP='PWR_MLCC_CAP',
 SEC='1',
 CDS_LIB='dev_discrete',
 CDS_PART_NAME='CAP_A_0603V-22.0UF,4V,20%,X6S,A',
 VOLTAGE='4V',
 PRIM_FILE='./archive_libs/discrete/cap_a/chips/chips.prt';

PART_NAME
 C1E11 'CAP_0402-0.220UF,16V,10%,X7R,AA':
 ROOM='PVCCIN_CPU1_PWR_VR',
 NO_XNET_CONNECTION='1';

SECTION_NUMBER 1
 '@BASEBOARD_FAB2_LIB.BASEBOARD_FAB2(SCH_1):PAGE207_I30@MSTR_DISCRETE.CAP(CHIPS)':
 C_PATH='@baseboard_fab2_lib.baseboard_fab2(sch_1):page207_i30@mstr_discrete.cap~
(chips)',
 P_PATH='@baseboard_fab2_lib.baseboard_fab2(sch_1):page207_i30@mstr_discrete.cap~
(chips)',
 PATH='I30',
 DRAWING='@BASEBOARD_FAB2_LIB.BASEBOARD_FAB2(SCH_1):PAGE207',
 SPOF='TRUE',
 TOLERANCE='10%',
 SEC_TYPE='0402',
 MATERIAL='X7R',
 NO_XNET_CONNECTION='1',
 PHYS_PAGE='207',
 XY='(-5675,3500)',
 ROT='2',
 VER='1',
 VALUE='0.220UF',
 PACK_TYPE='0402',
 PART_NUMBER='A36096-104',
 LOCATION='C1E11',
 ROOM='PVCCIN_CPU1_PWR_VR',
 SEC='1',
 CDS_LIB='mstr_discrete',
 CDS_PART_NAME='CAP_0402-0.220UF,16V,10%,X7R,AA',
 VOLTAGE='16V',
 PRIM_FILE='./archive_libs/mstr_discrete/cap/chips/chips.prt';

PART_NAME
 C1E12 'CAP_0805-10UF,16V,10%,X6S,C953A':
 ROOM='HOT_SWAP';

SECTION_NUMBER 1
 '@BASEBOARD_FAB2_LIB.BASEBOARD_FAB2(SCH_1):PAGE195_I32@MSTR_DISCRETE.CAP(CHIPS)':
 C_PATH='@baseboard_fab2_lib.baseboard_fab2(sch_1):page195_i32@mstr_discrete.cap~
(chips)',
 P_PATH='@baseboard_fab2_lib.baseboard_fab2(sch_1):page195_i32@mstr_discrete.cap~
(chips)',
 PATH='I32',
 DRAWING='@BASEBOARD_FAB2_LIB.BASEBOARD_FAB2(SCH_1):PAGE195',
 POP='NOPOP',
 TOLERANCE='10%',
 SEC_TYPE='0805',
 MATERIAL='X6S',
 PHYS_PAGE='195',
 XY='(-3375,3650)',
 ROT='0',
 VER='1',
 VALUE='10UF',
 PACK_TYPE='0805',
 PART_NUMBER='C95333-007',
 LOCATION='C1E12',
 ROOM='HOT_SWAP',
 SEC='1',
 CDS_LIB='mstr_discrete',
 CDS_PART_NAME='CAP_0805-10UF,16V,10%,X6S,C953A',
 VOLTAGE='16V',
 PRIM_FILE='./archive_libs/mstr_discrete/cap/chips/chips.prt';

PART_NAME
 C1E13 'CAP_0402-1.0UF,16V,10%,X6S,D97A':
 ROOM='PVCCIN_CPU1_PWR_VR';

SECTION_NUMBER 1
 '@BASEBOARD_FAB2_LIB.BASEBOARD_FAB2(SCH_1):PAGE207_I34@MSTR_DISCRETE.CAP(CHIPS)':
 C_PATH='@baseboard_fab2_lib.baseboard_fab2(sch_1):page207_i34@mstr_discrete.cap~
(chips)',
 P_PATH='@baseboard_fab2_lib.baseboard_fab2(sch_1):page207_i34@mstr_discrete.cap~
(chips)',
 PATH='I34',
 DRAWING='@BASEBOARD_FAB2_LIB.BASEBOARD_FAB2(SCH_1):PAGE207',
 TOLERANCE='10%',
 SEC_TYPE='0402',
 MATERIAL='X6S',
 PHYS_PAGE='207',
 XY='(-6150,4125)',
 ROT='0',
 VER='1',
 VALUE='1.0UF',
 PACK_TYPE='0402',
 PART_NUMBER='D97712-011',
 LOCATION='C1E13',
 ROOM='PVCCIN_CPU1_PWR_VR',
 SEC='1',
 CDS_LIB='mstr_discrete',
 CDS_PART_NAME='CAP_0402-1.0UF,16V,10%,X6S,D97A',
 VOLTAGE='16V',
 PRIM_FILE='./archive_libs/mstr_discrete/cap/chips/chips.prt';

PART_NAME
 C1E14 'CAP_A_0402V-0.1UF,16V,10%,X7R,A':
 ROOM='PVCCIN_CPU1_PWR_VR';

SECTION_NUMBER 1
 '@BASEBOARD_FAB2_LIB.BASEBOARD_FAB2(SCH_1):PAGE207_I33@DEV_DISCRETE.CAP_A(CHIPS)':
 C_PATH='@baseboard_fab2_lib.baseboard_fab2(sch_1):page207_i33@dev_discrete.cap_~
a(chips)',
 P_PATH='@baseboard_fab2_lib.baseboard_fab2(sch_1):page207_i33@dev_discrete.cap_~
a(chips)',
 PATH='I33',
 DRAWING='@BASEBOARD_FAB2_LIB.BASEBOARD_FAB2(SCH_1):PAGE207',
 TOLERANCE='10%',
 SEC_TYPE='0402V',
 MATERIAL='X7R',
 PHYS_PAGE='207',
 XY='(-5850,4125)',
 ROT='0',
 VER='1',
 VALUE='0.1UF',
 PACK_TYPE='0402V',
 PART_NUMBER='A36096-030',
 LOCATION='C1E14',
 ROOM='PVCCIN_CPU1_PWR_VR',
 SEC='1',
 CDS_LIB='dev_discrete',
 CDS_PART_NAME='CAP_A_0402V-0.1UF,16V,10%,X7R,A',
 VOLTAGE='16V',
 PRIM_FILE='./archive_libs/discrete/cap_a/chips/chips.prt';

PART_NAME
 C1E15 'CAP_0805-10UF,16V,10%,X6S,C953A':
 ROOM='HOT_SWAP';

SECTION_NUMBER 1
 '@BASEBOARD_FAB2_LIB.BASEBOARD_FAB2(SCH_1):PAGE195_I35@MSTR_DISCRETE.CAP(CHIPS)':
 C_PATH='@baseboard_fab2_lib.baseboard_fab2(sch_1):page195_i35@mstr_discrete.cap~
(chips)',
 P_PATH='@baseboard_fab2_lib.baseboard_fab2(sch_1):page195_i35@mstr_discrete.cap~
(chips)',
 PATH='I35',
 DRAWING='@BASEBOARD_FAB2_LIB.BASEBOARD_FAB2(SCH_1):PAGE195',
 POP='NOPOP',
 TOLERANCE='10%',
 SEC_TYPE='0805',
 MATERIAL='X6S',
 PHYS_PAGE='195',
 XY='(-3025,3650)',
 ROT='0',
 VER='1',
 VALUE='10UF',
 PACK_TYPE='0805',
 PART_NUMBER='C95333-007',
 LOCATION='C1E15',
 ROOM='HOT_SWAP',
 SEC='1',
 CDS_LIB='mstr_discrete',
 CDS_PART_NAME='CAP_0805-10UF,16V,10%,X6S,C953A',
 VOLTAGE='16V',
 PRIM_FILE='./archive_libs/mstr_discrete/cap/chips/chips.prt';

PART_NAME
 C1E16 'CAP_A_0402V-0.1UF,16V,10%,X7R,A':
 ROOM='HOT_SWAP';

SECTION_NUMBER 1
 '@BASEBOARD_FAB2_LIB.BASEBOARD_FAB2(SCH_1):PAGE195_I39@DEV_DISCRETE.CAP_A(CHIPS)':
 C_PATH='@baseboard_fab2_lib.baseboard_fab2(sch_1):page195_i39@dev_discrete.cap_~
a(chips)',
 P_PATH='@baseboard_fab2_lib.baseboard_fab2(sch_1):page195_i39@dev_discrete.cap_~
a(chips)',
 PATH='I39',
 DRAWING='@BASEBOARD_FAB2_LIB.BASEBOARD_FAB2(SCH_1):PAGE195',
 POP='NOPOP',
 TOLERANCE='10%',
 SEC_TYPE='0402V',
 MATERIAL='X7R',
 BOM_COST='HOT_SWAP',
 PHYS_PAGE='195',
 XY='(-1625,3650)',
 ROT='0',
 VER='1',
 VALUE='0.1UF',
 PACK_TYPE='0402V',
 PART_NUMBER='A36096-030',
 LOCATION='C1E16',
 ROOM='HOT_SWAP',
 SEC='1',
 CDS_LIB='dev_discrete',
 CDS_PART_NAME='CAP_A_0402V-0.1UF,16V,10%,X7R,A',
 VOLTAGE='16V',
 PRIM_FILE='./archive_libs/discrete/cap_a/chips/chips.prt';

PART_NAME
 C1E17 'CAP_A_0402V-0.1UF,16V,10%,X7R,A':
 ROOM='HOT_SWAP';

SECTION_NUMBER 1
 '@BASEBOARD_FAB2_LIB.BASEBOARD_FAB2(SCH_1):PAGE195_I38@DEV_DISCRETE.CAP_A(CHIPS)':
 C_PATH='@baseboard_fab2_lib.baseboard_fab2(sch_1):page195_i38@dev_discrete.cap_~
a(chips)',
 P_PATH='@baseboard_fab2_lib.baseboard_fab2(sch_1):page195_i38@dev_discrete.cap_~
a(chips)',
 PATH='I38',
 DRAWING='@BASEBOARD_FAB2_LIB.BASEBOARD_FAB2(SCH_1):PAGE195',
 POP='NOPOP',
 TOLERANCE='10%',
 SEC_TYPE='0402V',
 MATERIAL='X7R',
 BOM_COST='HOT_SWAP',
 PHYS_PAGE='195',
 XY='(-1950,3650)',
 ROT='0',
 VER='1',
 VALUE='0.1UF',
 PACK_TYPE='0402V',
 PART_NUMBER='A36096-030',
 LOCATION='C1E17',
 ROOM='HOT_SWAP',
 SEC='1',
 CDS_LIB='dev_discrete',
 CDS_PART_NAME='CAP_A_0402V-0.1UF,16V,10%,X7R,A',
 VOLTAGE='16V',
 PRIM_FILE='./archive_libs/discrete/cap_a/chips/chips.prt';

PART_NAME
 C1E18 'CAPP_2626-270UF,16V,20%,OSCON,A':
 ROOM='PVCCIN_CPU1_FILTER_VR';

SECTION_NUMBER 1
 '@BASEBOARD_FAB2_LIB.BASEBOARD_FAB2(SCH_1):PAGE209_I37@MSTR_DISCRETE.CAPP(CHIPS)':
 C_PATH='@baseboard_fab2_lib.baseboard_fab2(sch_1):page209_i37@mstr_discrete.cap~
p(chips)',
 P_PATH='@baseboard_fab2_lib.baseboard_fab2(sch_1):page209_i37@mstr_discrete.cap~
p(chips)',
 PATH='I37',
 DRAWING='@BASEBOARD_FAB2_LIB.BASEBOARD_FAB2(SCH_1):PAGE209',
 TOLERANCE='20%',
 SEC_TYPE='2626',
 MATERIAL='OSCON',
 PHYS_PAGE='209',
 XY='(-950,2050)',
 ROT='0',
 VER='1',
 VALUE='270UF',
 PACK_TYPE='2626',
 PART_NUMBER='A31228-047',
 LOCATION='C1E18',
 ROOM='PVCCIN_CPU1_FILTER_VR',
 SEC='1',
 CDS_LIB='mstr_discrete',
 CDS_PART_NAME='CAPP_2626-270UF,16V,20%,OSCON,A',
 VOLTAGE='16V',
 PRIM_FILE='./archive_libs/mstr_discrete/capp/chips/chips.prt';

PART_NAME
 C1E19 'CAP_0402LF-47.0PF,50V,5%,EMPTYA':
 ROOM='TEMP_SENSORS';

SECTION_NUMBER 1
 '@BASEBOARD_FAB2_LIB.BASEBOARD_FAB2(SCH_1):PAGE167_I24@MSTR_DISCRETE.CAP(CHIPS)':
 C_PATH='@baseboard_fab2_lib.baseboard_fab2(sch_1):page167_i24@mstr_discrete.cap~
(chips)',
 P_PATH='@baseboard_fab2_lib.baseboard_fab2(sch_1):page167_i24@mstr_discrete.cap~
(chips)',
 PATH='I24',
 DRAWING='@BASEBOARD_FAB2_LIB.BASEBOARD_FAB2(SCH_1):PAGE167',
 TOLERANCE='5%',
 SEC_TYPE='0402LF',
 MATERIAL='EMPTY',
 BOM_COST='SM_THERM',
 PHYS_PAGE='167',
 XY='(-4675,3175)',
 ROT='0',
 VER='1',
 VALUE='47.0PF',
 PACK_TYPE='0402LF',
 PART_NUMBER='A36095-025',
 LOCATION='C1E19',
 ROOM='TEMP_SENSORS',
 SEC='1',
 CDS_LIB='mstr_discrete',
 CDS_PART_NAME='CAP_0402LF-47.0PF,50V,5%,EMPTYA',
 VOLTAGE='50V',
 PRIM_FILE='./archive_libs/mstr_discrete/cap/chips/chips.prt';

PART_NAME
 C1E20 'CAP_A_0402V-0.1UF,16V,10%,X7R,A':
 ROOM='CPU_FANS';

SECTION_NUMBER 1
 '@BASEBOARD_FAB2_LIB.BASEBOARD_FAB2(SCH_1):PAGE161_I4@DEV_DISCRETE.CAP_A(CHIPS)':
 C_PATH='@baseboard_fab2_lib.baseboard_fab2(sch_1):page161_i4@dev_discrete.cap_a~
(chips)',
 P_PATH='@baseboard_fab2_lib.baseboard_fab2(sch_1):page161_i4@dev_discrete.cap_a~
(chips)',
 PATH='I4',
 DRAWING='@BASEBOARD_FAB2_LIB.BASEBOARD_FAB2(SCH_1):PAGE161',
 TOLERANCE='10%',
 SEC_TYPE='0402V',
 MATERIAL='X7R',
 BOM_COST='SM_THERM',
 PHYS_PAGE='161',
 XY='(-1125,4325)',
 ROT='0',
 VER='1',
 VALUE='0.1UF',
 PACK_TYPE='0402V',
 PART_NUMBER='A36096-030',
 LOCATION='C1E20',
 ROOM='CPU_FANS',
 SEC='1',
 CDS_LIB='dev_discrete',
 CDS_PART_NAME='CAP_A_0402V-0.1UF,16V,10%,X7R,A',
 VOLTAGE='16V',
 PRIM_FILE='./archive_libs/discrete/cap_a/chips/chips.prt';

PART_NAME
 C1E21 'CAP_0805-10UF,16V,10%,X6S,C953A':
 ROOM='CPU_FANS';

SECTION_NUMBER 1
 '@BASEBOARD_FAB2_LIB.BASEBOARD_FAB2(SCH_1):PAGE161_I3@MSTR_DISCRETE.CAP(CHIPS)':
 C_PATH='@baseboard_fab2_lib.baseboard_fab2(sch_1):page161_i3@mstr_discrete.cap(~
chips)',
 P_PATH='@baseboard_fab2_lib.baseboard_fab2(sch_1):page161_i3@mstr_discrete.cap(~
chips)',
 PATH='I3',
 DRAWING='@BASEBOARD_FAB2_LIB.BASEBOARD_FAB2(SCH_1):PAGE161',
 TOLERANCE='10%',
 SEC_TYPE='0805',
 MATERIAL='X6S',
 BOM_COST='SM_THERM',
 PHYS_PAGE='161',
 XY='(-1400,4350)',
 ROT='0',
 VER='1',
 VALUE='10UF',
 PACK_TYPE='0805',
 PART_NUMBER='C95333-007',
 LOCATION='C1E21',
 ROOM='CPU_FANS',
 SEC='1',
 CDS_LIB='mstr_discrete',
 CDS_PART_NAME='CAP_0805-10UF,16V,10%,X6S,C953A',
 VOLTAGE='16V',
 PRIM_FILE='./archive_libs/mstr_discrete/cap/chips/chips.prt';

PART_NAME
 C1E22 'CAP_A_0402V-0.1UF,16V,10%,X7R,A':
 ROOM='CPUFANS';

SECTION_NUMBER 1
 '@BASEBOARD_FAB2_LIB.BASEBOARD_FAB2(SCH_1):PAGE161_I113@DEV_DISCRETE.CAP_A(CHIPS)':
 C_PATH='@baseboard_fab2_lib.baseboard_fab2(sch_1):page161_i113@dev_discrete.cap~
_a(chips)',
 P_PATH='@baseboard_fab2_lib.baseboard_fab2(sch_1):page161_i113@dev_discrete.cap~
_a(chips)',
 PATH='I113',
 DRAWING='@BASEBOARD_FAB2_LIB.BASEBOARD_FAB2(SCH_1):PAGE161',
 TOLERANCE='10%',
 SEC_TYPE='0402V',
 MATERIAL='X7R',
 BOM_COST='SM_THERM',
 PHYS_PAGE='161',
 XY='(-5775,2150)',
 ROT='0',
 VER='1',
 VALUE='0.1UF',
 PACK_TYPE='0402V',
 PART_NUMBER='A36096-030',
 LOCATION='C1E22',
 ROOM='CPUFANS',
 SEC='1',
 CDS_LIB='dev_discrete',
 CDS_PART_NAME='CAP_A_0402V-0.1UF,16V,10%,X7R,A',
 VOLTAGE='16V',
 PRIM_FILE='./archive_libs/discrete/cap_a/chips/chips.prt';

PART_NAME
 C1E23 'SC1U10V2KX-4-GP_SMD-BCG6-SC1U1A':;

SECTION_NUMBER 1
 '@BASEBOARD_FAB2_LIB.BASEBOARD_FAB2(SCH_1):PAGE207_I109@W_HDL.SC1U10V2KX-4-GP(CHIPS)':
 C_PATH='@baseboard_fab2_lib.baseboard_fab2(sch_1):page207_i109@w_hdl.\sc1u10v2k~
x-4-gp\(chips)',
 P_PATH='@baseboard_fab2_lib.baseboard_fab2(sch_1):page207_i109@w_hdl.\sc1u10v2k~
x-4-gp\(chips)',
 PATH='I109',
 DRAWING='@BASEBOARD_FAB2_LIB.BASEBOARD_FAB2(SCH_1):PAGE207',
 PACK_SIZE='0402',
 RATED='10V',
 ATTRIBUTE='1UF',
 TOLERANCE='10%',
 SEC_TYPE='SMD-BCG6',
 PHYS_PAGE='207',
 XY='(-5000,1575)',
 ROT='0',
 VER='1',
 VALUE='SC1U10V2KX-4-GP',
 PACK_TYPE='SMD-BCG6',
 PART_NUMBER='78.10523.8FL',
 LOCATION='C1E23',
 SEC='1',
 CDS_LIB='w_hdl',
 CDS_PART_NAME='SC1U10V2KX-4-GP_SMD-BCG6-SC1U1A',
 PRIM_FILE='C:/<user>/w_hdl/sc1u10v2kx#2d4#2dgp/chips/chips.prt';

PART_NAME
 C1E24 'CAP_0402-1.0UF,16V,10%,X6S,D97A':
 ROOM='PVCCIN_CPU1_PWR_VR';

SECTION_NUMBER 1
 '@BASEBOARD_FAB2_LIB.BASEBOARD_FAB2(SCH_1):PAGE207_I40@MSTR_DISCRETE.CAP(CHIPS)':
 C_PATH='@baseboard_fab2_lib.baseboard_fab2(sch_1):page207_i40@mstr_discrete.cap~
(chips)',
 P_PATH='@baseboard_fab2_lib.baseboard_fab2(sch_1):page207_i40@mstr_discrete.cap~
(chips)',
 PATH='I40',
 DRAWING='@BASEBOARD_FAB2_LIB.BASEBOARD_FAB2(SCH_1):PAGE207',
 TOLERANCE='10%',
 SEC_TYPE='0402',
 MATERIAL='X6S',
 PHYS_PAGE='207',
 XY='(-5450,1525)',
 ROT='0',
 VER='1',
 VALUE='1.0UF',
 PACK_TYPE='0402',
 PART_NUMBER='D97712-011',
 LOCATION='C1E24',
 ROOM='PVCCIN_CPU1_PWR_VR',
 SEC='1',
 CDS_LIB='mstr_discrete',
 CDS_PART_NAME='CAP_0402-1.0UF,16V,10%,X6S,D97A',
 VOLTAGE='16V',
 PRIM_FILE='./archive_libs/mstr_discrete/cap/chips/chips.prt';

PART_NAME
 C1E25 'CAP_0402-0.22UF,16V,10%,X7R,A3A':
 ROOM='PVCCIN_CPU1_PWR_VR';

SECTION_NUMBER 1
 '@BASEBOARD_FAB2_LIB.BASEBOARD_FAB2(SCH_1):PAGE207_I36@MSTR_DISCRETE.CAP(CHIPS)':
 C_PATH='@baseboard_fab2_lib.baseboard_fab2(sch_1):page207_i36@mstr_discrete.cap~
(chips)',
 P_PATH='@baseboard_fab2_lib.baseboard_fab2(sch_1):page207_i36@mstr_discrete.cap~
(chips)',
 PATH='I36',
 DRAWING='@BASEBOARD_FAB2_LIB.BASEBOARD_FAB2(SCH_1):PAGE207',
 TOLERANCE='10%',
 SEC_TYPE='0402',
 MATERIAL='X7R',
 PHYS_PAGE='207',
 XY='(-4600,1575)',
 ROT='0',
 VER='1',
 VALUE='0.22UF',
 PACK_TYPE='0402',
 PART_NUMBER='A36096-155',
 LOCATION='C1E25',
 ROOM='PVCCIN_CPU1_PWR_VR',
 SEC='1',
 CDS_LIB='mstr_discrete',
 CDS_PART_NAME='CAP_0402-0.22UF,16V,10%,X7R,A3A',
 VOLTAGE='16V',
 PRIM_FILE='./archive_libs/mstr_discrete/cap/chips/chips.prt';

PART_NAME
 C1F2 'CAP_0402-0.22UF,16V,10%,X7R,A3A':
 ROOM='IO_SLOT';

SECTION_NUMBER 1
 '@BASEBOARD_FAB2_LIB.BASEBOARD_FAB2(SCH_1):PAGE181_I90@MSTR_DISCRETE.CAP(CHIPS)':
 C_PATH='@baseboard_fab2_lib.baseboard_fab2(sch_1):page181_i90@mstr_discrete.cap~
(chips)',
 P_PATH='@baseboard_fab2_lib.baseboard_fab2(sch_1):page181_i90@mstr_discrete.cap~
(chips)',
 PATH='I90',
 DRAWING='@BASEBOARD_FAB2_LIB.BASEBOARD_FAB2(SCH_1):PAGE181',
 TOLERANCE='10%',
 SEC_TYPE='0402',
 MATERIAL='X7R',
 BOM_COST='IO_SLOT',
 PHYS_PAGE='181',
 XY='(2250,3650)',
 ROT='0',
 VER='2',
 VALUE='0.22UF',
 PACK_TYPE='0402',
 PART_NUMBER='A36096-155',
 LOCATION='C1F2',
 ROOM='IO_SLOT',
 SEC='1',
 CDS_LIB='mstr_discrete',
 CDS_PART_NAME='CAP_0402-0.22UF,16V,10%,X7R,A3A',
 VOLTAGE='16V',
 PRIM_FILE='./archive_libs/mstr_discrete/cap/chips/chips.prt';

PART_NAME
 C1F3 'CAP_0402-0.22UF,16V,10%,X7R,A3A':
 ROOM='IO_SLOT';

SECTION_NUMBER 1
 '@BASEBOARD_FAB2_LIB.BASEBOARD_FAB2(SCH_1):PAGE181_I76@MSTR_DISCRETE.CAP(CHIPS)':
 C_PATH='@baseboard_fab2_lib.baseboard_fab2(sch_1):page181_i76@mstr_discrete.cap~
(chips)',
 P_PATH='@baseboard_fab2_lib.baseboard_fab2(sch_1):page181_i76@mstr_discrete.cap~
(chips)',
 PATH='I76',
 DRAWING='@BASEBOARD_FAB2_LIB.BASEBOARD_FAB2(SCH_1):PAGE181',
 TOLERANCE='10%',
 SEC_TYPE='0402',
 MATERIAL='X7R',
 BOM_COST='IO_SLOT',
 PHYS_PAGE='181',
 XY='(1825,3600)',
 ROT='0',
 VER='2',
 VALUE='0.22UF',
 PACK_TYPE='0402',
 PART_NUMBER='A36096-155',
 LOCATION='C1F3',
 ROOM='IO_SLOT',
 SEC='1',
 CDS_LIB='mstr_discrete',
 CDS_PART_NAME='CAP_0402-0.22UF,16V,10%,X7R,A3A',
 VOLTAGE='16V',
 PRIM_FILE='./archive_libs/mstr_discrete/cap/chips/chips.prt';

PART_NAME
 C1F4 'CAP_0402-0.22UF,16V,10%,X7R,A3A':
 ROOM='IO_SLOT';

SECTION_NUMBER 1
 '@BASEBOARD_FAB2_LIB.BASEBOARD_FAB2(SCH_1):PAGE181_I91@MSTR_DISCRETE.CAP(CHIPS)':
 C_PATH='@baseboard_fab2_lib.baseboard_fab2(sch_1):page181_i91@mstr_discrete.cap~
(chips)',
 P_PATH='@baseboard_fab2_lib.baseboard_fab2(sch_1):page181_i91@mstr_discrete.cap~
(chips)',
 PATH='I91',
 DRAWING='@BASEBOARD_FAB2_LIB.BASEBOARD_FAB2(SCH_1):PAGE181',
 TOLERANCE='10%',
 SEC_TYPE='0402',
 MATERIAL='X7R',
 BOM_COST='IO_SLOT',
 PHYS_PAGE='181',
 XY='(2250,3800)',
 ROT='0',
 VER='2',
 VALUE='0.22UF',
 PACK_TYPE='0402',
 PART_NUMBER='A36096-155',
 LOCATION='C1F4',
 ROOM='IO_SLOT',
 SEC='1',
 CDS_LIB='mstr_discrete',
 CDS_PART_NAME='CAP_0402-0.22UF,16V,10%,X7R,A3A',
 VOLTAGE='16V',
 PRIM_FILE='./archive_libs/mstr_discrete/cap/chips/chips.prt';

PART_NAME
 C1F5 'CAP_0402-0.22UF,16V,10%,X7R,A3A':
 ROOM='IO_SLOT';

SECTION_NUMBER 1
 '@BASEBOARD_FAB2_LIB.BASEBOARD_FAB2(SCH_1):PAGE181_I77@MSTR_DISCRETE.CAP(CHIPS)':
 C_PATH='@baseboard_fab2_lib.baseboard_fab2(sch_1):page181_i77@mstr_discrete.cap~
(chips)',
 P_PATH='@baseboard_fab2_lib.baseboard_fab2(sch_1):page181_i77@mstr_discrete.cap~
(chips)',
 PATH='I77',
 DRAWING='@BASEBOARD_FAB2_LIB.BASEBOARD_FAB2(SCH_1):PAGE181',
 TOLERANCE='10%',
 SEC_TYPE='0402',
 MATERIAL='X7R',
 BOM_COST='IO_SLOT',
 PHYS_PAGE='181',
 XY='(1825,3750)',
 ROT='0',
 VER='2',
 VALUE='0.22UF',
 PACK_TYPE='0402',
 PART_NUMBER='A36096-155',
 LOCATION='C1F5',
 ROOM='IO_SLOT',
 SEC='1',
 CDS_LIB='mstr_discrete',
 CDS_PART_NAME='CAP_0402-0.22UF,16V,10%,X7R,A3A',
 VOLTAGE='16V',
 PRIM_FILE='./archive_libs/mstr_discrete/cap/chips/chips.prt';

PART_NAME
 C1F6 'CAP_0402-0.22UF,16V,10%,X7R,A3A':
 ROOM='IO_SLOT';

SECTION_NUMBER 1
 '@BASEBOARD_FAB2_LIB.BASEBOARD_FAB2(SCH_1):PAGE181_I88@MSTR_DISCRETE.CAP(CHIPS)':
 C_PATH='@baseboard_fab2_lib.baseboard_fab2(sch_1):page181_i88@mstr_discrete.cap~
(chips)',
 P_PATH='@baseboard_fab2_lib.baseboard_fab2(sch_1):page181_i88@mstr_discrete.cap~
(chips)',
 PATH='I88',
 DRAWING='@BASEBOARD_FAB2_LIB.BASEBOARD_FAB2(SCH_1):PAGE181',
 TOLERANCE='10%',
 SEC_TYPE='0402',
 MATERIAL='X7R',
 BOM_COST='IO_SLOT',
 PHYS_PAGE='181',
 XY='(2275,3150)',
 ROT='0',
 VER='2',
 VALUE='0.22UF',
 PACK_TYPE='0402',
 PART_NUMBER='A36096-155',
 LOCATION='C1F6',
 ROOM='IO_SLOT',
 SEC='1',
 CDS_LIB='mstr_discrete',
 CDS_PART_NAME='CAP_0402-0.22UF,16V,10%,X7R,A3A',
 VOLTAGE='16V',
 PRIM_FILE='./archive_libs/mstr_discrete/cap/chips/chips.prt';

PART_NAME
 C1F7 'CAPP_4040LF-470UF,16V,20%,ALUMA':;

SECTION_NUMBER 1
 '@BASEBOARD_FAB2_LIB.BASEBOARD_FAB2(SCH_1):PAGE195_I85@MSTR_DISCRETE.CAPP(CHIPS)':
 C_PATH='@baseboard_fab2_lib.baseboard_fab2(sch_1):page195_i85@mstr_discrete.cap~
p(chips)',
 P_PATH='@baseboard_fab2_lib.baseboard_fab2(sch_1):page195_i85@mstr_discrete.cap~
p(chips)',
 PATH='I85',
 DRAWING='@BASEBOARD_FAB2_LIB.BASEBOARD_FAB2(SCH_1):PAGE195',
 TOLERANCE='20%',
 MATERIAL='ALUM',
 PHYS_PAGE='195',
 XY='(-5650,2900)',
 ROT='0',
 VER='1',
 VALUE='470UF',
 PACK_TYPE='4040LF',
 PART_NUMBER='A93539-036',
 LOCATION='C1F7',
 CDS_LIB='mstr_discrete',
 CDS_PART_NAME='CAPP_4040LF-470UF,16V,20%,ALUMA',
 VOLTAGE='16V',
 PRIM_FILE='./archive_libs/mstr_discrete/capp/chips/chips.prt';

PART_NAME
 C1F8 'CAP_0402-0.22UF,16V,10%,X7R,A3A':
 ROOM='IO_SLOT';

SECTION_NUMBER 1
 '@BASEBOARD_FAB2_LIB.BASEBOARD_FAB2(SCH_1):PAGE181_I73@MSTR_DISCRETE.CAP(CHIPS)':
 C_PATH='@baseboard_fab2_lib.baseboard_fab2(sch_1):page181_i73@mstr_discrete.cap~
(chips)',
 P_PATH='@baseboard_fab2_lib.baseboard_fab2(sch_1):page181_i73@mstr_discrete.cap~
(chips)',
 PATH='I73',
 DRAWING='@BASEBOARD_FAB2_LIB.BASEBOARD_FAB2(SCH_1):PAGE181',
 TOLERANCE='10%',
 SEC_TYPE='0402',
 MATERIAL='X7R',
 BOM_COST='IO_SLOT',
 PHYS_PAGE='181',
 XY='(1825,3100)',
 ROT='0',
 VER='2',
 VALUE='0.22UF',
 PACK_TYPE='0402',
 PART_NUMBER='A36096-155',
 LOCATION='C1F8',
 ROOM='IO_SLOT',
 SEC='1',
 CDS_LIB='mstr_discrete',
 CDS_PART_NAME='CAP_0402-0.22UF,16V,10%,X7R,A3A',
 VOLTAGE='16V',
 PRIM_FILE='./archive_libs/mstr_discrete/cap/chips/chips.prt';

PART_NAME
 C1F9 'CAP_A_0402V-0.01UF,25V,10%,X7RA':
 ROOM='CPU_FANS';

SECTION_NUMBER 1
 '@BASEBOARD_FAB2_LIB.BASEBOARD_FAB2(SCH_1):PAGE161_I46@DEV_DISCRETE.CAP_A(CHIPS)':
 C_PATH='@baseboard_fab2_lib.baseboard_fab2(sch_1):page161_i46@dev_discrete.cap_~
a(chips)',
 P_PATH='@baseboard_fab2_lib.baseboard_fab2(sch_1):page161_i46@dev_discrete.cap_~
a(chips)',
 PATH='I46',
 DRAWING='@BASEBOARD_FAB2_LIB.BASEBOARD_FAB2(SCH_1):PAGE161',
 TOLERANCE='10%',
 SEC_TYPE='0402V',
 MATERIAL='X7R',
 BOM_COST='SM_THERM',
 PHYS_PAGE='161',
 XY='(-2775,3625)',
 ROT='2',
 VER='1',
 VALUE='0.01UF',
 PACK_TYPE='0402V',
 PART_NUMBER='A36096-045',
 LOCATION='C1F9',
 ROOM='CPU_FANS',
 SEC='1',
 CDS_LIB='dev_discrete',
 CDS_PART_NAME='CAP_A_0402V-0.01UF,25V,10%,X7RA',
 VOLTAGE='25V',
 PRIM_FILE='./archive_libs/discrete/cap_a/chips/chips.prt';

PART_NAME
 C1F10 'CAP_0402-0.22UF,16V,10%,X7R,A3A':
 ROOM='IO_SLOT';

SECTION_NUMBER 1
 '@BASEBOARD_FAB2_LIB.BASEBOARD_FAB2(SCH_1):PAGE181_I87@MSTR_DISCRETE.CAP(CHIPS)':
 C_PATH='@baseboard_fab2_lib.baseboard_fab2(sch_1):page181_i87@mstr_discrete.cap~
(chips)',
 P_PATH='@baseboard_fab2_lib.baseboard_fab2(sch_1):page181_i87@mstr_discrete.cap~
(chips)',
 PATH='I87',
 DRAWING='@BASEBOARD_FAB2_LIB.BASEBOARD_FAB2(SCH_1):PAGE181',
 TOLERANCE='10%',
 SEC_TYPE='0402',
 MATERIAL='X7R',
 BOM_COST='IO_SLOT',
 PHYS_PAGE='181',
 XY='(2275,3300)',
 ROT='0',
 VER='2',
 VALUE='0.22UF',
 PACK_TYPE='0402',
 PART_NUMBER='A36096-155',
 LOCATION='C1F10',
 ROOM='IO_SLOT',
 SEC='1',
 CDS_LIB='mstr_discrete',
 CDS_PART_NAME='CAP_0402-0.22UF,16V,10%,X7R,A3A',
 VOLTAGE='16V',
 PRIM_FILE='./archive_libs/mstr_discrete/cap/chips/chips.prt';

PART_NAME
 C1F11 'CAP_0402-0.22UF,16V,10%,X7R,A3A':
 ROOM='IO_SLOT';

SECTION_NUMBER 1
 '@BASEBOARD_FAB2_LIB.BASEBOARD_FAB2(SCH_1):PAGE181_I74@MSTR_DISCRETE.CAP(CHIPS)':
 C_PATH='@baseboard_fab2_lib.baseboard_fab2(sch_1):page181_i74@mstr_discrete.cap~
(chips)',
 P_PATH='@baseboard_fab2_lib.baseboard_fab2(sch_1):page181_i74@mstr_discrete.cap~
(chips)',
 PATH='I74',
 DRAWING='@BASEBOARD_FAB2_LIB.BASEBOARD_FAB2(SCH_1):PAGE181',
 TOLERANCE='10%',
 SEC_TYPE='0402',
 MATERIAL='X7R',
 BOM_COST='IO_SLOT',
 PHYS_PAGE='181',
 XY='(1825,3250)',
 ROT='0',
 VER='2',
 VALUE='0.22UF',
 PACK_TYPE='0402',
 PART_NUMBER='A36096-155',
 LOCATION='C1F11',
 ROOM='IO_SLOT',
 SEC='1',
 CDS_LIB='mstr_discrete',
 CDS_PART_NAME='CAP_0402-0.22UF,16V,10%,X7R,A3A',
 VOLTAGE='16V',
 PRIM_FILE='./archive_libs/mstr_discrete/cap/chips/chips.prt';

PART_NAME
 C1F12 'CAP_0402-0.22UF,16V,10%,X7R,A3A':
 ROOM='IO_SLOT';

SECTION_NUMBER 1
 '@BASEBOARD_FAB2_LIB.BASEBOARD_FAB2(SCH_1):PAGE181_I75@MSTR_DISCRETE.CAP(CHIPS)':
 C_PATH='@baseboard_fab2_lib.baseboard_fab2(sch_1):page181_i75@mstr_discrete.cap~
(chips)',
 P_PATH='@baseboard_fab2_lib.baseboard_fab2(sch_1):page181_i75@mstr_discrete.cap~
(chips)',
 PATH='I75',
 DRAWING='@BASEBOARD_FAB2_LIB.BASEBOARD_FAB2(SCH_1):PAGE181',
 TOLERANCE='10%',
 SEC_TYPE='0402',
 MATERIAL='X7R',
 BOM_COST='IO_SLOT',
 PHYS_PAGE='181',
 XY='(1825,3400)',
 ROT='0',
 VER='2',
 VALUE='0.22UF',
 PACK_TYPE='0402',
 PART_NUMBER='A36096-155',
 LOCATION='C1F12',
 ROOM='IO_SLOT',
 SEC='1',
 CDS_LIB='mstr_discrete',
 CDS_PART_NAME='CAP_0402-0.22UF,16V,10%,X7R,A3A',
 VOLTAGE='16V',
 PRIM_FILE='./archive_libs/mstr_discrete/cap/chips/chips.prt';

PART_NAME
 C1F13 'CAP_0402-0.22UF,16V,10%,X7R,A3A':
 ROOM='IO_SLOT';

SECTION_NUMBER 1
 '@BASEBOARD_FAB2_LIB.BASEBOARD_FAB2(SCH_1):PAGE181_I89@MSTR_DISCRETE.CAP(CHIPS)':
 C_PATH='@baseboard_fab2_lib.baseboard_fab2(sch_1):page181_i89@mstr_discrete.cap~
(chips)',
 P_PATH='@baseboard_fab2_lib.baseboard_fab2(sch_1):page181_i89@mstr_discrete.cap~
(chips)',
 PATH='I89',
 DRAWING='@BASEBOARD_FAB2_LIB.BASEBOARD_FAB2(SCH_1):PAGE181',
 TOLERANCE='10%',
 SEC_TYPE='0402',
 MATERIAL='X7R',
 BOM_COST='IO_SLOT',
 PHYS_PAGE='181',
 XY='(2250,3450)',
 ROT='0',
 VER='2',
 VALUE='0.22UF',
 PACK_TYPE='0402',
 PART_NUMBER='A36096-155',
 LOCATION='C1F13',
 ROOM='IO_SLOT',
 SEC='1',
 CDS_LIB='mstr_discrete',
 CDS_PART_NAME='CAP_0402-0.22UF,16V,10%,X7R,A3A',
 VOLTAGE='16V',
 PRIM_FILE='./archive_libs/mstr_discrete/cap/chips/chips.prt';

PART_NAME
 C1F14 'CAP_0402-0.22UF,16V,10%,X7R,A3A':
 ROOM='IO_SLOT';

SECTION_NUMBER 1
 '@BASEBOARD_FAB2_LIB.BASEBOARD_FAB2(SCH_1):PAGE181_I70@MSTR_DISCRETE.CAP(CHIPS)':
 C_PATH='@baseboard_fab2_lib.baseboard_fab2(sch_1):page181_i70@mstr_discrete.cap~
(chips)',
 P_PATH='@baseboard_fab2_lib.baseboard_fab2(sch_1):page181_i70@mstr_discrete.cap~
(chips)',
 PATH='I70',
 DRAWING='@BASEBOARD_FAB2_LIB.BASEBOARD_FAB2(SCH_1):PAGE181',
 TOLERANCE='10%',
 SEC_TYPE='0402',
 MATERIAL='X7R',
 BOM_COST='IO_SLOT',
 PHYS_PAGE='181',
 XY='(1775,2550)',
 ROT='0',
 VER='2',
 VALUE='0.22UF',
 PACK_TYPE='0402',
 PART_NUMBER='A36096-155',
 LOCATION='C1F14',
 ROOM='IO_SLOT',
 SEC='1',
 CDS_LIB='mstr_discrete',
 CDS_PART_NAME='CAP_0402-0.22UF,16V,10%,X7R,A3A',
 VOLTAGE='16V',
 PRIM_FILE='./archive_libs/mstr_discrete/cap/chips/chips.prt';

PART_NAME
 C1F15 'CAP_0402-0.22UF,16V,10%,X7R,A3A':
 ROOM='IO_SLOT';

SECTION_NUMBER 1
 '@BASEBOARD_FAB2_LIB.BASEBOARD_FAB2(SCH_1):PAGE181_I78@MSTR_DISCRETE.CAP(CHIPS)':
 C_PATH='@baseboard_fab2_lib.baseboard_fab2(sch_1):page181_i78@mstr_discrete.cap~
(chips)',
 P_PATH='@baseboard_fab2_lib.baseboard_fab2(sch_1):page181_i78@mstr_discrete.cap~
(chips)',
 PATH='I78',
 DRAWING='@BASEBOARD_FAB2_LIB.BASEBOARD_FAB2(SCH_1):PAGE181',
 TOLERANCE='10%',
 SEC_TYPE='0402',
 MATERIAL='X7R',
 BOM_COST='IO_SLOT',
 PHYS_PAGE='181',
 XY='(2275,2600)',
 ROT='0',
 VER='2',
 VALUE='0.22UF',
 PACK_TYPE='0402',
 PART_NUMBER='A36096-155',
 LOCATION='C1F15',
 ROOM='IO_SLOT',
 SEC='1',
 CDS_LIB='mstr_discrete',
 CDS_PART_NAME='CAP_0402-0.22UF,16V,10%,X7R,A3A',
 VOLTAGE='16V',
 PRIM_FILE='./archive_libs/mstr_discrete/cap/chips/chips.prt';

PART_NAME
 C1F16 'CAP_0402-0.22UF,16V,10%,X7R,A3A':
 ROOM='IO_SLOT';

SECTION_NUMBER 1
 '@BASEBOARD_FAB2_LIB.BASEBOARD_FAB2(SCH_1):PAGE181_I79@MSTR_DISCRETE.CAP(CHIPS)':
 C_PATH='@baseboard_fab2_lib.baseboard_fab2(sch_1):page181_i79@mstr_discrete.cap~
(chips)',
 P_PATH='@baseboard_fab2_lib.baseboard_fab2(sch_1):page181_i79@mstr_discrete.cap~
(chips)',
 PATH='I79',
 DRAWING='@BASEBOARD_FAB2_LIB.BASEBOARD_FAB2(SCH_1):PAGE181',
 TOLERANCE='10%',
 SEC_TYPE='0402',
 MATERIAL='X7R',
 BOM_COST='IO_SLOT',
 PHYS_PAGE='181',
 XY='(2275,2750)',
 ROT='0',
 VER='2',
 VALUE='0.22UF',
 PACK_TYPE='0402',
 PART_NUMBER='A36096-155',
 LOCATION='C1F16',
 ROOM='IO_SLOT',
 SEC='1',
 CDS_LIB='mstr_discrete',
 CDS_PART_NAME='CAP_0402-0.22UF,16V,10%,X7R,A3A',
 VOLTAGE='16V',
 PRIM_FILE='./archive_libs/mstr_discrete/cap/chips/chips.prt';

PART_NAME
 C1F17 'CAP_0402-0.22UF,16V,10%,X7R,A3A':
 ROOM='IO_SLOT';

SECTION_NUMBER 1
 '@BASEBOARD_FAB2_LIB.BASEBOARD_FAB2(SCH_1):PAGE181_I71@MSTR_DISCRETE.CAP(CHIPS)':
 C_PATH='@baseboard_fab2_lib.baseboard_fab2(sch_1):page181_i71@mstr_discrete.cap~
(chips)',
 P_PATH='@baseboard_fab2_lib.baseboard_fab2(sch_1):page181_i71@mstr_discrete.cap~
(chips)',
 PATH='I71',
 DRAWING='@BASEBOARD_FAB2_LIB.BASEBOARD_FAB2(SCH_1):PAGE181',
 TOLERANCE='10%',
 SEC_TYPE='0402',
 MATERIAL='X7R',
 BOM_COST='IO_SLOT',
 PHYS_PAGE='181',
 XY='(1775,2700)',
 ROT='0',
 VER='2',
 VALUE='0.22UF',
 PACK_TYPE='0402',
 PART_NUMBER='A36096-155',
 LOCATION='C1F17',
 ROOM='IO_SLOT',
 SEC='1',
 CDS_LIB='mstr_discrete',
 CDS_PART_NAME='CAP_0402-0.22UF,16V,10%,X7R,A3A',
 VOLTAGE='16V',
 PRIM_FILE='./archive_libs/mstr_discrete/cap/chips/chips.prt';

PART_NAME
 C1F18 'CAP_0402-0.22UF,16V,10%,X7R,A3A':
 ROOM='IO_SLOT';

SECTION_NUMBER 1
 '@BASEBOARD_FAB2_LIB.BASEBOARD_FAB2(SCH_1):PAGE181_I72@MSTR_DISCRETE.CAP(CHIPS)':
 C_PATH='@baseboard_fab2_lib.baseboard_fab2(sch_1):page181_i72@mstr_discrete.cap~
(chips)',
 P_PATH='@baseboard_fab2_lib.baseboard_fab2(sch_1):page181_i72@mstr_discrete.cap~
(chips)',
 PATH='I72',
 DRAWING='@BASEBOARD_FAB2_LIB.BASEBOARD_FAB2(SCH_1):PAGE181',
 TOLERANCE='10%',
 SEC_TYPE='0402',
 MATERIAL='X7R',
 BOM_COST='IO_SLOT',
 PHYS_PAGE='181',
 XY='(1775,2850)',
 ROT='0',
 VER='2',
 VALUE='0.22UF',
 PACK_TYPE='0402',
 PART_NUMBER='A36096-155',
 LOCATION='C1F18',
 ROOM='IO_SLOT',
 SEC='1',
 CDS_LIB='mstr_discrete',
 CDS_PART_NAME='CAP_0402-0.22UF,16V,10%,X7R,A3A',
 VOLTAGE='16V',
 PRIM_FILE='./archive_libs/mstr_discrete/cap/chips/chips.prt';

PART_NAME
 C1F19 'CAP_A_0402V-0.01UF,25V,10%,X7RA':
 ROOM='PROC';

SECTION_NUMBER 1
 '@BASEBOARD_FAB2_LIB.BASEBOARD_FAB2(SCH_1):PAGE100_I8@DEV_DISCRETE.CAP_A(CHIPS)':
 C_PATH='@baseboard_fab2_lib.baseboard_fab2(sch_1):page100_i8@dev_discrete.cap_a~
(chips)',
 P_PATH='@baseboard_fab2_lib.baseboard_fab2(sch_1):page100_i8@dev_discrete.cap_a~
(chips)',
 PATH='I8',
 DRAWING='@BASEBOARD_FAB2_LIB.BASEBOARD_FAB2(SCH_1):PAGE100',
 TOLERANCE='10%',
 SEC_TYPE='0402V',
 MATERIAL='X7R',
 BOM_COST='PROC_SOCKET',
 PHYS_PAGE='100',
 XY='(-2350,3325)',
 ROT='0',
 VER='1',
 VALUE='0.01UF',
 PACK_TYPE='0402V',
 PART_NUMBER='A36096-045',
 LOCATION='C1F19',
 ROOM='PROC',
 SEC='1',
 CDS_LIB='dev_discrete',
 CDS_PART_NAME='CAP_A_0402V-0.01UF,25V,10%,X7RA',
 VOLTAGE='25V',
 PRIM_FILE='./archive_libs/discrete/cap_a/chips/chips.prt';

PART_NAME
 C1F20 'CAP_0402-0.22UF,16V,10%,X7R,A3A':
 ROOM='IO_SLOT';

SECTION_NUMBER 1
 '@BASEBOARD_FAB2_LIB.BASEBOARD_FAB2(SCH_1):PAGE181_I86@MSTR_DISCRETE.CAP(CHIPS)':
 C_PATH='@baseboard_fab2_lib.baseboard_fab2(sch_1):page181_i86@mstr_discrete.cap~
(chips)',
 P_PATH='@baseboard_fab2_lib.baseboard_fab2(sch_1):page181_i86@mstr_discrete.cap~
(chips)',
 PATH='I86',
 DRAWING='@BASEBOARD_FAB2_LIB.BASEBOARD_FAB2(SCH_1):PAGE181',
 TOLERANCE='10%',
 SEC_TYPE='0402',
 MATERIAL='X7R',
 BOM_COST='IO_SLOT',
 PHYS_PAGE='181',
 XY='(2275,2900)',
 ROT='0',
 VER='2',
 VALUE='0.22UF',
 PACK_TYPE='0402',
 PART_NUMBER='A36096-155',
 LOCATION='C1F20',
 ROOM='IO_SLOT',
 SEC='1',
 CDS_LIB='mstr_discrete',
 CDS_PART_NAME='CAP_0402-0.22UF,16V,10%,X7R,A3A',
 VOLTAGE='16V',
 PRIM_FILE='./archive_libs/mstr_discrete/cap/chips/chips.prt';

PART_NAME
 C1F21 'SC1U10V2KX-4-GP_SMD-BCG6-SC1U1A':;

SECTION_NUMBER 1
 '@BASEBOARD_FAB2_LIB.BASEBOARD_FAB2(SCH_1):PAGE224_I154@W_HDL.SC1U10V2KX-4-GP(CHIPS)':
 C_PATH='@baseboard_fab2_lib.baseboard_fab2(sch_1):page224_i154@w_hdl.\sc1u10v2k~
x-4-gp\(chips)',
 P_PATH='@baseboard_fab2_lib.baseboard_fab2(sch_1):page224_i154@w_hdl.\sc1u10v2k~
x-4-gp\(chips)',
 PATH='I154',
 DRAWING='@BASEBOARD_FAB2_LIB.BASEBOARD_FAB2(SCH_1):PAGE224',
 PACK_SIZE='0402',
 RATED='10V',
 ATTRIBUTE='1UF',
 BOM_SS='NOPOP',
 TOLERANCE='10%',
 SEC_TYPE='SMD-BCG6',
 PHYS_PAGE='224',
 XY='(-250,150)',
 ROT='0',
 VER='1',
 VALUE='SC1U10V2KX-4-GP',
 PACK_TYPE='SMD-BCG6',
 PART_NUMBER='78.10523.8FL',
 LOCATION='C1F21',
 SEC='1',
 CDS_LIB='w_hdl',
 CDS_PART_NAME='SC1U10V2KX-4-GP_SMD-BCG6-SC1U1A',
 PRIM_FILE='C:/<user>/w_hdl/sc1u10v2kx#2d4#2dgp/chips/chips.prt';

PART_NAME
 C1F22 'CAP_A_0402V-0.01UF,25V,10%,X7RA':
 ROOM='DDR4_CH_G';

SECTION_NUMBER 1
 '@BASEBOARD_FAB2_LIB.BASEBOARD_FAB2(SCH_1):PAGE77_I181@DEV_DISCRETE.CAP_A(CHIPS)':
 C_PATH='@baseboard_fab2_lib.baseboard_fab2(sch_1):page77_i181@dev_discrete.cap_~
a(chips)',
 P_PATH='@baseboard_fab2_lib.baseboard_fab2(sch_1):page77_i181@dev_discrete.cap_~
a(chips)',
 PATH='I181',
 DRAWING='@BASEBOARD_FAB2_LIB.BASEBOARD_FAB2(SCH_1):PAGE77',
 TOLERANCE='10%',
 MATERIAL='X7R',
 BOM_COST='MEM',
 PHYS_PAGE='77',
 XY='(-4425,1075)',
 ROT='2',
 VER='1',
 VALUE='0.01UF',
 PACK_TYPE='0402V',
 PART_NUMBER='A36096-045',
 LOCATION='C1F22',
 ROOM='DDR4_CH_G',
 CDS_LIB='dev_discrete',
 CDS_PART_NAME='CAP_A_0402V-0.01UF,25V,10%,X7RA',
 VOLTAGE='25V',
 PRIM_FILE='./archive_libs/discrete/cap_a/chips/chips.prt';

PART_NAME
 C1F26 'CAP_0402-0.220UF,16V,10%,X7R,AA':
 ROOM='VDDQ_GHJ_PWR_VR';

SECTION_NUMBER 1
 '@BASEBOARD_FAB2_LIB.BASEBOARD_FAB2(SCH_1):PAGE224_I75@MSTR_DISCRETE.CAP(CHIPS)':
 C_PATH='@baseboard_fab2_lib.baseboard_fab2(sch_1):page224_i75@mstr_discrete.cap~
(chips)',
 P_PATH='@baseboard_fab2_lib.baseboard_fab2(sch_1):page224_i75@mstr_discrete.cap~
(chips)',
 PATH='I75',
 DRAWING='@BASEBOARD_FAB2_LIB.BASEBOARD_FAB2(SCH_1):PAGE224',
 BOM_SS='NOPOP',
 SPOF='TRUE',
 TOLERANCE='10%',
 SEC_TYPE='0402',
 MATERIAL='X7R',
 PHYS_PAGE='224',
 XY='(-625,-475)',
 ROT='2',
 VER='1',
 VALUE='0.220UF',
 PACK_TYPE='0402',
 PART_NUMBER='A36096-104',
 LOCATION='C1F26',
 ROOM='VDDQ_GHJ_PWR_VR',
 SEC='1',
 CDS_LIB='mstr_discrete',
 CDS_PART_NAME='CAP_0402-0.220UF,16V,10%,X7R,AA',
 VOLTAGE='16V',
 PRIM_FILE='./archive_libs/mstr_discrete/cap/chips/chips.prt';

PART_NAME
 C1F27 'CAP_0402-1.0UF,16V,10%,X6S,D97A':
 ROOM='VDDQ_GHJ_PWR_VR';

SECTION_NUMBER 1
 '@BASEBOARD_FAB2_LIB.BASEBOARD_FAB2(SCH_1):PAGE224_I48@MSTR_DISCRETE.CAP(CHIPS)':
 C_PATH='@baseboard_fab2_lib.baseboard_fab2(sch_1):page224_i48@mstr_discrete.cap~
(chips)',
 P_PATH='@baseboard_fab2_lib.baseboard_fab2(sch_1):page224_i48@mstr_discrete.cap~
(chips)',
 PATH='I48',
 DRAWING='@BASEBOARD_FAB2_LIB.BASEBOARD_FAB2(SCH_1):PAGE224',
 TOLERANCE='10%',
 SEC_TYPE='0402',
 MATERIAL='X6S',
 PHYS_PAGE='224',
 XY='(-1425,2500)',
 ROT='0',
 VER='1',
 VALUE='1.0UF',
 PACK_TYPE='0402',
 PART_NUMBER='D97712-011',
 LOCATION='C1F27',
 ROOM='VDDQ_GHJ_PWR_VR',
 SEC='1',
 CDS_LIB='mstr_discrete',
 CDS_PART_NAME='CAP_0402-1.0UF,16V,10%,X6S,D97A',
 VOLTAGE='16V',
 PRIM_FILE='./archive_libs/mstr_discrete/cap/chips/chips.prt';

PART_NAME
 C1F28 'CAP_A_0402V-0.1UF,16V,10%,X7R,A':
 ROOM='VDDQ_GHJ_PWR_VR';

SECTION_NUMBER 1
 '@BASEBOARD_FAB2_LIB.BASEBOARD_FAB2(SCH_1):PAGE224_I78@DEV_DISCRETE.CAP_A(CHIPS)':
 C_PATH='@baseboard_fab2_lib.baseboard_fab2(sch_1):page224_i78@dev_discrete.cap_~
a(chips)',
 P_PATH='@baseboard_fab2_lib.baseboard_fab2(sch_1):page224_i78@dev_discrete.cap_~
a(chips)',
 PATH='I78',
 DRAWING='@BASEBOARD_FAB2_LIB.BASEBOARD_FAB2(SCH_1):PAGE224',
 TOLERANCE='10%',
 SEC_TYPE='0402V',
 MATERIAL='X7R',
 PHYS_PAGE='224',
 XY='(-1100,125)',
 ROT='0',
 VER='1',
 VALUE='0.1UF',
 PACK_TYPE='0402V',
 PART_NUMBER='A36096-030',
 LOCATION='C1F28',
 ROOM='VDDQ_GHJ_PWR_VR',
 SEC='1',
 CDS_LIB='dev_discrete',
 CDS_PART_NAME='CAP_A_0402V-0.1UF,16V,10%,X7R,A',
 VOLTAGE='16V',
 PRIM_FILE='./archive_libs/discrete/cap_a/chips/chips.prt';

PART_NAME
 C1G2 'SC22U16V5MX-4-GP_SMD-BCG5-SC22A':;

SECTION_NUMBER 1
 '@BASEBOARD_FAB2_LIB.BASEBOARD_FAB2(SCH_1):PAGE225_I250@W_HDL.SC22U16V5MX-4-GP(CHIPS)':
 C_PATH='@baseboard_fab2_lib.baseboard_fab2(sch_1):page225_i250@w_hdl.\sc22u16v5~
mx-4-gp\(chips)',
 P_PATH='@baseboard_fab2_lib.baseboard_fab2(sch_1):page225_i250@w_hdl.\sc22u16v5~
mx-4-gp\(chips)',
 PATH='I250',
 DRAWING='@BASEBOARD_FAB2_LIB.BASEBOARD_FAB2(SCH_1):PAGE225',
 TYPE='X6S',
 PACK_SIZE='0805',
 RATED='16V',
 ATTRIBUTE='22UF',
 TOLERANCE='20%',
 SEC_TYPE='SMD-BCG5',
 PHYS_PAGE='225',
 XY='(150,1150)',
 ROT='0',
 VER='1',
 VALUE='SC22U16V5MX-4-GP',
 PACK_TYPE='SMD-BCG5',
 PART_NUMBER='078.22611.0811',
 LOCATION='C1G2',
 SEC='1',
 CDS_LIB='w_hdl',
 CDS_PART_NAME='SC22U16V5MX-4-GP_SMD-BCG5-SC22A',
 PRIM_FILE='C:/<user>/w_hdl/sc22u16v5mx#2d4#2dgp/chips/chips.prt';

PART_NAME
 C1G4 'SC1U10V2KX-4-GP_SMD-BCG6-SC1U1A':;

SECTION_NUMBER 1
 '@BASEBOARD_FAB2_LIB.BASEBOARD_FAB2(SCH_1):PAGE224_I155@W_HDL.SC1U10V2KX-4-GP(CHIPS)':
 C_PATH='@baseboard_fab2_lib.baseboard_fab2(sch_1):page224_i155@w_hdl.\sc1u10v2k~
x-4-gp\(chips)',
 P_PATH='@baseboard_fab2_lib.baseboard_fab2(sch_1):page224_i155@w_hdl.\sc1u10v2k~
x-4-gp\(chips)',
 PATH='I155',
 DRAWING='@BASEBOARD_FAB2_LIB.BASEBOARD_FAB2(SCH_1):PAGE224',
 PACK_SIZE='0402',
 RATED='10V',
 ATTRIBUTE='1UF',
 TOLERANCE='10%',
 SEC_TYPE='SMD-BCG6',
 PHYS_PAGE='224',
 XY='(-375,2500)',
 ROT='0',
 VER='1',
 VALUE='SC1U10V2KX-4-GP',
 PACK_TYPE='SMD-BCG6',
 PART_NUMBER='78.10523.8FL',
 LOCATION='C1G4',
 SEC='1',
 CDS_LIB='w_hdl',
 CDS_PART_NAME='SC1U10V2KX-4-GP_SMD-BCG6-SC1U1A',
 PRIM_FILE='C:/<user>/w_hdl/sc1u10v2kx#2d4#2dgp/chips/chips.prt';

PART_NAME
 C1G5 'CAP_0402-0.22UF,16V,10%,X7R,A3A':
 ROOM='VDDQ_GHJ_PWR_VR';

SECTION_NUMBER 1
 '@BASEBOARD_FAB2_LIB.BASEBOARD_FAB2(SCH_1):PAGE224_I54@MSTR_DISCRETE.CAP(CHIPS)':
 C_PATH='@baseboard_fab2_lib.baseboard_fab2(sch_1):page224_i54@mstr_discrete.cap~
(chips)',
 P_PATH='@baseboard_fab2_lib.baseboard_fab2(sch_1):page224_i54@mstr_discrete.cap~
(chips)',
 PATH='I54',
 DRAWING='@BASEBOARD_FAB2_LIB.BASEBOARD_FAB2(SCH_1):PAGE224',
 TOLERANCE='10%',
 SEC_TYPE='0402',
 MATERIAL='X7R',
 PHYS_PAGE='224',
 XY='(25,2500)',
 ROT='0',
 VER='1',
 VALUE='0.22UF',
 PACK_TYPE='0402',
 PART_NUMBER='A36096-155',
 LOCATION='C1G5',
 ROOM='VDDQ_GHJ_PWR_VR',
 SEC='1',
 CDS_LIB='mstr_discrete',
 CDS_PART_NAME='CAP_0402-0.22UF,16V,10%,X7R,A3A',
 VOLTAGE='16V',
 PRIM_FILE='./archive_libs/mstr_discrete/cap/chips/chips.prt';

PART_NAME
 C1G6 'CAP_0402-1.0UF,16V,10%,X6S,D97A':
 ROOM='VDDQ_GHJ_PWR_VR';

SECTION_NUMBER 1
 '@BASEBOARD_FAB2_LIB.BASEBOARD_FAB2(SCH_1):PAGE224_I50@MSTR_DISCRETE.CAP(CHIPS)':
 C_PATH='@baseboard_fab2_lib.baseboard_fab2(sch_1):page224_i50@mstr_discrete.cap~
(chips)',
 P_PATH='@baseboard_fab2_lib.baseboard_fab2(sch_1):page224_i50@mstr_discrete.cap~
(chips)',
 PATH='I50',
 DRAWING='@BASEBOARD_FAB2_LIB.BASEBOARD_FAB2(SCH_1):PAGE224',
 TOLERANCE='10%',
 SEC_TYPE='0402',
 MATERIAL='X6S',
 PHYS_PAGE='224',
 XY='(-925,2500)',
 ROT='0',
 VER='1',
 VALUE='1.0UF',
 PACK_TYPE='0402',
 PART_NUMBER='D97712-011',
 LOCATION='C1G6',
 ROOM='VDDQ_GHJ_PWR_VR',
 SEC='1',
 CDS_LIB='mstr_discrete',
 CDS_PART_NAME='CAP_0402-1.0UF,16V,10%,X6S,D97A',
 VOLTAGE='16V',
 PRIM_FILE='./archive_libs/mstr_discrete/cap/chips/chips.prt';

PART_NAME
 C1G7 'ST270U2D5VBM-GP_SMD-TCG2-ST270A':;

SECTION_NUMBER 1
 '@BASEBOARD_FAB2_LIB.BASEBOARD_FAB2(SCH_1):PAGE225_I329@W_HDL.ST270U2D5VBM-GP(CHIPS)':
 C_PATH='@baseboard_fab2_lib.baseboard_fab2(sch_1):page225_i329@w_hdl.\st270u2d5~
vbm-gp\(chips)',
 P_PATH='@baseboard_fab2_lib.baseboard_fab2(sch_1):page225_i329@w_hdl.\st270u2d5~
vbm-gp\(chips)',
 PATH='I329',
 DRAWING='@BASEBOARD_FAB2_LIB.BASEBOARD_FAB2(SCH_1):PAGE225',
 NEW_PN='077.C3361.0001',
 NEW_SIZE='B2',
 NEW_VALUE='33UF',
 SEC_TYPE='SMD-TCG2',
 PHYS_PAGE='225',
 XY='(850,1150)',
 ROT='0',
 VER='1',
 VALUE='ST270U2D5VBM-GP',
 PACK_TYPE='SMD-TCG2',
 PART_NUMBER='077.C2771.0001',
 LOCATION='C1G7',
 SEC='1',
 CDS_LIB='w_hdl',
 CDS_PART_NAME='ST270U2D5VBM-GP_SMD-TCG2-ST270A',
 PRIM_FILE='C:/<user>/w_hdl/st270u2d5vbm#2dgp/chips/chips.prt';

PART_NAME
 C1G8 'CAP_A_0402V-0.01UF,25V,10%,X7RA':
 ROOM='PROC';

SECTION_NUMBER 1
 '@BASEBOARD_FAB2_LIB.BASEBOARD_FAB2(SCH_1):PAGE100_I26@DEV_DISCRETE.CAP_A(CHIPS)':
 C_PATH='@baseboard_fab2_lib.baseboard_fab2(sch_1):page100_i26@dev_discrete.cap_~
a(chips)',
 P_PATH='@baseboard_fab2_lib.baseboard_fab2(sch_1):page100_i26@dev_discrete.cap_~
a(chips)',
 PATH='I26',
 DRAWING='@BASEBOARD_FAB2_LIB.BASEBOARD_FAB2(SCH_1):PAGE100',
 TOLERANCE='10%',
 SEC_TYPE='0402V',
 MATERIAL='X7R',
 BOM_COST='PROC_SOCKET',
 PHYS_PAGE='100',
 XY='(0,3325)',
 ROT='0',
 VER='1',
 VALUE='0.01UF',
 PACK_TYPE='0402V',
 PART_NUMBER='A36096-045',
 LOCATION='C1G8',
 ROOM='PROC',
 SEC='1',
 CDS_LIB='dev_discrete',
 CDS_PART_NAME='CAP_A_0402V-0.01UF,25V,10%,X7RA',
 VOLTAGE='25V',
 PRIM_FILE='./archive_libs/discrete/cap_a/chips/chips.prt';

PART_NAME
 C1G10 'CAP_A_0402V-0.01UF,25V,10%,X7RA':
 ROOM='DDR4_GH_G';

SECTION_NUMBER 1
 '@BASEBOARD_FAB2_LIB.BASEBOARD_FAB2(SCH_1):PAGE80_I3@DEV_DISCRETE.CAP_A(CHIPS)':
 C_PATH='@baseboard_fab2_lib.baseboard_fab2(sch_1):page80_i3@dev_discrete.cap_a(~
chips)',
 P_PATH='@baseboard_fab2_lib.baseboard_fab2(sch_1):page80_i3@dev_discrete.cap_a(~
chips)',
 PATH='I3',
 DRAWING='@BASEBOARD_FAB2_LIB.BASEBOARD_FAB2(SCH_1):PAGE80',
 TOLERANCE='10%',
 MATERIAL='X7R',
 BOM_COST='MEM',
 PHYS_PAGE='80',
 XY='(-7225,1000)',
 ROT='2',
 VER='1',
 VALUE='0.01UF',
 PACK_TYPE='0402V',
 PART_NUMBER='A36096-045',
 LOCATION='C1G10',
 ROOM='DDR4_GH_G',
 CDS_LIB='dev_discrete',
 CDS_PART_NAME='CAP_A_0402V-0.01UF,25V,10%,X7RA',
 VOLTAGE='25V',
 PRIM_FILE='./archive_libs/discrete/cap_a/chips/chips.prt';

PART_NAME
 C1G11 'CAP_0402-0.220UF,16V,10%,X7R,AA':
 ROOM='VDDQ_GHJ_PWR_VR';

SECTION_NUMBER 1
 '@BASEBOARD_FAB2_LIB.BASEBOARD_FAB2(SCH_1):PAGE224_I44@MSTR_DISCRETE.CAP(CHIPS)':
 C_PATH='@baseboard_fab2_lib.baseboard_fab2(sch_1):page224_i44@mstr_discrete.cap~
(chips)',
 P_PATH='@baseboard_fab2_lib.baseboard_fab2(sch_1):page224_i44@mstr_discrete.cap~
(chips)',
 PATH='I44',
 DRAWING='@BASEBOARD_FAB2_LIB.BASEBOARD_FAB2(SCH_1):PAGE224',
 SPOF='TRUE',
 TOLERANCE='10%',
 SEC_TYPE='0402',
 MATERIAL='X7R',
 PHYS_PAGE='224',
 XY='(-775,1900)',
 ROT='2',
 VER='1',
 VALUE='0.220UF',
 PACK_TYPE='0402',
 PART_NUMBER='A36096-104',
 LOCATION='C1G11',
 ROOM='VDDQ_GHJ_PWR_VR',
 SEC='1',
 CDS_LIB='mstr_discrete',
 CDS_PART_NAME='CAP_0402-0.220UF,16V,10%,X7R,AA',
 VOLTAGE='16V',
 PRIM_FILE='./archive_libs/mstr_discrete/cap/chips/chips.prt';

PART_NAME
 C1G12 'ST270U2D5VBM-GP_SMD-TCG2-ST270A':;

SECTION_NUMBER 1
 '@BASEBOARD_FAB2_LIB.BASEBOARD_FAB2(SCH_1):PAGE225_I328@W_HDL.ST270U2D5VBM-GP(CHIPS)':
 C_PATH='@baseboard_fab2_lib.baseboard_fab2(sch_1):page225_i328@w_hdl.\st270u2d5~
vbm-gp\(chips)',
 P_PATH='@baseboard_fab2_lib.baseboard_fab2(sch_1):page225_i328@w_hdl.\st270u2d5~
vbm-gp\(chips)',
 PATH='I328',
 DRAWING='@BASEBOARD_FAB2_LIB.BASEBOARD_FAB2(SCH_1):PAGE225',
 NEW_PN='077.C3361.0001',
 NEW_SIZE='B2',
 NEW_VALUE='33UF',
 SEC_TYPE='SMD-TCG2',
 PHYS_PAGE='225',
 XY='(-550,1150)',
 ROT='0',
 VER='1',
 VALUE='ST270U2D5VBM-GP',
 PACK_TYPE='SMD-TCG2',
 PART_NUMBER='077.C2771.0001',
 LOCATION='C1G12',
 SEC='1',
 CDS_LIB='w_hdl',
 CDS_PART_NAME='ST270U2D5VBM-GP_SMD-TCG2-ST270A',
 PRIM_FILE='C:/<user>/w_hdl/st270u2d5vbm#2dgp/chips/chips.prt';

PART_NAME
 C1G13 'CAP_0402-1.0UF,16V,10%,X6S,D97A':
 ROOM='VDDQ_GHJ_PWR_VR';

SECTION_NUMBER 1
 '@BASEBOARD_FAB2_LIB.BASEBOARD_FAB2(SCH_1):PAGE224_I79@MSTR_DISCRETE.CAP(CHIPS)':
 C_PATH='@baseboard_fab2_lib.baseboard_fab2(sch_1):page224_i79@mstr_discrete.cap~
(chips)',
 P_PATH='@baseboard_fab2_lib.baseboard_fab2(sch_1):page224_i79@mstr_discrete.cap~
(chips)',
 PATH='I79',
 DRAWING='@BASEBOARD_FAB2_LIB.BASEBOARD_FAB2(SCH_1):PAGE224',
 TOLERANCE='10%',
 SEC_TYPE='0402',
 MATERIAL='X6S',
 PHYS_PAGE='224',
 XY='(-1375,125)',
 ROT='0',
 VER='1',
 VALUE='1.0UF',
 PACK_TYPE='0402',
 PART_NUMBER='D97712-011',
 LOCATION='C1G13',
 ROOM='VDDQ_GHJ_PWR_VR',
 SEC='1',
 CDS_LIB='mstr_discrete',
 CDS_PART_NAME='CAP_0402-1.0UF,16V,10%,X6S,D97A',
 VOLTAGE='16V',
 PRIM_FILE='./archive_libs/mstr_discrete/cap/chips/chips.prt';

PART_NAME
 C1G14 'CAP_A_0402V-0.1UF,16V,10%,X7R,A':
 ROOM='VDDQ_GHJ_PWR_VR';

SECTION_NUMBER 1
 '@BASEBOARD_FAB2_LIB.BASEBOARD_FAB2(SCH_1):PAGE224_I51@DEV_DISCRETE.CAP_A(CHIPS)':
 C_PATH='@baseboard_fab2_lib.baseboard_fab2(sch_1):page224_i51@dev_discrete.cap_~
a(chips)',
 P_PATH='@baseboard_fab2_lib.baseboard_fab2(sch_1):page224_i51@dev_discrete.cap_~
a(chips)',
 PATH='I51',
 DRAWING='@BASEBOARD_FAB2_LIB.BASEBOARD_FAB2(SCH_1):PAGE224',
 TOLERANCE='10%',
 SEC_TYPE='0402V',
 MATERIAL='X7R',
 PHYS_PAGE='224',
 XY='(-1175,2500)',
 ROT='0',
 VER='1',
 VALUE='0.1UF',
 PACK_TYPE='0402V',
 PART_NUMBER='A36096-030',
 LOCATION='C1G14',
 ROOM='VDDQ_GHJ_PWR_VR',
 SEC='1',
 CDS_LIB='dev_discrete',
 CDS_PART_NAME='CAP_A_0402V-0.1UF,16V,10%,X7R,A',
 VOLTAGE='16V',
 PRIM_FILE='./archive_libs/discrete/cap_a/chips/chips.prt';

PART_NAME
 C1G15 'ST270U2D5VBM-GP_SMD-TCG2-ST270A':;

SECTION_NUMBER 1
 '@BASEBOARD_FAB2_LIB.BASEBOARD_FAB2(SCH_1):PAGE225_I327@W_HDL.ST270U2D5VBM-GP(CHIPS)':
 C_PATH='@baseboard_fab2_lib.baseboard_fab2(sch_1):page225_i327@w_hdl.\st270u2d5~
vbm-gp\(chips)',
 P_PATH='@baseboard_fab2_lib.baseboard_fab2(sch_1):page225_i327@w_hdl.\st270u2d5~
vbm-gp\(chips)',
 PATH='I327',
 DRAWING='@BASEBOARD_FAB2_LIB.BASEBOARD_FAB2(SCH_1):PAGE225',
 NEW_PN='077.C3361.0001',
 NEW_SIZE='B2',
 NEW_VALUE='33UF',
 SEC_TYPE='SMD-TCG2',
 PHYS_PAGE='225',
 XY='(-1250,1150)',
 ROT='0',
 VER='1',
 VALUE='ST270U2D5VBM-GP',
 PACK_TYPE='SMD-TCG2',
 PART_NUMBER='077.C2771.0001',
 LOCATION='C1G15',
 SEC='1',
 CDS_LIB='w_hdl',
 CDS_PART_NAME='ST270U2D5VBM-GP_SMD-TCG2-ST270A',
 PRIM_FILE='C:/<user>/w_hdl/st270u2d5vbm#2dgp/chips/chips.prt';

PART_NAME
 C1G16 'CAP_0402LF-220PF,50V,10%,X7R,AA':
 ROOM='VDDQ_GHJ_PWR_VR',
 NO_XNET_CONNECTION='1';

SECTION_NUMBER 1
 '@BASEBOARD_FAB2_LIB.BASEBOARD_FAB2(SCH_1):PAGE223_I12@MSTR_DISCRETE.CAP(CHIPS)':
 C_PATH='@baseboard_fab2_lib.baseboard_fab2(sch_1):page223_i12@mstr_discrete.cap~
(chips)',
 P_PATH='@baseboard_fab2_lib.baseboard_fab2(sch_1):page223_i12@mstr_discrete.cap~
(chips)',
 PATH='I12',
 DRAWING='@BASEBOARD_FAB2_LIB.BASEBOARD_FAB2(SCH_1):PAGE223',
 TOLERANCE='10%',
 SEC_TYPE='0402LF',
 MATERIAL='X7R',
 NO_XNET_CONNECTION='1',
 PHYS_PAGE='223',
 XY='(-1450,575)',
 ROT='0',
 VER='1',
 VALUE='220PF',
 PACK_TYPE='0402LF',
 PART_NUMBER='A36096-050',
 LOCATION='C1G16',
 ROOM='VDDQ_GHJ_PWR_VR',
 SEC='1',
 CDS_LIB='mstr_discrete',
 CDS_PART_NAME='CAP_0402LF-220PF,50V,10%,X7R,AA',
 VOLTAGE='50V',
 PRIM_FILE='./archive_libs/mstr_discrete/cap/chips/chips.prt';

PART_NAME
 C1G17 'CAP_0805LF-22UF,4V,20%,X6S,C95A':
 GROUP='PWR_MLCC_CAP',
 ROOM='VDDQ_GHJ_PWR_VR';

SECTION_NUMBER 1
 '@BASEBOARD_FAB2_LIB.BASEBOARD_FAB2(SCH_1):PAGE224_I6@MSTR_DISCRETE.CAP(CHIPS)':
 C_PATH='@baseboard_fab2_lib.baseboard_fab2(sch_1):page224_i6@mstr_discrete.cap(~
chips)',
 P_PATH='@baseboard_fab2_lib.baseboard_fab2(sch_1):page224_i6@mstr_discrete.cap(~
chips)',
 PATH='I6',
 DRAWING='@BASEBOARD_FAB2_LIB.BASEBOARD_FAB2(SCH_1):PAGE224',
 TOLERANCE='20%',
 SEC_TYPE='0805LF',
 MATERIAL='X6S',
 BOM_COST='VDDQ_GHJ_PWR_VR',
 PHYS_PAGE='224',
 XY='(4500,1800)',
 ROT='0',
 VER='1',
 VALUE='22UF',
 PACK_TYPE='0805LF',
 PART_NUMBER='C95333-002',
 LOCATION='C1G17',
 ROOM='VDDQ_GHJ_PWR_VR',
 GROUP='PWR_MLCC_CAP',
 SEC='1',
 CDS_LIB='mstr_discrete',
 CDS_PART_NAME='CAP_0805LF-22UF,4V,20%,X6S,C95A',
 VOLTAGE='4V',
 PRIM_FILE='./archive_libs/mstr_discrete/cap/chips/chips.prt';

PART_NAME
 C1G18 'CAP_A_0402V-0.01UF,25V,10%,X7RA':
 ROOM='PROC';

SECTION_NUMBER 1
 '@BASEBOARD_FAB2_LIB.BASEBOARD_FAB2(SCH_1):PAGE100_I42@DEV_DISCRETE.CAP_A(CHIPS)':
 C_PATH='@baseboard_fab2_lib.baseboard_fab2(sch_1):page100_i42@dev_discrete.cap_~
a(chips)',
 P_PATH='@baseboard_fab2_lib.baseboard_fab2(sch_1):page100_i42@dev_discrete.cap_~
a(chips)',
 PATH='I42',
 DRAWING='@BASEBOARD_FAB2_LIB.BASEBOARD_FAB2(SCH_1):PAGE100',
 TOLERANCE='10%',
 SEC_TYPE='0402V',
 MATERIAL='X7R',
 BOM_COST='PROC_SOCKET',
 PHYS_PAGE='100',
 XY='(2450,3325)',
 ROT='0',
 VER='1',
 VALUE='0.01UF',
 PACK_TYPE='0402V',
 PART_NUMBER='A36096-045',
 LOCATION='C1G18',
 ROOM='PROC',
 SEC='1',
 CDS_LIB='dev_discrete',
 CDS_PART_NAME='CAP_A_0402V-0.01UF,25V,10%,X7RA',
 VOLTAGE='25V',
 PRIM_FILE='./archive_libs/discrete/cap_a/chips/chips.prt';

PART_NAME
 C1G19 'CAP_A_0402V-0.01UF,25V,10%,X7RA':
 ROOM='DDR4_CH_J';

SECTION_NUMBER 1
 '@BASEBOARD_FAB2_LIB.BASEBOARD_FAB2(SCH_1):PAGE82_I180@DEV_DISCRETE.CAP_A(CHIPS)':
 C_PATH='@baseboard_fab2_lib.baseboard_fab2(sch_1):page82_i180@dev_discrete.cap_~
a(chips)',
 P_PATH='@baseboard_fab2_lib.baseboard_fab2(sch_1):page82_i180@dev_discrete.cap_~
a(chips)',
 PATH='I180',
 DRAWING='@BASEBOARD_FAB2_LIB.BASEBOARD_FAB2(SCH_1):PAGE82',
 TOLERANCE='10%',
 MATERIAL='X7R',
 BOM_COST='MEM',
 PHYS_PAGE='82',
 XY='(-4500,1450)',
 ROT='2',
 VER='1',
 VALUE='0.01UF',
 PACK_TYPE='0402V',
 PART_NUMBER='A36096-045',
 LOCATION='C1G19',
 ROOM='DDR4_CH_J',
 CDS_LIB='dev_discrete',
 CDS_PART_NAME='CAP_A_0402V-0.01UF,25V,10%,X7RA',
 VOLTAGE='25V',
 PRIM_FILE='./archive_libs/discrete/cap_a/chips/chips.prt';

PART_NAME
 C1G20 'CAP_0805LF-22UF,4V,20%,X6S,C95A':
 GROUP='PWR_MLCC_CAP',
 ROOM='VDDQ_GHJ_PWR_VR';

SECTION_NUMBER 1
 '@BASEBOARD_FAB2_LIB.BASEBOARD_FAB2(SCH_1):PAGE224_I68@MSTR_DISCRETE.CAP(CHIPS)':
 C_PATH='@baseboard_fab2_lib.baseboard_fab2(sch_1):page224_i68@mstr_discrete.cap~
(chips)',
 P_PATH='@baseboard_fab2_lib.baseboard_fab2(sch_1):page224_i68@mstr_discrete.cap~
(chips)',
 PATH='I68',
 DRAWING='@BASEBOARD_FAB2_LIB.BASEBOARD_FAB2(SCH_1):PAGE224',
 BOM_SS='NOPOP',
 TOLERANCE='20%',
 SEC_TYPE='0805LF',
 MATERIAL='X6S',
 BOM_COST='VDDQ_GHJ_PWR_VR',
 PHYS_PAGE='224',
 XY='(4500,-575)',
 ROT='0',
 VER='1',
 VALUE='22UF',
 PACK_TYPE='0805LF',
 PART_NUMBER='C95333-002',
 LOCATION='C1G20',
 ROOM='VDDQ_GHJ_PWR_VR',
 GROUP='PWR_MLCC_CAP',
 SEC='1',
 CDS_LIB='mstr_discrete',
 CDS_PART_NAME='CAP_0805LF-22UF,4V,20%,X6S,C95A',
 VOLTAGE='4V',
 PRIM_FILE='./archive_libs/mstr_discrete/cap/chips/chips.prt';

PART_NAME
 C1G21 'CAP_0402LF-1000PF,50V,10%,X7R,A':
 ROOM='VDDQ_GHJ_PWR_VR';

SECTION_NUMBER 1
 '@BASEBOARD_FAB2_LIB.BASEBOARD_FAB2(SCH_1):PAGE223_I40@MSTR_DISCRETE.CAP(CHIPS)':
 C_PATH='@baseboard_fab2_lib.baseboard_fab2(sch_1):page223_i40@mstr_discrete.cap~
(chips)',
 P_PATH='@baseboard_fab2_lib.baseboard_fab2(sch_1):page223_i40@mstr_discrete.cap~
(chips)',
 PATH='I40',
 DRAWING='@BASEBOARD_FAB2_LIB.BASEBOARD_FAB2(SCH_1):PAGE223',
 TOLERANCE='10%',
 SEC_TYPE='0402LF',
 MATERIAL='X7R',
 PHYS_PAGE='223',
 XY='(3050,650)',
 ROT='0',
 VER='1',
 VALUE='1000PF',
 PACK_TYPE='0402LF',
 PART_NUMBER='A36096-046',
 LOCATION='C1G21',
 ROOM='VDDQ_GHJ_PWR_VR',
 SEC='1',
 CDS_LIB='mstr_discrete',
 CDS_PART_NAME='CAP_0402LF-1000PF,50V,10%,X7R,A',
 VOLTAGE='50V',
 PRIM_FILE='./archive_libs/mstr_discrete/cap/chips/chips.prt';

PART_NAME
 C1G22 'CAP_A_0402V-0.1UF,16V,10%,X7R,A':
 ROOM='VDDQ_GHJ_PWR_VR';

SECTION_NUMBER 1
 '@BASEBOARD_FAB2_LIB.BASEBOARD_FAB2(SCH_1):PAGE223_I43@DEV_DISCRETE.CAP_A(CHIPS)':
 C_PATH='@baseboard_fab2_lib.baseboard_fab2(sch_1):page223_i43@dev_discrete.cap_~
a(chips)',
 P_PATH='@baseboard_fab2_lib.baseboard_fab2(sch_1):page223_i43@dev_discrete.cap_~
a(chips)',
 PATH='I43',
 DRAWING='@BASEBOARD_FAB2_LIB.BASEBOARD_FAB2(SCH_1):PAGE223',
 TOLERANCE='10%',
 SEC_TYPE='0402V',
 MATERIAL='X7R',
 PHYS_PAGE='223',
 XY='(3375,-225)',
 ROT='0',
 VER='1',
 VALUE='0.1UF',
 PACK_TYPE='0402V',
 PART_NUMBER='A36096-030',
 LOCATION='C1G22',
 ROOM='VDDQ_GHJ_PWR_VR',
 SEC='1',
 CDS_LIB='dev_discrete',
 CDS_PART_NAME='CAP_A_0402V-0.1UF,16V,10%,X7R,A',
 VOLTAGE='16V',
 PRIM_FILE='./archive_libs/discrete/cap_a/chips/chips.prt';

PART_NAME
 C1G23 'CAP_A_0402V-1.0UF,6.3V,10%,X6SA':
 ROOM='VDDQ_GHJ_PWR_VR';

SECTION_NUMBER 1
 '@BASEBOARD_FAB2_LIB.BASEBOARD_FAB2(SCH_1):PAGE223_I44@DEV_DISCRETE.CAP_A(CHIPS)':
 C_PATH='@baseboard_fab2_lib.baseboard_fab2(sch_1):page223_i44@dev_discrete.cap_~
a(chips)',
 P_PATH='@baseboard_fab2_lib.baseboard_fab2(sch_1):page223_i44@dev_discrete.cap_~
a(chips)',
 PATH='I44',
 DRAWING='@BASEBOARD_FAB2_LIB.BASEBOARD_FAB2(SCH_1):PAGE223',
 TOLERANCE='10%',
 SEC_TYPE='0402V',
 MATERIAL='X6S',
 PHYS_PAGE='223',
 XY='(4025,-225)',
 ROT='0',
 VER='1',
 VALUE='1.0UF',
 PACK_TYPE='0402V',
 PART_NUMBER='D97712-004',
 LOCATION='C1G23',
 ROOM='VDDQ_GHJ_PWR_VR',
 SEC='1',
 CDS_LIB='dev_discrete',
 CDS_PART_NAME='CAP_A_0402V-1.0UF,6.3V,10%,X6SA',
 VOLTAGE='6.3V',
 PRIM_FILE='./archive_libs/discrete/cap_a/chips/chips.prt';

PART_NAME
 C1G24 'CAP_0402LF-220PF,50V,10%,X7R,AA':
 ROOM='VDDQ_GHJ_PWR_VR';

SECTION_NUMBER 1
 '@BASEBOARD_FAB2_LIB.BASEBOARD_FAB2(SCH_1):PAGE223_I27@MSTR_DISCRETE.CAP(CHIPS)':
 C_PATH='@baseboard_fab2_lib.baseboard_fab2(sch_1):page223_i27@mstr_discrete.cap~
(chips)',
 P_PATH='@baseboard_fab2_lib.baseboard_fab2(sch_1):page223_i27@mstr_discrete.cap~
(chips)',
 PATH='I27',
 DRAWING='@BASEBOARD_FAB2_LIB.BASEBOARD_FAB2(SCH_1):PAGE223',
 TOLERANCE='10%',
 SEC_TYPE='0402LF',
 MATERIAL='X7R',
 PHYS_PAGE='223',
 XY='(100,400)',
 ROT='2',
 VER='1',
 VALUE='220PF',
 PACK_TYPE='0402LF',
 PART_NUMBER='A36096-050',
 LOCATION='C1G24',
 ROOM='VDDQ_GHJ_PWR_VR',
 SEC='1',
 CDS_LIB='mstr_discrete',
 CDS_PART_NAME='CAP_0402LF-220PF,50V,10%,X7R,AA',
 VOLTAGE='50V',
 PRIM_FILE='./archive_libs/mstr_discrete/cap/chips/chips.prt';

PART_NAME
 C1G25 'CAP_A_0402V-0.1UF,16V,10%,X7R,A':
 ROOM='VDDQ_GHJ_PWR_VR';

SECTION_NUMBER 1
 '@BASEBOARD_FAB2_LIB.BASEBOARD_FAB2(SCH_1):PAGE223_I35@DEV_DISCRETE.CAP_A(CHIPS)':
 C_PATH='@baseboard_fab2_lib.baseboard_fab2(sch_1):page223_i35@dev_discrete.cap_~
a(chips)',
 P_PATH='@baseboard_fab2_lib.baseboard_fab2(sch_1):page223_i35@dev_discrete.cap_~
a(chips)',
 PATH='I35',
 DRAWING='@BASEBOARD_FAB2_LIB.BASEBOARD_FAB2(SCH_1):PAGE223',
 TOLERANCE='10%',
 SEC_TYPE='0402V',
 MATERIAL='X7R',
 PHYS_PAGE='223',
 XY='(1100,2750)',
 ROT='0',
 VER='1',
 VALUE='0.1UF',
 PACK_TYPE='0402V',
 PART_NUMBER='A36096-030',
 LOCATION='C1G25',
 ROOM='VDDQ_GHJ_PWR_VR',
 SEC='1',
 CDS_LIB='dev_discrete',
 CDS_PART_NAME='CAP_A_0402V-0.1UF,16V,10%,X7R,A',
 VOLTAGE='16V',
 PRIM_FILE='./archive_libs/discrete/cap_a/chips/chips.prt';

PART_NAME
 C1G27 'CAP_A_0402V-1.0UF,6.3V,10%,X6SA':
 ROOM='VDDQ_GHJ_PWR_VR';

SECTION_NUMBER 1
 '@BASEBOARD_FAB2_LIB.BASEBOARD_FAB2(SCH_1):PAGE223_I36@DEV_DISCRETE.CAP_A(CHIPS)':
 C_PATH='@baseboard_fab2_lib.baseboard_fab2(sch_1):page223_i36@dev_discrete.cap_~
a(chips)',
 P_PATH='@baseboard_fab2_lib.baseboard_fab2(sch_1):page223_i36@dev_discrete.cap_~
a(chips)',
 PATH='I36',
 DRAWING='@BASEBOARD_FAB2_LIB.BASEBOARD_FAB2(SCH_1):PAGE223',
 TOLERANCE='10%',
 SEC_TYPE='0402V',
 MATERIAL='X6S',
 PHYS_PAGE='223',
 XY='(1600,2750)',
 ROT='0',
 VER='1',
 VALUE='1.0UF',
 PACK_TYPE='0402V',
 PART_NUMBER='D97712-004',
 LOCATION='C1G27',
 ROOM='VDDQ_GHJ_PWR_VR',
 SEC='1',
 CDS_LIB='dev_discrete',
 CDS_PART_NAME='CAP_A_0402V-1.0UF,6.3V,10%,X6SA',
 VOLTAGE='6.3V',
 PRIM_FILE='./archive_libs/discrete/cap_a/chips/chips.prt';

PART_NAME
 C1G28 'CAP_0402-1.0UF,16V,10%,X6S,D97A':
 ROOM='VDDQ_GHJ_PWR_VR';

SECTION_NUMBER 1
 '@BASEBOARD_FAB2_LIB.BASEBOARD_FAB2(SCH_1):PAGE224_I77@MSTR_DISCRETE.CAP(CHIPS)':
 C_PATH='@baseboard_fab2_lib.baseboard_fab2(sch_1):page224_i77@mstr_discrete.cap~
(chips)',
 P_PATH='@baseboard_fab2_lib.baseboard_fab2(sch_1):page224_i77@mstr_discrete.cap~
(chips)',
 PATH='I77',
 DRAWING='@BASEBOARD_FAB2_LIB.BASEBOARD_FAB2(SCH_1):PAGE224',
 BOM_SS='NOPOP',
 TOLERANCE='10%',
 SEC_TYPE='0402',
 MATERIAL='X6S',
 PHYS_PAGE='224',
 XY='(-800,125)',
 ROT='0',
 VER='1',
 VALUE='1.0UF',
 PACK_TYPE='0402',
 PART_NUMBER='D97712-011',
 LOCATION='C1G28',
 ROOM='VDDQ_GHJ_PWR_VR',
 SEC='1',
 CDS_LIB='mstr_discrete',
 CDS_PART_NAME='CAP_0402-1.0UF,16V,10%,X6S,D97A',
 VOLTAGE='16V',
 PRIM_FILE='./archive_libs/mstr_discrete/cap/chips/chips.prt';

PART_NAME
 C1G29 'CAP_0402-0.22UF,16V,10%,X7R,A3A':
 ROOM='VDDQ_GHJ_PWR_VR';

SECTION_NUMBER 1
 '@BASEBOARD_FAB2_LIB.BASEBOARD_FAB2(SCH_1):PAGE224_I72@MSTR_DISCRETE.CAP(CHIPS)':
 C_PATH='@baseboard_fab2_lib.baseboard_fab2(sch_1):page224_i72@mstr_discrete.cap~
(chips)',
 P_PATH='@baseboard_fab2_lib.baseboard_fab2(sch_1):page224_i72@mstr_discrete.cap~
(chips)',
 PATH='I72',
 DRAWING='@BASEBOARD_FAB2_LIB.BASEBOARD_FAB2(SCH_1):PAGE224',
 BOM_SS='NOPOP',
 TOLERANCE='10%',
 SEC_TYPE='0402',
 MATERIAL='X7R',
 PHYS_PAGE='224',
 XY='(100,150)',
 ROT='0',
 VER='1',
 VALUE='0.22UF',
 PACK_TYPE='0402',
 PART_NUMBER='A36096-155',
 LOCATION='C1G29',
 ROOM='VDDQ_GHJ_PWR_VR',
 SEC='1',
 CDS_LIB='mstr_discrete',
 CDS_PART_NAME='CAP_0402-0.22UF,16V,10%,X7R,A3A',
 VOLTAGE='16V',
 PRIM_FILE='./archive_libs/mstr_discrete/cap/chips/chips.prt';

PART_NAME
 C1L1 'CAP_0402-1.0UF,16V,10%,X6S,D97A':
 ROOM='DEBUG';

SECTION_NUMBER 1
 '@BASEBOARD_FAB2_LIB.BASEBOARD_FAB2(SCH_1):PAGE112_I136@MSTR_DISCRETE.CAP(CHIPS)':
 C_PATH='@baseboard_fab2_lib.baseboard_fab2(sch_1):page112_i136@mstr_discrete.ca~
p(chips)',
 P_PATH='@baseboard_fab2_lib.baseboard_fab2(sch_1):page112_i136@mstr_discrete.ca~
p(chips)',
 PATH='I136',
 DRAWING='@BASEBOARD_FAB2_LIB.BASEBOARD_FAB2(SCH_1):PAGE112',
 TOLERANCE='10%',
 SEC_TYPE='0402',
 MATERIAL='X6S',
 PHYS_PAGE='112',
 XY='(-1125,1850)',
 ROT='0',
 VER='1',
 VALUE='1.0UF',
 PACK_TYPE='0402',
 PART_NUMBER='D97712-011',
 LOCATION='C1L1',
 ROOM='DEBUG',
 SEC='1',
 CDS_LIB='mstr_discrete',
 CDS_PART_NAME='CAP_0402-1.0UF,16V,10%,X6S,D97A',
 VOLTAGE='16V',
 PRIM_FILE='./archive_libs/mstr_discrete/cap/chips/chips.prt';

PART_NAME
 C1L4 'CAP_A_0402V-0.1UF,16V,10%,X7R,A':
 ROOM='MIO_CHASSIS';

SECTION_NUMBER 1
 '@BASEBOARD_FAB2_LIB.BASEBOARD_FAB2(SCH_1):PAGE175_I64@DEV_DISCRETE.CAP_A(CHIPS)':
 C_PATH='@baseboard_fab2_lib.baseboard_fab2(sch_1):page175_i64@dev_discrete.cap_~
a(chips)',
 P_PATH='@baseboard_fab2_lib.baseboard_fab2(sch_1):page175_i64@dev_discrete.cap_~
a(chips)',
 PATH='I64',
 DRAWING='@BASEBOARD_FAB2_LIB.BASEBOARD_FAB2(SCH_1):PAGE175',
 TOLERANCE='10%',
 SEC_TYPE='0402V',
 MATERIAL='X7R',
 BOM_COST='MIO_CHASSIS',
 PHYS_PAGE='175',
 XY='(-2900,1725)',
 ROT='0',
 VER='1',
 VALUE='0.1UF',
 PACK_TYPE='0402V',
 PART_NUMBER='A36096-030',
 LOCATION='C1L4',
 ROOM='MIO_CHASSIS',
 SEC='1',
 CDS_LIB='dev_discrete',
 CDS_PART_NAME='CAP_A_0402V-0.1UF,16V,10%,X7R,A',
 VOLTAGE='16V',
 PRIM_FILE='./archive_libs/discrete/cap_a/chips/chips.prt';

PART_NAME
 C1L5 'CAP_A_0402V-1.0UF,6.3V,10%,X6SA':
 ROOM='DEBUG';

SECTION_NUMBER 1
 '@BASEBOARD_FAB2_LIB.BASEBOARD_FAB2(SCH_1):PAGE111_I30@DEV_DISCRETE.CAP_A(CHIPS)':
 C_PATH='@baseboard_fab2_lib.baseboard_fab2(sch_1):page111_i30@dev_discrete.cap_~
a(chips)',
 P_PATH='@baseboard_fab2_lib.baseboard_fab2(sch_1):page111_i30@dev_discrete.cap_~
a(chips)',
 PATH='I30',
 DRAWING='@BASEBOARD_FAB2_LIB.BASEBOARD_FAB2(SCH_1):PAGE111',
 TOLERANCE='10%',
 MATERIAL='X6S',
 BOM_COST='DEBUG',
 PHYS_PAGE='111',
 XY='(0,2925)',
 ROT='0',
 VER='1',
 VALUE='1.0UF',
 PACK_TYPE='0402V',
 PART_NUMBER='D97712-004',
 LOCATION='C1L5',
 ROOM='DEBUG',
 CDS_LIB='dev_discrete',
 CDS_PART_NAME='CAP_A_0402V-1.0UF,6.3V,10%,X6SA',
 VOLTAGE='6.3V',
 PRIM_FILE='./archive_libs/discrete/cap_a/chips/chips.prt';

PART_NAME
 C1L8 'CAP_A_0402V-0.1UF,16V,10%,X7R,A':
 ROOM='DEBUG';

SECTION_NUMBER 1
 '@BASEBOARD_FAB2_LIB.BASEBOARD_FAB2(SCH_1):PAGE111_I14@DEV_DISCRETE.CAP_A(CHIPS)':
 C_PATH='@baseboard_fab2_lib.baseboard_fab2(sch_1):page111_i14@dev_discrete.cap_~
a(chips)',
 P_PATH='@baseboard_fab2_lib.baseboard_fab2(sch_1):page111_i14@dev_discrete.cap_~
a(chips)',
 PATH='I14',
 DRAWING='@BASEBOARD_FAB2_LIB.BASEBOARD_FAB2(SCH_1):PAGE111',
 TOLERANCE='10%',
 SEC_TYPE='0402V',
 MATERIAL='X7R',
 BOM_COST='DEBUG',
 PHYS_PAGE='111',
 XY='(2825,950)',
 ROT='1',
 VER='1',
 VALUE='0.1UF',
 PACK_TYPE='0402V',
 PART_NUMBER='A36096-030',
 LOCATION='C1L8',
 ROOM='DEBUG',
 SEC='1',
 CDS_LIB='dev_discrete',
 CDS_PART_NAME='CAP_A_0402V-0.1UF,16V,10%,X7R,A',
 VOLTAGE='16V',
 PRIM_FILE='./archive_libs/discrete/cap_a/chips/chips.prt';

PART_NAME
 C1L9 'CAP_A_0402V-0.1UF,16V,10%,X7R,A':
 ROOM='MIO_CHASSIS';

SECTION_NUMBER 1
 '@BASEBOARD_FAB2_LIB.BASEBOARD_FAB2(SCH_1):PAGE175_I38@DEV_DISCRETE.CAP_A(CHIPS)':
 C_PATH='@baseboard_fab2_lib.baseboard_fab2(sch_1):page175_i38@dev_discrete.cap_~
a(chips)',
 P_PATH='@baseboard_fab2_lib.baseboard_fab2(sch_1):page175_i38@dev_discrete.cap_~
a(chips)',
 PATH='I38',
 DRAWING='@BASEBOARD_FAB2_LIB.BASEBOARD_FAB2(SCH_1):PAGE175',
 TOLERANCE='10%',
 SEC_TYPE='0402V',
 MATERIAL='X7R',
 BOM_COST='MIO_CHASSIS',
 PHYS_PAGE='175',
 XY='(-2975,3000)',
 ROT='0',
 VER='1',
 VALUE='0.1UF',
 PACK_TYPE='0402V',
 PART_NUMBER='A36096-030',
 LOCATION='C1L9',
 ROOM='MIO_CHASSIS',
 SEC='1',
 CDS_LIB='dev_discrete',
 CDS_PART_NAME='CAP_A_0402V-0.1UF,16V,10%,X7R,A',
 VOLTAGE='16V',
 PRIM_FILE='./archive_libs/discrete/cap_a/chips/chips.prt';

PART_NAME
 C1L10 'CAP_A_0402V-1.0UF,6.3V,10%,X6SA':
 ROOM='MIO_CHASSIS';

SECTION_NUMBER 1
 '@BASEBOARD_FAB2_LIB.BASEBOARD_FAB2(SCH_1):PAGE175_I19@DEV_DISCRETE.CAP_A(CHIPS)':
 C_PATH='@baseboard_fab2_lib.baseboard_fab2(sch_1):page175_i19@dev_discrete.cap_~
a(chips)',
 P_PATH='@baseboard_fab2_lib.baseboard_fab2(sch_1):page175_i19@dev_discrete.cap_~
a(chips)',
 PATH='I19',
 DRAWING='@BASEBOARD_FAB2_LIB.BASEBOARD_FAB2(SCH_1):PAGE175',
 TOLERANCE='10%',
 SEC_TYPE='0402V',
 MATERIAL='X6S',
 BOM_COST='MIO_CHASSIS',
 PHYS_PAGE='175',
 XY='(-4925,2550)',
 ROT='0',
 VER='1',
 VALUE='1.0UF',
 PACK_TYPE='0402V',
 PART_NUMBER='D97712-004',
 LOCATION='C1L10',
 ROOM='MIO_CHASSIS',
 SEC='1',
 CDS_LIB='dev_discrete',
 CDS_PART_NAME='CAP_A_0402V-1.0UF,6.3V,10%,X6SA',
 VOLTAGE='6.3V',
 PRIM_FILE='./archive_libs/discrete/cap_a/chips/chips.prt';

PART_NAME
 C1L11 'CAP_A_0402V-0.1UF,16V,10%,X7R,A':
 ROOM='DEBUG';

SECTION_NUMBER 1
 '@BASEBOARD_FAB2_LIB.BASEBOARD_FAB2(SCH_1):PAGE111_I87@DEV_DISCRETE.CAP_A(CHIPS)':
 C_PATH='@baseboard_fab2_lib.baseboard_fab2(sch_1):page111_i87@dev_discrete.cap_~
a(chips)',
 P_PATH='@baseboard_fab2_lib.baseboard_fab2(sch_1):page111_i87@dev_discrete.cap_~
a(chips)',
 PATH='I87',
 DRAWING='@BASEBOARD_FAB2_LIB.BASEBOARD_FAB2(SCH_1):PAGE111',
 TOLERANCE='10%',
 SEC_TYPE='0402V',
 MATERIAL='X7R',
 BOM_COST='DEBUG',
 PHYS_PAGE='111',
 XY='(3900,3625)',
 ROT='0',
 VER='1',
 VALUE='0.1UF',
 PACK_TYPE='0402V',
 PART_NUMBER='A36096-030',
 LOCATION='C1L11',
 ROOM='DEBUG',
 SEC='1',
 CDS_LIB='dev_discrete',
 CDS_PART_NAME='CAP_A_0402V-0.1UF,16V,10%,X7R,A',
 VOLTAGE='16V',
 PRIM_FILE='./archive_libs/discrete/cap_a/chips/chips.prt';

PART_NAME
 C1L16 'CAP_A_0402V-0.1UF,16V,10%,X7R,A':
 ROOM='V_SUPER';

SECTION_NUMBER 1
 '@BASEBOARD_FAB2_LIB.BASEBOARD_FAB2(SCH_1):PAGE196_I81@DEV_DISCRETE.CAP_A(CHIPS)':
 C_PATH='@baseboard_fab2_lib.baseboard_fab2(sch_1):page196_i81@dev_discrete.cap_~
a(chips)',
 P_PATH='@baseboard_fab2_lib.baseboard_fab2(sch_1):page196_i81@dev_discrete.cap_~
a(chips)',
 PATH='I81',
 DRAWING='@BASEBOARD_FAB2_LIB.BASEBOARD_FAB2(SCH_1):PAGE196',
 TOLERANCE='10%',
 SEC_TYPE='0402V',
 MATERIAL='X7R',
 PHYS_PAGE='196',
 XY='(-300,1250)',
 ROT='0',
 VER='1',
 VALUE='0.1UF',
 PACK_TYPE='0402V',
 PART_NUMBER='A36096-030',
 LOCATION='C1L16',
 ROOM='V_SUPER',
 SEC='1',
 CDS_LIB='dev_discrete',
 CDS_PART_NAME='CAP_A_0402V-0.1UF,16V,10%,X7R,A',
 VOLTAGE='16V',
 PRIM_FILE='./archive_libs/discrete/cap_a/chips/chips.prt';

PART_NAME
 C1L17 'CAP_A_0402V-0.1UF,16V,10%,X7R,A':
 ROOM='MIO_CHASSIS';

SECTION_NUMBER 1
 '@BASEBOARD_FAB2_LIB.BASEBOARD_FAB2(SCH_1):PAGE175_I37@DEV_DISCRETE.CAP_A(CHIPS)':
 C_PATH='@baseboard_fab2_lib.baseboard_fab2(sch_1):page175_i37@dev_discrete.cap_~
a(chips)',
 P_PATH='@baseboard_fab2_lib.baseboard_fab2(sch_1):page175_i37@dev_discrete.cap_~
a(chips)',
 PATH='I37',
 DRAWING='@BASEBOARD_FAB2_LIB.BASEBOARD_FAB2(SCH_1):PAGE175',
 TOLERANCE='10%',
 SEC_TYPE='0402V',
 MATERIAL='X7R',
 BOM_COST='MIO_CHASSIS',
 PHYS_PAGE='175',
 XY='(-2950,4450)',
 ROT='0',
 VER='1',
 VALUE='0.1UF',
 PACK_TYPE='0402V',
 PART_NUMBER='A36096-030',
 LOCATION='C1L17',
 ROOM='MIO_CHASSIS',
 SEC='1',
 CDS_LIB='dev_discrete',
 CDS_PART_NAME='CAP_A_0402V-0.1UF,16V,10%,X7R,A',
 VOLTAGE='16V',
 PRIM_FILE='./archive_libs/discrete/cap_a/chips/chips.prt';

PART_NAME
 C1L18 'CAP_A_0402V-1.0UF,6.3V,10%,X6SA':
 ROOM='MIO_CHASSIS';

SECTION_NUMBER 1
 '@BASEBOARD_FAB2_LIB.BASEBOARD_FAB2(SCH_1):PAGE175_I11@DEV_DISCRETE.CAP_A(CHIPS)':
 C_PATH='@baseboard_fab2_lib.baseboard_fab2(sch_1):page175_i11@dev_discrete.cap_~
a(chips)',
 P_PATH='@baseboard_fab2_lib.baseboard_fab2(sch_1):page175_i11@dev_discrete.cap_~
a(chips)',
 PATH='I11',
 DRAWING='@BASEBOARD_FAB2_LIB.BASEBOARD_FAB2(SCH_1):PAGE175',
 TOLERANCE='10%',
 SEC_TYPE='0402V',
 MATERIAL='X6S',
 BOM_COST='MIO_CHASSIS',
 PHYS_PAGE='175',
 XY='(-4975,3950)',
 ROT='0',
 VER='1',
 VALUE='1.0UF',
 PACK_TYPE='0402V',
 PART_NUMBER='D97712-004',
 LOCATION='C1L18',
 ROOM='MIO_CHASSIS',
 SEC='1',
 CDS_LIB='dev_discrete',
 CDS_PART_NAME='CAP_A_0402V-1.0UF,6.3V,10%,X6SA',
 VOLTAGE='6.3V',
 PRIM_FILE='./archive_libs/discrete/cap_a/chips/chips.prt';

PART_NAME
 C1L19 'CAP_0402-1.0UF,16V,10%,X6S,D97A':
 ROOM='DEBUG';

SECTION_NUMBER 1
 '@BASEBOARD_FAB2_LIB.BASEBOARD_FAB2(SCH_1):PAGE112_I140@MSTR_DISCRETE.CAP(CHIPS)':
 C_PATH='@baseboard_fab2_lib.baseboard_fab2(sch_1):page112_i140@mstr_discrete.ca~
p(chips)',
 P_PATH='@baseboard_fab2_lib.baseboard_fab2(sch_1):page112_i140@mstr_discrete.ca~
p(chips)',
 PATH='I140',
 DRAWING='@BASEBOARD_FAB2_LIB.BASEBOARD_FAB2(SCH_1):PAGE112',
 TOLERANCE='10%',
 SEC_TYPE='0402',
 MATERIAL='X6S',
 PHYS_PAGE='112',
 XY='(-1350,625)',
 ROT='0',
 VER='1',
 VALUE='1.0UF',
 PACK_TYPE='0402',
 PART_NUMBER='D97712-011',
 LOCATION='C1L19',
 ROOM='DEBUG',
 SEC='1',
 CDS_LIB='mstr_discrete',
 CDS_PART_NAME='CAP_0402-1.0UF,16V,10%,X6S,D97A',
 VOLTAGE='16V',
 PRIM_FILE='./archive_libs/mstr_discrete/cap/chips/chips.prt';

PART_NAME
 C1L20 'CAP_A_0402V-0.01UF,25V,10%,X7RA':
 GROUP='MCP',
 ROOM='DEBUG';

SECTION_NUMBER 1
 '@BASEBOARD_FAB2_LIB.BASEBOARD_FAB2(SCH_1):PAGE113_I267@DEV_DISCRETE.CAP_A(CHIPS)':
 C_PATH='@baseboard_fab2_lib.baseboard_fab2(sch_1):page113_i267@dev_discrete.cap~
_a(chips)',
 P_PATH='@baseboard_fab2_lib.baseboard_fab2(sch_1):page113_i267@dev_discrete.cap~
_a(chips)',
 PATH='I267',
 DRAWING='@BASEBOARD_FAB2_LIB.BASEBOARD_FAB2(SCH_1):PAGE113',
 TOLERANCE='10%',
 SEC_TYPE='0402V',
 MATERIAL='X7R',
 BOM_COST='DEBUG',
 PHYS_PAGE='113',
 XY='(3025,3650)',
 ROT='2',
 VER='1',
 VALUE='0.01UF',
 PACK_TYPE='0402V',
 PART_NUMBER='A36096-045',
 LOCATION='C1L20',
 ROOM='DEBUG',
 GROUP='MCP',
 SEC='1',
 CDS_LIB='dev_discrete',
 CDS_PART_NAME='CAP_A_0402V-0.01UF,25V,10%,X7RA',
 VOLTAGE='25V',
 PRIM_FILE='./archive_libs/discrete/cap_a/chips/chips.prt';

PART_NAME
 C1L119 'CAP_0402-1.0UF,16V,10%,X6S,D97A':
 ROOM='DEBUG';

SECTION_NUMBER 1
 '@BASEBOARD_FAB2_LIB.BASEBOARD_FAB2(SCH_1):PAGE189_I69@MSTR_DISCRETE.CAP(CHIPS)':
 C_PATH='@baseboard_fab2_lib.baseboard_fab2(sch_1):page189_i69@mstr_discrete.cap~
(chips)',
 P_PATH='@baseboard_fab2_lib.baseboard_fab2(sch_1):page189_i69@mstr_discrete.cap~
(chips)',
 PATH='I69',
 DRAWING='@BASEBOARD_FAB2_LIB.BASEBOARD_FAB2(SCH_1):PAGE189',
 TOLERANCE='10%',
 MATERIAL='X6S',
 PHYS_PAGE='189',
 XY='(775,3525)',
 ROT='0',
 VER='1',
 VALUE='1.0UF',
 PACK_TYPE='0402',
 PART_NUMBER='D97712-011',
 LOCATION='C1L119',
 ROOM='DEBUG',
 CDS_LIB='mstr_discrete',
 CDS_PART_NAME='CAP_0402-1.0UF,16V,10%,X6S,D97A',
 VOLTAGE='16V',
 PRIM_FILE='./archive_libs/mstr_discrete/cap/chips/chips.prt';

PART_NAME
 C1M3 'CAP_A_0402V-1.0UF,6.3V,10%,X6SA':
 ROOM='MIO_CHASSIS';

SECTION_NUMBER 1
 '@BASEBOARD_FAB2_LIB.BASEBOARD_FAB2(SCH_1):PAGE177_I20@DEV_DISCRETE.CAP_A(CHIPS)':
 C_PATH='@baseboard_fab2_lib.baseboard_fab2(sch_1):page177_i20@dev_discrete.cap_~
a(chips)',
 P_PATH='@baseboard_fab2_lib.baseboard_fab2(sch_1):page177_i20@dev_discrete.cap_~
a(chips)',
 PATH='I20',
 DRAWING='@BASEBOARD_FAB2_LIB.BASEBOARD_FAB2(SCH_1):PAGE177',
 TOLERANCE='10%',
 MATERIAL='X6S',
 PHYS_PAGE='177',
 XY='(-5625,5425)',
 ROT='0',
 VER='1',
 VALUE='1.0UF',
 PACK_TYPE='0402V',
 PART_NUMBER='D97712-004',
 LOCATION='C1M3',
 ROOM='MIO_CHASSIS',
 CDS_LIB='dev_discrete',
 CDS_PART_NAME='CAP_A_0402V-1.0UF,6.3V,10%,X6SA',
 VOLTAGE='6.3V',
 PRIM_FILE='./archive_libs/discrete/cap_a/chips/chips.prt';

PART_NAME
 C1M4 'CAP_0402LF-47.0PF,50V,5%,EMPTYA':
 ROOM='TEMP_SENSORS';

SECTION_NUMBER 1
 '@BASEBOARD_FAB2_LIB.BASEBOARD_FAB2(SCH_1):PAGE167_I7@MSTR_DISCRETE.CAP(CHIPS)':
 C_PATH='@baseboard_fab2_lib.baseboard_fab2(sch_1):page167_i7@mstr_discrete.cap(~
chips)',
 P_PATH='@baseboard_fab2_lib.baseboard_fab2(sch_1):page167_i7@mstr_discrete.cap(~
chips)',
 PATH='I7',
 DRAWING='@BASEBOARD_FAB2_LIB.BASEBOARD_FAB2(SCH_1):PAGE167',
 TOLERANCE='5%',
 SEC_TYPE='0402LF',
 MATERIAL='EMPTY',
 BOM_COST='SM_THERM',
 PHYS_PAGE='167',
 XY='(-4850,4625)',
 ROT='0',
 VER='1',
 VALUE='47.0PF',
 PACK_TYPE='0402LF',
 PART_NUMBER='A36095-025',
 LOCATION='C1M4',
 ROOM='TEMP_SENSORS',
 SEC='1',
 CDS_LIB='mstr_discrete',
 CDS_PART_NAME='CAP_0402LF-47.0PF,50V,5%,EMPTYA',
 VOLTAGE='50V',
 PRIM_FILE='./archive_libs/mstr_discrete/cap/chips/chips.prt';

PART_NAME
 C1M5 'CAPP_3018-68UF,16V,20%,TANT,72A':;

SECTION_NUMBER 1
 '@BASEBOARD_FAB2_LIB.BASEBOARD_FAB2(SCH_1):PAGE195_I103@MSTR_DISCRETE.CAPP(CHIPS)':
 C_PATH='@baseboard_fab2_lib.baseboard_fab2(sch_1):page195_i103@mstr_discrete.ca~
pp(chips)',
 P_PATH='@baseboard_fab2_lib.baseboard_fab2(sch_1):page195_i103@mstr_discrete.ca~
pp(chips)',
 PATH='I103',
 DRAWING='@BASEBOARD_FAB2_LIB.BASEBOARD_FAB2(SCH_1):PAGE195',
 TOLERANCE='20%',
 SEC_TYPE='3018',
 MATERIAL='TANT',
 PHYS_PAGE='195',
 XY='(-6550,775)',
 ROT='0',
 VER='1',
 VALUE='68UF',
 PACK_TYPE='3018',
 PART_NUMBER='724613-112',
 LOCATION='C1M5',
 SEC='1',
 CDS_LIB='mstr_discrete',
 CDS_PART_NAME='CAPP_3018-68UF,16V,20%,TANT,72A',
 VOLTAGE='16V',
 PRIM_FILE='./archive_libs/mstr_discrete/capp/chips/chips.prt';

PART_NAME
 C1M6 'CAP_0402-0.22UF,16V,10%,X7R,A3A':
 ROOM='PCIE_STEERING';

SECTION_NUMBER 1
 '@BASEBOARD_FAB2_LIB.BASEBOARD_FAB2(SCH_1):PAGE106_I109@MSTR_DISCRETE.CAP(CHIPS)':
 C_PATH='@baseboard_fab2_lib.baseboard_fab2(sch_1):page106_i109@mstr_discrete.ca~
p(chips)',
 P_PATH='@baseboard_fab2_lib.baseboard_fab2(sch_1):page106_i109@mstr_discrete.ca~
p(chips)',
 PATH='I109',
 DRAWING='@BASEBOARD_FAB2_LIB.BASEBOARD_FAB2(SCH_1):PAGE106',
 TOLERANCE='10%',
 MATERIAL='X7R',
 PHYS_PAGE='106',
 XY='(-7100,2350)',
 ROT='2',
 VER='1',
 VALUE='0.22UF',
 PACK_TYPE='0402',
 PART_NUMBER='A36096-155',
 LOCATION='C1M6',
 ROOM='PCIE_STEERING',
 CDS_LIB='mstr_discrete',
 CDS_PART_NAME='CAP_0402-0.22UF,16V,10%,X7R,A3A',
 VOLTAGE='16V',
 PRIM_FILE='./archive_libs/mstr_discrete/cap/chips/chips.prt';

PART_NAME
 C1M7 'CAP_0402-0.22UF,16V,10%,X7R,A3A':
 ROOM='PCIE_STEERING';

SECTION_NUMBER 1
 '@BASEBOARD_FAB2_LIB.BASEBOARD_FAB2(SCH_1):PAGE106_I122@MSTR_DISCRETE.CAP(CHIPS)':
 C_PATH='@baseboard_fab2_lib.baseboard_fab2(sch_1):page106_i122@mstr_discrete.ca~
p(chips)',
 P_PATH='@baseboard_fab2_lib.baseboard_fab2(sch_1):page106_i122@mstr_discrete.ca~
p(chips)',
 PATH='I122',
 DRAWING='@BASEBOARD_FAB2_LIB.BASEBOARD_FAB2(SCH_1):PAGE106',
 TOLERANCE='10%',
 MATERIAL='X7R',
 PHYS_PAGE='106',
 XY='(-7050,1350)',
 ROT='2',
 VER='1',
 VALUE='0.22UF',
 PACK_TYPE='0402',
 PART_NUMBER='A36096-155',
 LOCATION='C1M7',
 ROOM='PCIE_STEERING',
 CDS_LIB='mstr_discrete',
 CDS_PART_NAME='CAP_0402-0.22UF,16V,10%,X7R,A3A',
 VOLTAGE='16V',
 PRIM_FILE='./archive_libs/mstr_discrete/cap/chips/chips.prt';

PART_NAME
 C1M8 'CAP_0402-0.22UF,16V,10%,X7R,A3A':
 ROOM='PCIE_STEERING';

SECTION_NUMBER 1
 '@BASEBOARD_FAB2_LIB.BASEBOARD_FAB2(SCH_1):PAGE106_I105@MSTR_DISCRETE.CAP(CHIPS)':
 C_PATH='@baseboard_fab2_lib.baseboard_fab2(sch_1):page106_i105@mstr_discrete.ca~
p(chips)',
 P_PATH='@baseboard_fab2_lib.baseboard_fab2(sch_1):page106_i105@mstr_discrete.ca~
p(chips)',
 PATH='I105',
 DRAWING='@BASEBOARD_FAB2_LIB.BASEBOARD_FAB2(SCH_1):PAGE106',
 TOLERANCE='10%',
 MATERIAL='X7R',
 PHYS_PAGE='106',
 XY='(-6900,2650)',
 ROT='2',
 VER='1',
 VALUE='0.22UF',
 PACK_TYPE='0402',
 PART_NUMBER='A36096-155',
 LOCATION='C1M8',
 ROOM='PCIE_STEERING',
 CDS_LIB='mstr_discrete',
 CDS_PART_NAME='CAP_0402-0.22UF,16V,10%,X7R,A3A',
 VOLTAGE='16V',
 PRIM_FILE='./archive_libs/mstr_discrete/cap/chips/chips.prt';

PART_NAME
 C1M9 'CAP_0402-0.22UF,16V,10%,X7R,A3A':
 ROOM='PCIE_STEERING';

SECTION_NUMBER 1
 '@BASEBOARD_FAB2_LIB.BASEBOARD_FAB2(SCH_1):PAGE106_I114@MSTR_DISCRETE.CAP(CHIPS)':
 C_PATH='@baseboard_fab2_lib.baseboard_fab2(sch_1):page106_i114@mstr_discrete.ca~
p(chips)',
 P_PATH='@baseboard_fab2_lib.baseboard_fab2(sch_1):page106_i114@mstr_discrete.ca~
p(chips)',
 PATH='I114',
 DRAWING='@BASEBOARD_FAB2_LIB.BASEBOARD_FAB2(SCH_1):PAGE106',
 TOLERANCE='10%',
 MATERIAL='X7R',
 PHYS_PAGE='106',
 XY='(-6850,1650)',
 ROT='2',
 VER='1',
 VALUE='0.22UF',
 PACK_TYPE='0402',
 PART_NUMBER='A36096-155',
 LOCATION='C1M9',
 ROOM='PCIE_STEERING',
 CDS_LIB='mstr_discrete',
 CDS_PART_NAME='CAP_0402-0.22UF,16V,10%,X7R,A3A',
 VOLTAGE='16V',
 PRIM_FILE='./archive_libs/mstr_discrete/cap/chips/chips.prt';

PART_NAME
 C1M10 'CAP_0402-0.22UF,16V,10%,X7R,A3A':
 ROOM='PCIE_STEERING';

SECTION_NUMBER 1
 '@BASEBOARD_FAB2_LIB.BASEBOARD_FAB2(SCH_1):PAGE106_I102@MSTR_DISCRETE.CAP(CHIPS)':
 C_PATH='@baseboard_fab2_lib.baseboard_fab2(sch_1):page106_i102@mstr_discrete.ca~
p(chips)',
 P_PATH='@baseboard_fab2_lib.baseboard_fab2(sch_1):page106_i102@mstr_discrete.ca~
p(chips)',
 PATH='I102',
 DRAWING='@BASEBOARD_FAB2_LIB.BASEBOARD_FAB2(SCH_1):PAGE106',
 TOLERANCE='10%',
 MATERIAL='X7R',
 BOM_COST='IO_SLOT',
 PHYS_PAGE='106',
 XY='(-6700,2350)',
 ROT='2',
 VER='1',
 VALUE='0.22UF',
 PACK_TYPE='0402',
 PART_NUMBER='A36096-155',
 LOCATION='C1M10',
 ROOM='PCIE_STEERING',
 CDS_LIB='mstr_discrete',
 CDS_PART_NAME='CAP_0402-0.22UF,16V,10%,X7R,A3A',
 VOLTAGE='16V',
 PRIM_FILE='./archive_libs/mstr_discrete/cap/chips/chips.prt';

PART_NAME
 C1M11 'CAP_0402-0.22UF,16V,10%,X7R,A3A':
 ROOM='PCIE_STEERING';

SECTION_NUMBER 1
 '@BASEBOARD_FAB2_LIB.BASEBOARD_FAB2(SCH_1):PAGE106_I117@MSTR_DISCRETE.CAP(CHIPS)':
 C_PATH='@baseboard_fab2_lib.baseboard_fab2(sch_1):page106_i117@mstr_discrete.ca~
p(chips)',
 P_PATH='@baseboard_fab2_lib.baseboard_fab2(sch_1):page106_i117@mstr_discrete.ca~
p(chips)',
 PATH='I117',
 DRAWING='@BASEBOARD_FAB2_LIB.BASEBOARD_FAB2(SCH_1):PAGE106',
 TOLERANCE='10%',
 MATERIAL='X7R',
 BOM_COST='IO_SLOT',
 PHYS_PAGE='106',
 XY='(-6650,1350)',
 ROT='2',
 VER='1',
 VALUE='0.22UF',
 PACK_TYPE='0402',
 PART_NUMBER='A36096-155',
 LOCATION='C1M11',
 ROOM='PCIE_STEERING',
 CDS_LIB='mstr_discrete',
 CDS_PART_NAME='CAP_0402-0.22UF,16V,10%,X7R,A3A',
 VOLTAGE='16V',
 PRIM_FILE='./archive_libs/mstr_discrete/cap/chips/chips.prt';

PART_NAME
 C1M12 'CAP_0402-0.22UF,16V,10%,X7R,A3A':
 ROOM='PCIE_STEERING';

SECTION_NUMBER 1
 '@BASEBOARD_FAB2_LIB.BASEBOARD_FAB2(SCH_1):PAGE106_I100@MSTR_DISCRETE.CAP(CHIPS)':
 C_PATH='@baseboard_fab2_lib.baseboard_fab2(sch_1):page106_i100@mstr_discrete.ca~
p(chips)',
 P_PATH='@baseboard_fab2_lib.baseboard_fab2(sch_1):page106_i100@mstr_discrete.ca~
p(chips)',
 PATH='I100',
 DRAWING='@BASEBOARD_FAB2_LIB.BASEBOARD_FAB2(SCH_1):PAGE106',
 TOLERANCE='10%',
 MATERIAL='X7R',
 BOM_COST='IO_SLOT',
 PHYS_PAGE='106',
 XY='(-6500,2650)',
 ROT='2',
 VER='1',
 VALUE='0.22UF',
 PACK_TYPE='0402',
 PART_NUMBER='A36096-155',
 LOCATION='C1M12',
 ROOM='PCIE_STEERING',
 CDS_LIB='mstr_discrete',
 CDS_PART_NAME='CAP_0402-0.22UF,16V,10%,X7R,A3A',
 VOLTAGE='16V',
 PRIM_FILE='./archive_libs/mstr_discrete/cap/chips/chips.prt';

PART_NAME
 C1M13 'CAP_0402-0.22UF,16V,10%,X7R,A3A':
 ROOM='PCIE_STEERING';

SECTION_NUMBER 1
 '@BASEBOARD_FAB2_LIB.BASEBOARD_FAB2(SCH_1):PAGE106_I111@MSTR_DISCRETE.CAP(CHIPS)':
 C_PATH='@baseboard_fab2_lib.baseboard_fab2(sch_1):page106_i111@mstr_discrete.ca~
p(chips)',
 P_PATH='@baseboard_fab2_lib.baseboard_fab2(sch_1):page106_i111@mstr_discrete.ca~
p(chips)',
 PATH='I111',
 DRAWING='@BASEBOARD_FAB2_LIB.BASEBOARD_FAB2(SCH_1):PAGE106',
 TOLERANCE='10%',
 MATERIAL='X7R',
 BOM_COST='IO_SLOT',
 PHYS_PAGE='106',
 XY='(-6450,1650)',
 ROT='2',
 VER='1',
 VALUE='0.22UF',
 PACK_TYPE='0402',
 PART_NUMBER='A36096-155',
 LOCATION='C1M13',
 ROOM='PCIE_STEERING',
 CDS_LIB='mstr_discrete',
 CDS_PART_NAME='CAP_0402-0.22UF,16V,10%,X7R,A3A',
 VOLTAGE='16V',
 PRIM_FILE='./archive_libs/mstr_discrete/cap/chips/chips.prt';

PART_NAME
 C1M14 'CAP_0402-0.22UF,16V,10%,X7R,A3A':
 ROOM='PCIE_STEERING';

SECTION_NUMBER 1
 '@BASEBOARD_FAB2_LIB.BASEBOARD_FAB2(SCH_1):PAGE106_I85@MSTR_DISCRETE.CAP(CHIPS)':
 C_PATH='@baseboard_fab2_lib.baseboard_fab2(sch_1):page106_i85@mstr_discrete.cap~
(chips)',
 P_PATH='@baseboard_fab2_lib.baseboard_fab2(sch_1):page106_i85@mstr_discrete.cap~
(chips)',
 PATH='I85',
 DRAWING='@BASEBOARD_FAB2_LIB.BASEBOARD_FAB2(SCH_1):PAGE106',
 TOLERANCE='10%',
 MATERIAL='X7R',
 BOM_COST='IO_SLOT',
 PHYS_PAGE='106',
 XY='(-6300,2350)',
 ROT='2',
 VER='1',
 VALUE='0.22UF',
 PACK_TYPE='0402',
 PART_NUMBER='A36096-155',
 LOCATION='C1M14',
 ROOM='PCIE_STEERING',
 CDS_LIB='mstr_discrete',
 CDS_PART_NAME='CAP_0402-0.22UF,16V,10%,X7R,A3A',
 VOLTAGE='16V',
 PRIM_FILE='./archive_libs/mstr_discrete/cap/chips/chips.prt';

PART_NAME
 C1M15 'CAP_0402-0.22UF,16V,10%,X7R,A3A':
 ROOM='PCIE_STEERING';

SECTION_NUMBER 1
 '@BASEBOARD_FAB2_LIB.BASEBOARD_FAB2(SCH_1):PAGE106_I95@MSTR_DISCRETE.CAP(CHIPS)':
 C_PATH='@baseboard_fab2_lib.baseboard_fab2(sch_1):page106_i95@mstr_discrete.cap~
(chips)',
 P_PATH='@baseboard_fab2_lib.baseboard_fab2(sch_1):page106_i95@mstr_discrete.cap~
(chips)',
 PATH='I95',
 DRAWING='@BASEBOARD_FAB2_LIB.BASEBOARD_FAB2(SCH_1):PAGE106',
 TOLERANCE='10%',
 MATERIAL='X7R',
 BOM_COST='IO_SLOT',
 PHYS_PAGE='106',
 XY='(-6250,1350)',
 ROT='2',
 VER='1',
 VALUE='0.22UF',
 PACK_TYPE='0402',
 PART_NUMBER='A36096-155',
 LOCATION='C1M15',
 ROOM='PCIE_STEERING',
 CDS_LIB='mstr_discrete',
 CDS_PART_NAME='CAP_0402-0.22UF,16V,10%,X7R,A3A',
 VOLTAGE='16V',
 PRIM_FILE='./archive_libs/mstr_discrete/cap/chips/chips.prt';

PART_NAME
 C1M16 'CAP_0402-0.22UF,16V,10%,X7R,A3A':
 ROOM='PCIE_STEERING';

SECTION_NUMBER 1
 '@BASEBOARD_FAB2_LIB.BASEBOARD_FAB2(SCH_1):PAGE106_I82@MSTR_DISCRETE.CAP(CHIPS)':
 C_PATH='@baseboard_fab2_lib.baseboard_fab2(sch_1):page106_i82@mstr_discrete.cap~
(chips)',
 P_PATH='@baseboard_fab2_lib.baseboard_fab2(sch_1):page106_i82@mstr_discrete.cap~
(chips)',
 PATH='I82',
 DRAWING='@BASEBOARD_FAB2_LIB.BASEBOARD_FAB2(SCH_1):PAGE106',
 TOLERANCE='10%',
 MATERIAL='X7R',
 BOM_COST='IO_SLOT',
 PHYS_PAGE='106',
 XY='(-6100,2650)',
 ROT='2',
 VER='1',
 VALUE='0.22UF',
 PACK_TYPE='0402',
 PART_NUMBER='A36096-155',
 LOCATION='C1M16',
 ROOM='PCIE_STEERING',
 CDS_LIB='mstr_discrete',
 CDS_PART_NAME='CAP_0402-0.22UF,16V,10%,X7R,A3A',
 VOLTAGE='16V',
 PRIM_FILE='./archive_libs/mstr_discrete/cap/chips/chips.prt';

PART_NAME
 C1M17 'CAP_0402-0.22UF,16V,10%,X7R,A3A':
 ROOM='PCIE_STEERING';

SECTION_NUMBER 1
 '@BASEBOARD_FAB2_LIB.BASEBOARD_FAB2(SCH_1):PAGE106_I92@MSTR_DISCRETE.CAP(CHIPS)':
 C_PATH='@baseboard_fab2_lib.baseboard_fab2(sch_1):page106_i92@mstr_discrete.cap~
(chips)',
 P_PATH='@baseboard_fab2_lib.baseboard_fab2(sch_1):page106_i92@mstr_discrete.cap~
(chips)',
 PATH='I92',
 DRAWING='@BASEBOARD_FAB2_LIB.BASEBOARD_FAB2(SCH_1):PAGE106',
 TOLERANCE='10%',
 MATERIAL='X7R',
 BOM_COST='IO_SLOT',
 PHYS_PAGE='106',
 XY='(-6050,1650)',
 ROT='2',
 VER='1',
 VALUE='0.22UF',
 PACK_TYPE='0402',
 PART_NUMBER='A36096-155',
 LOCATION='C1M17',
 ROOM='PCIE_STEERING',
 CDS_LIB='mstr_discrete',
 CDS_PART_NAME='CAP_0402-0.22UF,16V,10%,X7R,A3A',
 VOLTAGE='16V',
 PRIM_FILE='./archive_libs/mstr_discrete/cap/chips/chips.prt';

PART_NAME
 C1M18 'CAP_0402-0.22UF,16V,10%,X7R,A3A':
 ROOM='PCIE_STEERING';

SECTION_NUMBER 1
 '@BASEBOARD_FAB2_LIB.BASEBOARD_FAB2(SCH_1):PAGE106_I78@MSTR_DISCRETE.CAP(CHIPS)':
 C_PATH='@baseboard_fab2_lib.baseboard_fab2(sch_1):page106_i78@mstr_discrete.cap~
(chips)',
 P_PATH='@baseboard_fab2_lib.baseboard_fab2(sch_1):page106_i78@mstr_discrete.cap~
(chips)',
 PATH='I78',
 DRAWING='@BASEBOARD_FAB2_LIB.BASEBOARD_FAB2(SCH_1):PAGE106',
 TOLERANCE='10%',
 MATERIAL='X7R',
 BOM_COST='IO_SLOT',
 PHYS_PAGE='106',
 XY='(-5900,2350)',
 ROT='2',
 VER='1',
 VALUE='0.22UF',
 PACK_TYPE='0402',
 PART_NUMBER='A36096-155',
 LOCATION='C1M18',
 ROOM='PCIE_STEERING',
 CDS_LIB='mstr_discrete',
 CDS_PART_NAME='CAP_0402-0.22UF,16V,10%,X7R,A3A',
 VOLTAGE='16V',
 PRIM_FILE='./archive_libs/mstr_discrete/cap/chips/chips.prt';

PART_NAME
 C1M19 'CAP_0402-0.22UF,16V,10%,X7R,A3A':
 ROOM='PCIE_STEERING';

SECTION_NUMBER 1
 '@BASEBOARD_FAB2_LIB.BASEBOARD_FAB2(SCH_1):PAGE106_I90@MSTR_DISCRETE.CAP(CHIPS)':
 C_PATH='@baseboard_fab2_lib.baseboard_fab2(sch_1):page106_i90@mstr_discrete.cap~
(chips)',
 P_PATH='@baseboard_fab2_lib.baseboard_fab2(sch_1):page106_i90@mstr_discrete.cap~
(chips)',
 PATH='I90',
 DRAWING='@BASEBOARD_FAB2_LIB.BASEBOARD_FAB2(SCH_1):PAGE106',
 TOLERANCE='10%',
 MATERIAL='X7R',
 BOM_COST='IO_SLOT',
 PHYS_PAGE='106',
 XY='(-5850,1350)',
 ROT='2',
 VER='1',
 VALUE='0.22UF',
 PACK_TYPE='0402',
 PART_NUMBER='A36096-155',
 LOCATION='C1M19',
 ROOM='PCIE_STEERING',
 CDS_LIB='mstr_discrete',
 CDS_PART_NAME='CAP_0402-0.22UF,16V,10%,X7R,A3A',
 VOLTAGE='16V',
 PRIM_FILE='./archive_libs/mstr_discrete/cap/chips/chips.prt';

PART_NAME
 C1M20 'CAP_A_0402V-0.1UF,16V,10%,X7R,A':
 ROOM='IO_SLOT';

SECTION_NUMBER 1
 '@BASEBOARD_FAB2_LIB.BASEBOARD_FAB2(SCH_1):PAGE186_I270@DEV_DISCRETE.CAP_A(CHIPS)':
 C_PATH='@baseboard_fab2_lib.baseboard_fab2(sch_1):page186_i270@dev_discrete.cap~
_a(chips)',
 P_PATH='@baseboard_fab2_lib.baseboard_fab2(sch_1):page186_i270@dev_discrete.cap~
_a(chips)',
 PATH='I270',
 DRAWING='@BASEBOARD_FAB2_LIB.BASEBOARD_FAB2(SCH_1):PAGE186',
 TOLERANCE='10%',
 SEC_TYPE='0402V',
 MATERIAL='X7R',
 PHYS_PAGE='186',
 XY='(11650,4675)',
 ROT='0',
 VER='1',
 VALUE='0.1UF',
 PACK_TYPE='0402V',
 PART_NUMBER='A36096-030',
 LOCATION='C1M20',
 ROOM='IO_SLOT',
 SEC='1',
 CDS_LIB='dev_discrete',
 CDS_PART_NAME='CAP_A_0402V-0.1UF,16V,10%,X7R,A',
 VOLTAGE='16V',
 PRIM_FILE='./archive_libs/discrete/cap_a/chips/chips.prt';

PART_NAME
 C1M21 'CAP_A_0402V-1.0UF,6.3V,10%,X6SA':
 ROOM='IO_SLOT';

SECTION_NUMBER 1
 '@BASEBOARD_FAB2_LIB.BASEBOARD_FAB2(SCH_1):PAGE186_I334@DEV_DISCRETE.CAP_A(CHIPS)':
 C_PATH='@baseboard_fab2_lib.baseboard_fab2(sch_1):page186_i334@dev_discrete.cap~
_a(chips)',
 P_PATH='@baseboard_fab2_lib.baseboard_fab2(sch_1):page186_i334@dev_discrete.cap~
_a(chips)',
 PATH='I334',
 DRAWING='@BASEBOARD_FAB2_LIB.BASEBOARD_FAB2(SCH_1):PAGE186',
 TOLERANCE='10%',
 SEC_TYPE='0402V',
 MATERIAL='X6S',
 PHYS_PAGE='186',
 XY='(10450,4700)',
 ROT='0',
 VER='1',
 VALUE='1.0UF',
 PACK_TYPE='0402V',
 PART_NUMBER='D97712-004',
 LOCATION='C1M21',
 ROOM='IO_SLOT',
 SEC='1',
 CDS_LIB='dev_discrete',
 CDS_PART_NAME='CAP_A_0402V-1.0UF,6.3V,10%,X6SA',
 VOLTAGE='6.3V',
 PRIM_FILE='./archive_libs/discrete/cap_a/chips/chips.prt';

PART_NAME
 C1M22 'CAP_A_0402V-0.1UF,16V,10%,X7R,A':
 ROOM='IO_SLOT';

SECTION_NUMBER 1
 '@BASEBOARD_FAB2_LIB.BASEBOARD_FAB2(SCH_1):PAGE186_I8@DEV_DISCRETE.CAP_A(CHIPS)':
 C_PATH='@baseboard_fab2_lib.baseboard_fab2(sch_1):page186_i8@dev_discrete.cap_a~
(chips)',
 P_PATH='@baseboard_fab2_lib.baseboard_fab2(sch_1):page186_i8@dev_discrete.cap_a~
(chips)',
 PATH='I8',
 DRAWING='@BASEBOARD_FAB2_LIB.BASEBOARD_FAB2(SCH_1):PAGE186',
 TOLERANCE='10%',
 SEC_TYPE='0402V',
 MATERIAL='X7R',
 PHYS_PAGE='186',
 XY='(11650,3950)',
 ROT='0',
 VER='1',
 VALUE='0.1UF',
 PACK_TYPE='0402V',
 PART_NUMBER='A36096-030',
 LOCATION='C1M22',
 ROOM='IO_SLOT',
 SEC='1',
 CDS_LIB='dev_discrete',
 CDS_PART_NAME='CAP_A_0402V-0.1UF,16V,10%,X7R,A',
 VOLTAGE='16V',
 PRIM_FILE='./archive_libs/discrete/cap_a/chips/chips.prt';

PART_NAME
 C1M23 'CAP_A_0402V-0.1UF,16V,10%,X7R,A':
 ROOM='IO_SLOT';

SECTION_NUMBER 1
 '@BASEBOARD_FAB2_LIB.BASEBOARD_FAB2(SCH_1):PAGE186_I7@DEV_DISCRETE.CAP_A(CHIPS)':
 C_PATH='@baseboard_fab2_lib.baseboard_fab2(sch_1):page186_i7@dev_discrete.cap_a~
(chips)',
 P_PATH='@baseboard_fab2_lib.baseboard_fab2(sch_1):page186_i7@dev_discrete.cap_a~
(chips)',
 PATH='I7',
 DRAWING='@BASEBOARD_FAB2_LIB.BASEBOARD_FAB2(SCH_1):PAGE186',
 TOLERANCE='10%',
 SEC_TYPE='0402V',
 MATERIAL='X7R',
 PHYS_PAGE='186',
 XY='(11225,3950)',
 ROT='0',
 VER='1',
 VALUE='0.1UF',
 PACK_TYPE='0402V',
 PART_NUMBER='A36096-030',
 LOCATION='C1M23',
 ROOM='IO_SLOT',
 SEC='1',
 CDS_LIB='dev_discrete',
 CDS_PART_NAME='CAP_A_0402V-0.1UF,16V,10%,X7R,A',
 VOLTAGE='16V',
 PRIM_FILE='./archive_libs/discrete/cap_a/chips/chips.prt';

PART_NAME
 C1M24 'CAP_A_0402V-0.1UF,16V,10%,X7R,A':
 ROOM='IO_SLOT';

SECTION_NUMBER 1
 '@BASEBOARD_FAB2_LIB.BASEBOARD_FAB2(SCH_1):PAGE186_I10@DEV_DISCRETE.CAP_A(CHIPS)':
 C_PATH='@baseboard_fab2_lib.baseboard_fab2(sch_1):page186_i10@dev_discrete.cap_~
a(chips)',
 P_PATH='@baseboard_fab2_lib.baseboard_fab2(sch_1):page186_i10@dev_discrete.cap_~
a(chips)',
 PATH='I10',
 DRAWING='@BASEBOARD_FAB2_LIB.BASEBOARD_FAB2(SCH_1):PAGE186',
 TOLERANCE='10%',
 SEC_TYPE='0402V',
 MATERIAL='X7R',
 PHYS_PAGE='186',
 XY='(10850,4675)',
 ROT='0',
 VER='1',
 VALUE='0.1UF',
 PACK_TYPE='0402V',
 PART_NUMBER='A36096-030',
 LOCATION='C1M24',
 ROOM='IO_SLOT',
 SEC='1',
 CDS_LIB='dev_discrete',
 CDS_PART_NAME='CAP_A_0402V-0.1UF,16V,10%,X7R,A',
 VOLTAGE='16V',
 PRIM_FILE='./archive_libs/discrete/cap_a/chips/chips.prt';

PART_NAME
 C1M25 'CAP_A_0402V-1.0UF,6.3V,10%,X6SA':
 ROOM='IO_SLOT';

SECTION_NUMBER 1
 '@BASEBOARD_FAB2_LIB.BASEBOARD_FAB2(SCH_1):PAGE186_I335@DEV_DISCRETE.CAP_A(CHIPS)':
 C_PATH='@baseboard_fab2_lib.baseboard_fab2(sch_1):page186_i335@dev_discrete.cap~
_a(chips)',
 P_PATH='@baseboard_fab2_lib.baseboard_fab2(sch_1):page186_i335@dev_discrete.cap~
_a(chips)',
 PATH='I335',
 DRAWING='@BASEBOARD_FAB2_LIB.BASEBOARD_FAB2(SCH_1):PAGE186',
 TOLERANCE='10%',
 SEC_TYPE='0402V',
 MATERIAL='X6S',
 PHYS_PAGE='186',
 XY='(11250,4700)',
 ROT='0',
 VER='1',
 VALUE='1.0UF',
 PACK_TYPE='0402V',
 PART_NUMBER='D97712-004',
 LOCATION='C1M25',
 ROOM='IO_SLOT',
 SEC='1',
 CDS_LIB='dev_discrete',
 CDS_PART_NAME='CAP_A_0402V-1.0UF,6.3V,10%,X6SA',
 VOLTAGE='6.3V',
 PRIM_FILE='./archive_libs/discrete/cap_a/chips/chips.prt';

PART_NAME
 C1M26 'CAP_0805-10UF,16V,10%,X6S,C953A':
 ROOM='IO_SLOT';

SECTION_NUMBER 1
 '@BASEBOARD_FAB2_LIB.BASEBOARD_FAB2(SCH_1):PAGE186_I6@MSTR_DISCRETE.CAP(CHIPS)':
 C_PATH='@baseboard_fab2_lib.baseboard_fab2(sch_1):page186_i6@mstr_discrete.cap(~
chips)',
 P_PATH='@baseboard_fab2_lib.baseboard_fab2(sch_1):page186_i6@mstr_discrete.cap(~
chips)',
 PATH='I6',
 DRAWING='@BASEBOARD_FAB2_LIB.BASEBOARD_FAB2(SCH_1):PAGE186',
 TOLERANCE='10%',
 SEC_TYPE='0805',
 MATERIAL='X6S',
 PHYS_PAGE='186',
 XY='(10850,3950)',
 ROT='0',
 VER='1',
 VALUE='10UF',
 PACK_TYPE='0805',
 PART_NUMBER='C95333-007',
 LOCATION='C1M26',
 ROOM='IO_SLOT',
 SEC='1',
 CDS_LIB='mstr_discrete',
 CDS_PART_NAME='CAP_0805-10UF,16V,10%,X6S,C953A',
 VOLTAGE='16V',
 PRIM_FILE='./archive_libs/mstr_discrete/cap/chips/chips.prt';

PART_NAME
 C1M27 'CAP_0805-10UF,16V,10%,X6S,C953A':
 ROOM='IO_SLOT';

SECTION_NUMBER 1
 '@BASEBOARD_FAB2_LIB.BASEBOARD_FAB2(SCH_1):PAGE186_I3@MSTR_DISCRETE.CAP(CHIPS)':
 C_PATH='@baseboard_fab2_lib.baseboard_fab2(sch_1):page186_i3@mstr_discrete.cap(~
chips)',
 P_PATH='@baseboard_fab2_lib.baseboard_fab2(sch_1):page186_i3@mstr_discrete.cap(~
chips)',
 PATH='I3',
 DRAWING='@BASEBOARD_FAB2_LIB.BASEBOARD_FAB2(SCH_1):PAGE186',
 TOLERANCE='10%',
 SEC_TYPE='0805',
 MATERIAL='X6S',
 PHYS_PAGE='186',
 XY='(10450,3975)',
 ROT='0',
 VER='1',
 VALUE='10UF',
 PACK_TYPE='0805',
 PART_NUMBER='C95333-007',
 LOCATION='C1M27',
 ROOM='IO_SLOT',
 SEC='1',
 CDS_LIB='mstr_discrete',
 CDS_PART_NAME='CAP_0805-10UF,16V,10%,X6S,C953A',
 VOLTAGE='16V',
 PRIM_FILE='./archive_libs/mstr_discrete/cap/chips/chips.prt';

PART_NAME
 C1M28 'CAP_A_0402V-0.01UF,25V,10%,X7RA':
 GROUP='MCP',
 ROOM='DEBUG';

SECTION_NUMBER 1
 '@BASEBOARD_FAB2_LIB.BASEBOARD_FAB2(SCH_1):PAGE113_I119@DEV_DISCRETE.CAP_A(CHIPS)':
 C_PATH='@baseboard_fab2_lib.baseboard_fab2(sch_1):page113_i119@dev_discrete.cap~
_a(chips)',
 P_PATH='@baseboard_fab2_lib.baseboard_fab2(sch_1):page113_i119@dev_discrete.cap~
_a(chips)',
 PATH='I119',
 DRAWING='@BASEBOARD_FAB2_LIB.BASEBOARD_FAB2(SCH_1):PAGE113',
 TOLERANCE='10%',
 SEC_TYPE='0402V',
 MATERIAL='X7R',
 BOM_COST='DEBUG',
 PHYS_PAGE='113',
 XY='(-2250,1250)',
 ROT='2',
 VER='1',
 VALUE='0.01UF',
 PACK_TYPE='0402V',
 PART_NUMBER='A36096-045',
 LOCATION='C1M28',
 ROOM='DEBUG',
 GROUP='MCP',
 SEC='1',
 CDS_LIB='dev_discrete',
 CDS_PART_NAME='CAP_A_0402V-0.01UF,25V,10%,X7RA',
 VOLTAGE='25V',
 PRIM_FILE='./archive_libs/discrete/cap_a/chips/chips.prt';

PART_NAME
 C1M29 'CAP_A_0402V-0.1UF,16V,10%,X7R,A':
 GROUP='MCP',
 ROOM='DEBUG';

SECTION_NUMBER 1
 '@BASEBOARD_FAB2_LIB.BASEBOARD_FAB2(SCH_1):PAGE113_I147@DEV_DISCRETE.CAP_A(CHIPS)':
 C_PATH='@baseboard_fab2_lib.baseboard_fab2(sch_1):page113_i147@dev_discrete.cap~
_a(chips)',
 P_PATH='@baseboard_fab2_lib.baseboard_fab2(sch_1):page113_i147@dev_discrete.cap~
_a(chips)',
 PATH='I147',
 DRAWING='@BASEBOARD_FAB2_LIB.BASEBOARD_FAB2(SCH_1):PAGE113',
 TOLERANCE='10%',
 MATERIAL='X7R',
 PHYS_PAGE='113',
 XY='(-975,4650)',
 ROT='0',
 VER='1',
 VALUE='0.1UF',
 PACK_TYPE='0402V',
 PART_NUMBER='A36096-030',
 LOCATION='C1M29',
 ROOM='DEBUG',
 GROUP='MCP',
 CDS_LIB='dev_discrete',
 CDS_PART_NAME='CAP_A_0402V-0.1UF,16V,10%,X7R,A',
 VOLTAGE='16V',
 PRIM_FILE='./archive_libs/discrete/cap_a/chips/chips.prt';

PART_NAME
 C1M30 'CAP_A_0402V-0.01UF,25V,10%,X7RA':
 ROOM='DEBUG';

SECTION_NUMBER 1
 '@BASEBOARD_FAB2_LIB.BASEBOARD_FAB2(SCH_1):PAGE112_I131@DEV_DISCRETE.CAP_A(CHIPS)':
 C_PATH='@baseboard_fab2_lib.baseboard_fab2(sch_1):page112_i131@dev_discrete.cap~
_a(chips)',
 P_PATH='@baseboard_fab2_lib.baseboard_fab2(sch_1):page112_i131@dev_discrete.cap~
_a(chips)',
 PATH='I131',
 DRAWING='@BASEBOARD_FAB2_LIB.BASEBOARD_FAB2(SCH_1):PAGE112',
 TOLERANCE='10%',
 SEC_TYPE='0402V',
 MATERIAL='X7R',
 BOM_COST='DEBUG',
 PHYS_PAGE='112',
 XY='(3550,3725)',
 ROT='2',
 VER='1',
 VALUE='0.01UF',
 PACK_TYPE='0402V',
 PART_NUMBER='A36096-045',
 LOCATION='C1M30',
 ROOM='DEBUG',
 SEC='1',
 CDS_LIB='dev_discrete',
 CDS_PART_NAME='CAP_A_0402V-0.01UF,25V,10%,X7RA',
 VOLTAGE='25V',
 PRIM_FILE='./archive_libs/discrete/cap_a/chips/chips.prt';

PART_NAME
 C1M31 'CAP_A_0402V-0.01UF,25V,10%,X7RA':
 GROUP='MCP',
 ROOM='DEBUG';

SECTION_NUMBER 1
 '@BASEBOARD_FAB2_LIB.BASEBOARD_FAB2(SCH_1):PAGE113_I116@DEV_DISCRETE.CAP_A(CHIPS)':
 C_PATH='@baseboard_fab2_lib.baseboard_fab2(sch_1):page113_i116@dev_discrete.cap~
_a(chips)',
 P_PATH='@baseboard_fab2_lib.baseboard_fab2(sch_1):page113_i116@dev_discrete.cap~
_a(chips)',
 PATH='I116',
 DRAWING='@BASEBOARD_FAB2_LIB.BASEBOARD_FAB2(SCH_1):PAGE113',
 TOLERANCE='10%',
 SEC_TYPE='0402V',
 MATERIAL='X7R',
 BOM_COST='DEBUG',
 PHYS_PAGE='113',
 XY='(-1550,3025)',
 ROT='2',
 VER='1',
 VALUE='0.01UF',
 PACK_TYPE='0402V',
 PART_NUMBER='A36096-045',
 LOCATION='C1M31',
 ROOM='DEBUG',
 GROUP='MCP',
 SEC='1',
 CDS_LIB='dev_discrete',
 CDS_PART_NAME='CAP_A_0402V-0.01UF,25V,10%,X7RA',
 VOLTAGE='25V',
 PRIM_FILE='./archive_libs/discrete/cap_a/chips/chips.prt';

PART_NAME
 C1M32 'CAP_A_0402V-1.0UF,6.3V,10%,X6SA':
 GROUP='MCP',
 ROOM='DEBUG';

SECTION_NUMBER 1
 '@BASEBOARD_FAB2_LIB.BASEBOARD_FAB2(SCH_1):PAGE113_I117@DEV_DISCRETE.CAP_A(CHIPS)':
 C_PATH='@baseboard_fab2_lib.baseboard_fab2(sch_1):page113_i117@dev_discrete.cap~
_a(chips)',
 P_PATH='@baseboard_fab2_lib.baseboard_fab2(sch_1):page113_i117@dev_discrete.cap~
_a(chips)',
 PATH='I117',
 DRAWING='@BASEBOARD_FAB2_LIB.BASEBOARD_FAB2(SCH_1):PAGE113',
 TOLERANCE='10%',
 SEC_TYPE='0402V',
 MATERIAL='X6S',
 BOM_COST='DEBUG',
 PHYS_PAGE='113',
 XY='(-1250,3025)',
 ROT='2',
 VER='1',
 VALUE='1.0UF',
 PACK_TYPE='0402V',
 PART_NUMBER='D97712-004',
 LOCATION='C1M32',
 ROOM='DEBUG',
 GROUP='MCP',
 SEC='1',
 CDS_LIB='dev_discrete',
 CDS_PART_NAME='CAP_A_0402V-1.0UF,6.3V,10%,X6SA',
 VOLTAGE='6.3V',
 PRIM_FILE='./archive_libs/discrete/cap_a/chips/chips.prt';

PART_NAME
 C1M33 'CAP_A_0402V-0.1UF,16V,10%,X7R,A':
 ROOM='DEBUG';

SECTION_NUMBER 1
 '@BASEBOARD_FAB2_LIB.BASEBOARD_FAB2(SCH_1):PAGE113_I248@DEV_DISCRETE.CAP_A(CHIPS)':
 C_PATH='@baseboard_fab2_lib.baseboard_fab2(sch_1):page113_i248@dev_discrete.cap~
_a(chips)',
 P_PATH='@baseboard_fab2_lib.baseboard_fab2(sch_1):page113_i248@dev_discrete.cap~
_a(chips)',
 PATH='I248',
 DRAWING='@BASEBOARD_FAB2_LIB.BASEBOARD_FAB2(SCH_1):PAGE113',
 POP='NOPOP',
 TOLERANCE='10%',
 SEC_TYPE='0402V',
 MATERIAL='X7R',
 BOM_COST='DEBUG',
 PHYS_PAGE='113',
 XY='(2125,2650)',
 ROT='2',
 VER='1',
 VALUE='0.1UF',
 PACK_TYPE='0402V',
 PART_NUMBER='A36096-030',
 LOCATION='C1M33',
 ROOM='DEBUG',
 SEC='1',
 CDS_LIB='dev_discrete',
 CDS_PART_NAME='CAP_A_0402V-0.1UF,16V,10%,X7R,A',
 VOLTAGE='16V',
 PRIM_FILE='./archive_libs/discrete/cap_a/chips/chips.prt';

PART_NAME
 C1M34 'CAP_A_0402V-0.01UF,25V,10%,X7RA':
 GROUP='MCP',
 ROOM='DEBUG';

SECTION_NUMBER 1
 '@BASEBOARD_FAB2_LIB.BASEBOARD_FAB2(SCH_1):PAGE113_I265@DEV_DISCRETE.CAP_A(CHIPS)':
 C_PATH='@baseboard_fab2_lib.baseboard_fab2(sch_1):page113_i265@dev_discrete.cap~
_a(chips)',
 P_PATH='@baseboard_fab2_lib.baseboard_fab2(sch_1):page113_i265@dev_discrete.cap~
_a(chips)',
 PATH='I265',
 DRAWING='@BASEBOARD_FAB2_LIB.BASEBOARD_FAB2(SCH_1):PAGE113',
 TOLERANCE='10%',
 SEC_TYPE='0402V',
 MATERIAL='X7R',
 BOM_COST='DEBUG',
 PHYS_PAGE='113',
 XY='(-1275,1825)',
 ROT='2',
 VER='1',
 VALUE='0.01UF',
 PACK_TYPE='0402V',
 PART_NUMBER='A36096-045',
 LOCATION='C1M34',
 ROOM='DEBUG',
 GROUP='MCP',
 SEC='1',
 CDS_LIB='dev_discrete',
 CDS_PART_NAME='CAP_A_0402V-0.01UF,25V,10%,X7RA',
 VOLTAGE='25V',
 PRIM_FILE='./archive_libs/discrete/cap_a/chips/chips.prt';

PART_NAME
 C1M35 'CAP_A_0402V-0.01UF,25V,10%,X7RA':
 GROUP='MCP',
 ROOM='DEBUG';

SECTION_NUMBER 1
 '@BASEBOARD_FAB2_LIB.BASEBOARD_FAB2(SCH_1):PAGE113_I266@DEV_DISCRETE.CAP_A(CHIPS)':
 C_PATH='@baseboard_fab2_lib.baseboard_fab2(sch_1):page113_i266@dev_discrete.cap~
_a(chips)',
 P_PATH='@baseboard_fab2_lib.baseboard_fab2(sch_1):page113_i266@dev_discrete.cap~
_a(chips)',
 PATH='I266',
 DRAWING='@BASEBOARD_FAB2_LIB.BASEBOARD_FAB2(SCH_1):PAGE113',
 TOLERANCE='10%',
 SEC_TYPE='0402V',
 MATERIAL='X7R',
 BOM_COST='DEBUG',
 PHYS_PAGE='113',
 XY='(-1600,1825)',
 ROT='2',
 VER='1',
 VALUE='0.01UF',
 PACK_TYPE='0402V',
 PART_NUMBER='A36096-045',
 LOCATION='C1M35',
 ROOM='DEBUG',
 GROUP='MCP',
 SEC='1',
 CDS_LIB='dev_discrete',
 CDS_PART_NAME='CAP_A_0402V-0.01UF,25V,10%,X7RA',
 VOLTAGE='25V',
 PRIM_FILE='./archive_libs/discrete/cap_a/chips/chips.prt';

PART_NAME
 C1M36 'CAP_A_0402V-0.01UF,25V,10%,X7RA':
 ROOM='DEBUG';

SECTION_NUMBER 1
 '@BASEBOARD_FAB2_LIB.BASEBOARD_FAB2(SCH_1):PAGE112_I42@DEV_DISCRETE.CAP_A(CHIPS)':
 C_PATH='@baseboard_fab2_lib.baseboard_fab2(sch_1):page112_i42@dev_discrete.cap_~
a(chips)',
 P_PATH='@baseboard_fab2_lib.baseboard_fab2(sch_1):page112_i42@dev_discrete.cap_~
a(chips)',
 PATH='I42',
 DRAWING='@BASEBOARD_FAB2_LIB.BASEBOARD_FAB2(SCH_1):PAGE112',
 TOLERANCE='10%',
 SEC_TYPE='0402V',
 MATERIAL='X7R',
 BOM_COST='DEBUG',
 PHYS_PAGE='112',
 XY='(3100,4025)',
 ROT='2',
 VER='1',
 VALUE='0.01UF',
 PACK_TYPE='0402V',
 PART_NUMBER='A36096-045',
 LOCATION='C1M36',
 ROOM='DEBUG',
 SEC='1',
 CDS_LIB='dev_discrete',
 CDS_PART_NAME='CAP_A_0402V-0.01UF,25V,10%,X7RA',
 VOLTAGE='25V',
 PRIM_FILE='./archive_libs/discrete/cap_a/chips/chips.prt';

PART_NAME
 C1M37 'CAP_A_0402V-1.0UF,6.3V,10%,X6SA':
 ROOM='DEBUG';

SECTION_NUMBER 1
 '@BASEBOARD_FAB2_LIB.BASEBOARD_FAB2(SCH_1):PAGE112_I47@DEV_DISCRETE.CAP_A(CHIPS)':
 C_PATH='@baseboard_fab2_lib.baseboard_fab2(sch_1):page112_i47@dev_discrete.cap_~
a(chips)',
 P_PATH='@baseboard_fab2_lib.baseboard_fab2(sch_1):page112_i47@dev_discrete.cap_~
a(chips)',
 PATH='I47',
 DRAWING='@BASEBOARD_FAB2_LIB.BASEBOARD_FAB2(SCH_1):PAGE112',
 TOLERANCE='10%',
 MATERIAL='X6S',
 BOM_COST='DEBUG',
 PHYS_PAGE='112',
 XY='(2700,4025)',
 ROT='2',
 VER='1',
 VALUE='1.0UF',
 PACK_TYPE='0402V',
 PART_NUMBER='D97712-004',
 LOCATION='C1M37',
 ROOM='DEBUG',
 CDS_LIB='dev_discrete',
 CDS_PART_NAME='CAP_A_0402V-1.0UF,6.3V,10%,X6SA',
 VOLTAGE='6.3V',
 PRIM_FILE='./archive_libs/discrete/cap_a/chips/chips.prt';

PART_NAME
 C1M38 'CAP_A_0402V-0.1UF,16V,10%,X7R,A':
 ROOM='USB_REAR';

SECTION_NUMBER 1
 '@BASEBOARD_FAB2_LIB.BASEBOARD_FAB2(SCH_1):PAGE176_I108@DEV_DISCRETE.CAP_A(CHIPS)':
 C_PATH='@baseboard_fab2_lib.baseboard_fab2(sch_1):page176_i108@dev_discrete.cap~
_a(chips)',
 P_PATH='@baseboard_fab2_lib.baseboard_fab2(sch_1):page176_i108@dev_discrete.cap~
_a(chips)',
 PATH='I108',
 DRAWING='@BASEBOARD_FAB2_LIB.BASEBOARD_FAB2(SCH_1):PAGE176',
 TOLERANCE='10%',
 SEC_TYPE='0402V',
 MATERIAL='X7R',
 BOM_COST='MIO_USB',
 PHYS_PAGE='176',
 XY='(-5225,3525)',
 ROT='0',
 VER='1',
 VALUE='0.1UF',
 PACK_TYPE='0402V',
 PART_NUMBER='A36096-030',
 LOCATION='C1M38',
 ROOM='USB_REAR',
 SEC='1',
 CDS_LIB='dev_discrete',
 CDS_PART_NAME='CAP_A_0402V-0.1UF,16V,10%,X7R,A',
 VOLTAGE='16V',
 PRIM_FILE='./archive_libs/discrete/cap_a/chips/chips.prt';

PART_NAME
 C1R1 'CAP_0402-0.22UF,16V,10%,X7R,A3A':
 ROOM='PCIE_STEERING';

SECTION_NUMBER 1
 '@BASEBOARD_FAB2_LIB.BASEBOARD_FAB2(SCH_1):PAGE106_I29@MSTR_DISCRETE.CAP(CHIPS)':
 C_PATH='@baseboard_fab2_lib.baseboard_fab2(sch_1):page106_i29@mstr_discrete.cap~
(chips)',
 P_PATH='@baseboard_fab2_lib.baseboard_fab2(sch_1):page106_i29@mstr_discrete.cap~
(chips)',
 PATH='I29',
 DRAWING='@BASEBOARD_FAB2_LIB.BASEBOARD_FAB2(SCH_1):PAGE106',
 TOLERANCE='10%',
 MATERIAL='X7R',
 BOM_COST='IO_SLOT',
 PHYS_PAGE='106',
 XY='(-4075,1650)',
 ROT='2',
 VER='1',
 VALUE='0.22UF',
 PACK_TYPE='0402',
 PART_NUMBER='A36096-155',
 LOCATION='C1R1',
 ROOM='PCIE_STEERING',
 CDS_LIB='mstr_discrete',
 CDS_PART_NAME='CAP_0402-0.22UF,16V,10%,X7R,A3A',
 VOLTAGE='16V',
 PRIM_FILE='./archive_libs/mstr_discrete/cap/chips/chips.prt';

PART_NAME
 C1R2 'CAP_0402-0.22UF,16V,10%,X7R,A3A':
 ROOM='PCIE_STEERING';

SECTION_NUMBER 1
 '@BASEBOARD_FAB2_LIB.BASEBOARD_FAB2(SCH_1):PAGE106_I10@MSTR_DISCRETE.CAP(CHIPS)':
 C_PATH='@baseboard_fab2_lib.baseboard_fab2(sch_1):page106_i10@mstr_discrete.cap~
(chips)',
 P_PATH='@baseboard_fab2_lib.baseboard_fab2(sch_1):page106_i10@mstr_discrete.cap~
(chips)',
 PATH='I10',
 DRAWING='@BASEBOARD_FAB2_LIB.BASEBOARD_FAB2(SCH_1):PAGE106',
 TOLERANCE='10%',
 MATERIAL='X7R',
 BOM_COST='IO_SLOT',
 PHYS_PAGE='106',
 XY='(-4100,2650)',
 ROT='2',
 VER='1',
 VALUE='0.22UF',
 PACK_TYPE='0402',
 PART_NUMBER='A36096-155',
 LOCATION='C1R2',
 ROOM='PCIE_STEERING',
 CDS_LIB='mstr_discrete',
 CDS_PART_NAME='CAP_0402-0.22UF,16V,10%,X7R,A3A',
 VOLTAGE='16V',
 PRIM_FILE='./archive_libs/mstr_discrete/cap/chips/chips.prt';

PART_NAME
 C1R3 'CAP_0402-0.22UF,16V,10%,X7R,A3A':
 ROOM='PCIE_STEERING';

SECTION_NUMBER 1
 '@BASEBOARD_FAB2_LIB.BASEBOARD_FAB2(SCH_1):PAGE106_I37@MSTR_DISCRETE.CAP(CHIPS)':
 C_PATH='@baseboard_fab2_lib.baseboard_fab2(sch_1):page106_i37@mstr_discrete.cap~
(chips)',
 P_PATH='@baseboard_fab2_lib.baseboard_fab2(sch_1):page106_i37@mstr_discrete.cap~
(chips)',
 PATH='I37',
 DRAWING='@BASEBOARD_FAB2_LIB.BASEBOARD_FAB2(SCH_1):PAGE106',
 TOLERANCE='10%',
 MATERIAL='X7R',
 BOM_COST='IO_SLOT',
 PHYS_PAGE='106',
 XY='(-4275,1350)',
 ROT='2',
 VER='1',
 VALUE='0.22UF',
 PACK_TYPE='0402',
 PART_NUMBER='A36096-155',
 LOCATION='C1R3',
 ROOM='PCIE_STEERING',
 CDS_LIB='mstr_discrete',
 CDS_PART_NAME='CAP_0402-0.22UF,16V,10%,X7R,A3A',
 VOLTAGE='16V',
 PRIM_FILE='./archive_libs/mstr_discrete/cap/chips/chips.prt';

PART_NAME
 C1R4 'CAP_0402-0.22UF,16V,10%,X7R,A3A':
 ROOM='PCIE_STEERING';

SECTION_NUMBER 1
 '@BASEBOARD_FAB2_LIB.BASEBOARD_FAB2(SCH_1):PAGE106_I26@MSTR_DISCRETE.CAP(CHIPS)':
 C_PATH='@baseboard_fab2_lib.baseboard_fab2(sch_1):page106_i26@mstr_discrete.cap~
(chips)',
 P_PATH='@baseboard_fab2_lib.baseboard_fab2(sch_1):page106_i26@mstr_discrete.cap~
(chips)',
 PATH='I26',
 DRAWING='@BASEBOARD_FAB2_LIB.BASEBOARD_FAB2(SCH_1):PAGE106',
 TOLERANCE='10%',
 MATERIAL='X7R',
 BOM_COST='IO_SLOT',
 PHYS_PAGE='106',
 XY='(-4300,2350)',
 ROT='2',
 VER='1',
 VALUE='0.22UF',
 PACK_TYPE='0402',
 PART_NUMBER='A36096-155',
 LOCATION='C1R4',
 ROOM='PCIE_STEERING',
 CDS_LIB='mstr_discrete',
 CDS_PART_NAME='CAP_0402-0.22UF,16V,10%,X7R,A3A',
 VOLTAGE='16V',
 PRIM_FILE='./archive_libs/mstr_discrete/cap/chips/chips.prt';

PART_NAME
 C1R5 'CAP_0402-0.22UF,16V,10%,X7R,A3A':
 ROOM='PCIE_STEERING';

SECTION_NUMBER 1
 '@BASEBOARD_FAB2_LIB.BASEBOARD_FAB2(SCH_1):PAGE106_I59@MSTR_DISCRETE.CAP(CHIPS)':
 C_PATH='@baseboard_fab2_lib.baseboard_fab2(sch_1):page106_i59@mstr_discrete.cap~
(chips)',
 P_PATH='@baseboard_fab2_lib.baseboard_fab2(sch_1):page106_i59@mstr_discrete.cap~
(chips)',
 PATH='I59',
 DRAWING='@BASEBOARD_FAB2_LIB.BASEBOARD_FAB2(SCH_1):PAGE106',
 TOLERANCE='10%',
 MATERIAL='X7R',
 BOM_COST='IO_SLOT',
 PHYS_PAGE='106',
 XY='(-4475,1650)',
 ROT='2',
 VER='1',
 VALUE='0.22UF',
 PACK_TYPE='0402',
 PART_NUMBER='A36096-155',
 LOCATION='C1R5',
 ROOM='PCIE_STEERING',
 CDS_LIB='mstr_discrete',
 CDS_PART_NAME='CAP_0402-0.22UF,16V,10%,X7R,A3A',
 VOLTAGE='16V',
 PRIM_FILE='./archive_libs/mstr_discrete/cap/chips/chips.prt';

PART_NAME
 C1R6 'CAP_0402-0.22UF,16V,10%,X7R,A3A':
 ROOM='PCIE_STEERING';

SECTION_NUMBER 1
 '@BASEBOARD_FAB2_LIB.BASEBOARD_FAB2(SCH_1):PAGE106_I40@MSTR_DISCRETE.CAP(CHIPS)':
 C_PATH='@baseboard_fab2_lib.baseboard_fab2(sch_1):page106_i40@mstr_discrete.cap~
(chips)',
 P_PATH='@baseboard_fab2_lib.baseboard_fab2(sch_1):page106_i40@mstr_discrete.cap~
(chips)',
 PATH='I40',
 DRAWING='@BASEBOARD_FAB2_LIB.BASEBOARD_FAB2(SCH_1):PAGE106',
 TOLERANCE='10%',
 MATERIAL='X7R',
 PHYS_PAGE='106',
 XY='(-4500,2650)',
 ROT='2',
 VER='1',
 VALUE='0.22UF',
 PACK_TYPE='0402',
 PART_NUMBER='A36096-155',
 LOCATION='C1R6',
 ROOM='PCIE_STEERING',
 CDS_LIB='mstr_discrete',
 CDS_PART_NAME='CAP_0402-0.22UF,16V,10%,X7R,A3A',
 VOLTAGE='16V',
 PRIM_FILE='./archive_libs/mstr_discrete/cap/chips/chips.prt';

PART_NAME
 C1R7 'CAP_0402-0.22UF,16V,10%,X7R,A3A':
 ROOM='PCIE_STEERING';

SECTION_NUMBER 1
 '@BASEBOARD_FAB2_LIB.BASEBOARD_FAB2(SCH_1):PAGE106_I70@MSTR_DISCRETE.CAP(CHIPS)':
 C_PATH='@baseboard_fab2_lib.baseboard_fab2(sch_1):page106_i70@mstr_discrete.cap~
(chips)',
 P_PATH='@baseboard_fab2_lib.baseboard_fab2(sch_1):page106_i70@mstr_discrete.cap~
(chips)',
 PATH='I70',
 DRAWING='@BASEBOARD_FAB2_LIB.BASEBOARD_FAB2(SCH_1):PAGE106',
 TOLERANCE='10%',
 MATERIAL='X7R',
 BOM_COST='IO_SLOT',
 PHYS_PAGE='106',
 XY='(-4675,1350)',
 ROT='2',
 VER='1',
 VALUE='0.22UF',
 PACK_TYPE='0402',
 PART_NUMBER='A36096-155',
 LOCATION='C1R7',
 ROOM='PCIE_STEERING',
 CDS_LIB='mstr_discrete',
 CDS_PART_NAME='CAP_0402-0.22UF,16V,10%,X7R,A3A',
 VOLTAGE='16V',
 PRIM_FILE='./archive_libs/mstr_discrete/cap/chips/chips.prt';

PART_NAME
 C1R8 'CAP_0402-0.22UF,16V,10%,X7R,A3A':
 ROOM='PCIE_STEERING';

SECTION_NUMBER 1
 '@BASEBOARD_FAB2_LIB.BASEBOARD_FAB2(SCH_1):PAGE106_I55@MSTR_DISCRETE.CAP(CHIPS)':
 C_PATH='@baseboard_fab2_lib.baseboard_fab2(sch_1):page106_i55@mstr_discrete.cap~
(chips)',
 P_PATH='@baseboard_fab2_lib.baseboard_fab2(sch_1):page106_i55@mstr_discrete.cap~
(chips)',
 PATH='I55',
 DRAWING='@BASEBOARD_FAB2_LIB.BASEBOARD_FAB2(SCH_1):PAGE106',
 TOLERANCE='10%',
 MATERIAL='X7R',
 PHYS_PAGE='106',
 XY='(-4700,2350)',
 ROT='2',
 VER='1',
 VALUE='0.22UF',
 PACK_TYPE='0402',
 PART_NUMBER='A36096-155',
 LOCATION='C1R8',
 ROOM='PCIE_STEERING',
 CDS_LIB='mstr_discrete',
 CDS_PART_NAME='CAP_0402-0.22UF,16V,10%,X7R,A3A',
 VOLTAGE='16V',
 PRIM_FILE='./archive_libs/mstr_discrete/cap/chips/chips.prt';

PART_NAME
 C1R9 'CAP_0402-0.22UF,16V,10%,X7R,A3A':
 ROOM='PCIE_STEERING';

SECTION_NUMBER 1
 '@BASEBOARD_FAB2_LIB.BASEBOARD_FAB2(SCH_1):PAGE106_I134@MSTR_DISCRETE.CAP(CHIPS)':
 C_PATH='@baseboard_fab2_lib.baseboard_fab2(sch_1):page106_i134@mstr_discrete.ca~
p(chips)',
 P_PATH='@baseboard_fab2_lib.baseboard_fab2(sch_1):page106_i134@mstr_discrete.ca~
p(chips)',
 PATH='I134',
 DRAWING='@BASEBOARD_FAB2_LIB.BASEBOARD_FAB2(SCH_1):PAGE106',
 TOLERANCE='10%',
 MATERIAL='X7R',
 BOM_COST='IO_SLOT',
 PHYS_PAGE='106',
 XY='(-4875,1650)',
 ROT='2',
 VER='1',
 VALUE='0.22UF',
 PACK_TYPE='0402',
 PART_NUMBER='A36096-155',
 LOCATION='C1R9',
 ROOM='PCIE_STEERING',
 CDS_LIB='mstr_discrete',
 CDS_PART_NAME='CAP_0402-0.22UF,16V,10%,X7R,A3A',
 VOLTAGE='16V',
 PRIM_FILE='./archive_libs/mstr_discrete/cap/chips/chips.prt';

PART_NAME
 C1R10 'CAP_0402-0.22UF,16V,10%,X7R,A3A':
 ROOM='PCIE_STEERING';

SECTION_NUMBER 1
 '@BASEBOARD_FAB2_LIB.BASEBOARD_FAB2(SCH_1):PAGE106_I128@MSTR_DISCRETE.CAP(CHIPS)':
 C_PATH='@baseboard_fab2_lib.baseboard_fab2(sch_1):page106_i128@mstr_discrete.ca~
p(chips)',
 P_PATH='@baseboard_fab2_lib.baseboard_fab2(sch_1):page106_i128@mstr_discrete.ca~
p(chips)',
 PATH='I128',
 DRAWING='@BASEBOARD_FAB2_LIB.BASEBOARD_FAB2(SCH_1):PAGE106',
 TOLERANCE='10%',
 MATERIAL='X7R',
 BOM_COST='IO_SLOT',
 PHYS_PAGE='106',
 XY='(-4900,2650)',
 ROT='2',
 VER='1',
 VALUE='0.22UF',
 PACK_TYPE='0402',
 PART_NUMBER='A36096-155',
 LOCATION='C1R10',
 ROOM='PCIE_STEERING',
 CDS_LIB='mstr_discrete',
 CDS_PART_NAME='CAP_0402-0.22UF,16V,10%,X7R,A3A',
 VOLTAGE='16V',
 PRIM_FILE='./archive_libs/mstr_discrete/cap/chips/chips.prt';

PART_NAME
 C1R13 'CAP_0603-10UF,6.3V,20%,X6S,E15A':
 GROUP='NI_I210&RJ45',
 ROOM='NIC_SPRV';

SECTION_NUMBER 1
 '@BASEBOARD_FAB2_LIB.BASEBOARD_FAB2(SCH_1):PAGE139_I142@MSTR_DISCRETE.CAP(CHIPS)':
 C_PATH='@baseboard_fab2_lib.baseboard_fab2(sch_1):page139_i142@mstr_discrete.ca~
p(chips)',
 P_PATH='@baseboard_fab2_lib.baseboard_fab2(sch_1):page139_i142@mstr_discrete.ca~
p(chips)',
 PATH='I142',
 DRAWING='@BASEBOARD_FAB2_LIB.BASEBOARD_FAB2(SCH_1):PAGE139',
 TOLERANCE='20%',
 MATERIAL='X6S',
 BOM_COST='NT_GBE_BASE',
 PHYS_PAGE='139',
 XY='(-5450,850)',
 ROT='0',
 VER='1',
 VALUE='10UF',
 PACK_TYPE='0603',
 PART_NUMBER='E15431-002',
 LOCATION='C1R13',
 ROOM='NIC_SPRV',
 GROUP='NI_I210&RJ45',
 CDS_LIB='mstr_discrete',
 CDS_PART_NAME='CAP_0603-10UF,6.3V,20%,X6S,E15A',
 VOLTAGE='6.3V',
 PRIM_FILE='./archive_libs/mstr_discrete/cap/chips/chips.prt';

PART_NAME
 C1R14 'CAP_A_0402V-0.1UF,16V,10%,X7R,A':
 GROUP='NI_I210&RJ45',
 ROOM='NIC_SPRV';

SECTION_NUMBER 1
 '@BASEBOARD_FAB2_LIB.BASEBOARD_FAB2(SCH_1):PAGE139_I145@DEV_DISCRETE.CAP_A(CHIPS)':
 C_PATH='@baseboard_fab2_lib.baseboard_fab2(sch_1):page139_i145@dev_discrete.cap~
_a(chips)',
 P_PATH='@baseboard_fab2_lib.baseboard_fab2(sch_1):page139_i145@dev_discrete.cap~
_a(chips)',
 PATH='I145',
 DRAWING='@BASEBOARD_FAB2_LIB.BASEBOARD_FAB2(SCH_1):PAGE139',
 TOLERANCE='10%',
 MATERIAL='X7R',
 BOM_COST='NT_GBE_BASE',
 PHYS_PAGE='139',
 XY='(-4700,850)',
 ROT='0',
 VER='1',
 VALUE='0.1UF',
 PACK_TYPE='0402V',
 PART_NUMBER='A36096-030',
 LOCATION='C1R14',
 ROOM='NIC_SPRV',
 GROUP='NI_I210&RJ45',
 CDS_LIB='dev_discrete',
 CDS_PART_NAME='CAP_A_0402V-0.1UF,16V,10%,X7R,A',
 VOLTAGE='16V',
 PRIM_FILE='./archive_libs/discrete/cap_a/chips/chips.prt';

PART_NAME
 C1R15 'CAP_A_0402V-0.1UF,16V,10%,X7R,A':
 GROUP='NI_I210&RJ45',
 ROOM='NIC_SPRV';

SECTION_NUMBER 1
 '@BASEBOARD_FAB2_LIB.BASEBOARD_FAB2(SCH_1):PAGE139_I160@DEV_DISCRETE.CAP_A(CHIPS)':
 C_PATH='@baseboard_fab2_lib.baseboard_fab2(sch_1):page139_i160@dev_discrete.cap~
_a(chips)',
 P_PATH='@baseboard_fab2_lib.baseboard_fab2(sch_1):page139_i160@dev_discrete.cap~
_a(chips)',
 PATH='I160',
 DRAWING='@BASEBOARD_FAB2_LIB.BASEBOARD_FAB2(SCH_1):PAGE139',
 TOLERANCE='10%',
 MATERIAL='X7R',
 BOM_COST='NT_GBE_BASE',
 PHYS_PAGE='139',
 XY='(-1100,875)',
 ROT='0',
 VER='1',
 VALUE='0.1UF',
 PACK_TYPE='0402V',
 PART_NUMBER='A36096-030',
 LOCATION='C1R15',
 ROOM='NIC_SPRV',
 GROUP='NI_I210&RJ45',
 CDS_LIB='dev_discrete',
 CDS_PART_NAME='CAP_A_0402V-0.1UF,16V,10%,X7R,A',
 VOLTAGE='16V',
 PRIM_FILE='./archive_libs/discrete/cap_a/chips/chips.prt';

PART_NAME
 C1R16 'CAP_0603-10UF,6.3V,20%,X6S,E15A':
 GROUP='NI_I210&RJ45',
 ROOM='NIC_SPRV';

SECTION_NUMBER 1
 '@BASEBOARD_FAB2_LIB.BASEBOARD_FAB2(SCH_1):PAGE139_I161@MSTR_DISCRETE.CAP(CHIPS)':
 C_PATH='@baseboard_fab2_lib.baseboard_fab2(sch_1):page139_i161@mstr_discrete.ca~
p(chips)',
 P_PATH='@baseboard_fab2_lib.baseboard_fab2(sch_1):page139_i161@mstr_discrete.ca~
p(chips)',
 PATH='I161',
 DRAWING='@BASEBOARD_FAB2_LIB.BASEBOARD_FAB2(SCH_1):PAGE139',
 TOLERANCE='20%',
 MATERIAL='X6S',
 BOM_COST='NT_GBE_BASE',
 PHYS_PAGE='139',
 XY='(-1350,875)',
 ROT='0',
 VER='1',
 VALUE='10UF',
 PACK_TYPE='0603',
 PART_NUMBER='E15431-002',
 LOCATION='C1R16',
 ROOM='NIC_SPRV',
 GROUP='NI_I210&RJ45',
 CDS_LIB='mstr_discrete',
 CDS_PART_NAME='CAP_0603-10UF,6.3V,20%,X6S,E15A',
 VOLTAGE='6.3V',
 PRIM_FILE='./archive_libs/mstr_discrete/cap/chips/chips.prt';

PART_NAME
 C1R17 'CAP_0603-10UF,6.3V,20%,X6S,E15A':
 GROUP='NI_I210&RJ45',
 ROOM='NIC_SPRV';

SECTION_NUMBER 1
 '@BASEBOARD_FAB2_LIB.BASEBOARD_FAB2(SCH_1):PAGE139_I153@MSTR_DISCRETE.CAP(CHIPS)':
 C_PATH='@baseboard_fab2_lib.baseboard_fab2(sch_1):page139_i153@mstr_discrete.ca~
p(chips)',
 P_PATH='@baseboard_fab2_lib.baseboard_fab2(sch_1):page139_i153@mstr_discrete.ca~
p(chips)',
 PATH='I153',
 DRAWING='@BASEBOARD_FAB2_LIB.BASEBOARD_FAB2(SCH_1):PAGE139',
 TOLERANCE='20%',
 MATERIAL='X6S',
 BOM_COST='NT_GBE_BASE',
 PHYS_PAGE='139',
 XY='(-3325,875)',
 ROT='0',
 VER='1',
 VALUE='10UF',
 PACK_TYPE='0603',
 PART_NUMBER='E15431-002',
 LOCATION='C1R17',
 ROOM='NIC_SPRV',
 GROUP='NI_I210&RJ45',
 CDS_LIB='mstr_discrete',
 CDS_PART_NAME='CAP_0603-10UF,6.3V,20%,X6S,E15A',
 VOLTAGE='6.3V',
 PRIM_FILE='./archive_libs/mstr_discrete/cap/chips/chips.prt';

PART_NAME
 C1R18 'CAP_A_0402V-0.1UF,16V,10%,X7R,A':
 GROUP='NI_I210&RJ45',
 ROOM='NIC_SPRV';

SECTION_NUMBER 1
 '@BASEBOARD_FAB2_LIB.BASEBOARD_FAB2(SCH_1):PAGE139_I157@DEV_DISCRETE.CAP_A(CHIPS)':
 C_PATH='@baseboard_fab2_lib.baseboard_fab2(sch_1):page139_i157@dev_discrete.cap~
_a(chips)',
 P_PATH='@baseboard_fab2_lib.baseboard_fab2(sch_1):page139_i157@dev_discrete.cap~
_a(chips)',
 PATH='I157',
 DRAWING='@BASEBOARD_FAB2_LIB.BASEBOARD_FAB2(SCH_1):PAGE139',
 TOLERANCE='10%',
 MATERIAL='X7R',
 BOM_COST='NT_GBE_BASE',
 PHYS_PAGE='139',
 XY='(-350,875)',
 ROT='0',
 VER='1',
 VALUE='0.1UF',
 PACK_TYPE='0402V',
 PART_NUMBER='A36096-030',
 LOCATION='C1R18',
 ROOM='NIC_SPRV',
 GROUP='NI_I210&RJ45',
 CDS_LIB='dev_discrete',
 CDS_PART_NAME='CAP_A_0402V-0.1UF,16V,10%,X7R,A',
 VOLTAGE='16V',
 PRIM_FILE='./archive_libs/discrete/cap_a/chips/chips.prt';

PART_NAME
 C1R19 'CAP_A_0402V-0.1UF,16V,10%,X7R,A':
 GROUP='NI_I210&RJ45',
 ROOM='NIC_SPRV';

SECTION_NUMBER 1
 '@BASEBOARD_FAB2_LIB.BASEBOARD_FAB2(SCH_1):PAGE139_I151@DEV_DISCRETE.CAP_A(CHIPS)':
 C_PATH='@baseboard_fab2_lib.baseboard_fab2(sch_1):page139_i151@dev_discrete.cap~
_a(chips)',
 P_PATH='@baseboard_fab2_lib.baseboard_fab2(sch_1):page139_i151@dev_discrete.cap~
_a(chips)',
 PATH='I151',
 DRAWING='@BASEBOARD_FAB2_LIB.BASEBOARD_FAB2(SCH_1):PAGE139',
 TOLERANCE='10%',
 MATERIAL='X7R',
 BOM_COST='NT_GBE_BASE',
 PHYS_PAGE='139',
 XY='(-2825,875)',
 ROT='0',
 VER='1',
 VALUE='0.1UF',
 PACK_TYPE='0402V',
 PART_NUMBER='A36096-030',
 LOCATION='C1R19',
 ROOM='NIC_SPRV',
 GROUP='NI_I210&RJ45',
 CDS_LIB='dev_discrete',
 CDS_PART_NAME='CAP_A_0402V-0.1UF,16V,10%,X7R,A',
 VOLTAGE='16V',
 PRIM_FILE='./archive_libs/discrete/cap_a/chips/chips.prt';

PART_NAME
 C1R20 'CAP_A_0402V-0.1UF,16V,10%,X7R,A':
 GROUP='NI_I210&RJ45',
 ROOM='NIC_SPRV';

SECTION_NUMBER 1
 '@BASEBOARD_FAB2_LIB.BASEBOARD_FAB2(SCH_1):PAGE139_I143@DEV_DISCRETE.CAP_A(CHIPS)':
 C_PATH='@baseboard_fab2_lib.baseboard_fab2(sch_1):page139_i143@dev_discrete.cap~
_a(chips)',
 P_PATH='@baseboard_fab2_lib.baseboard_fab2(sch_1):page139_i143@dev_discrete.cap~
_a(chips)',
 PATH='I143',
 DRAWING='@BASEBOARD_FAB2_LIB.BASEBOARD_FAB2(SCH_1):PAGE139',
 TOLERANCE='10%',
 MATERIAL='X7R',
 BOM_COST='NT_GBE_BASE',
 PHYS_PAGE='139',
 XY='(-5200,850)',
 ROT='0',
 VER='1',
 VALUE='0.1UF',
 PACK_TYPE='0402V',
 PART_NUMBER='A36096-030',
 LOCATION='C1R20',
 ROOM='NIC_SPRV',
 GROUP='NI_I210&RJ45',
 CDS_LIB='dev_discrete',
 CDS_PART_NAME='CAP_A_0402V-0.1UF,16V,10%,X7R,A',
 VOLTAGE='16V',
 PRIM_FILE='./archive_libs/discrete/cap_a/chips/chips.prt';

PART_NAME
 C1R21 'CAP_A_0402V-0.1UF,16V,10%,X7R,A':
 GROUP='NI_I210&RJ45',
 ROOM='NIC_SPRV';

SECTION_NUMBER 1
 '@BASEBOARD_FAB2_LIB.BASEBOARD_FAB2(SCH_1):PAGE139_I146@DEV_DISCRETE.CAP_A(CHIPS)':
 C_PATH='@baseboard_fab2_lib.baseboard_fab2(sch_1):page139_i146@dev_discrete.cap~
_a(chips)',
 P_PATH='@baseboard_fab2_lib.baseboard_fab2(sch_1):page139_i146@dev_discrete.cap~
_a(chips)',
 PATH='I146',
 DRAWING='@BASEBOARD_FAB2_LIB.BASEBOARD_FAB2(SCH_1):PAGE139',
 TOLERANCE='10%',
 MATERIAL='X7R',
 BOM_COST='NT_GBE_BASE',
 PHYS_PAGE='139',
 XY='(-4450,850)',
 ROT='0',
 VER='1',
 VALUE='0.1UF',
 PACK_TYPE='0402V',
 PART_NUMBER='A36096-030',
 LOCATION='C1R21',
 ROOM='NIC_SPRV',
 GROUP='NI_I210&RJ45',
 CDS_LIB='dev_discrete',
 CDS_PART_NAME='CAP_A_0402V-0.1UF,16V,10%,X7R,A',
 VOLTAGE='16V',
 PRIM_FILE='./archive_libs/discrete/cap_a/chips/chips.prt';

PART_NAME
 C1R22 'CAP_0603-10UF,6.3V,20%,X6S,E15A':
 GROUP='NI_I210&RJ45',
 ROOM='NIC_SPRV';

SECTION_NUMBER 1
 '@BASEBOARD_FAB2_LIB.BASEBOARD_FAB2(SCH_1):PAGE139_I136@MSTR_DISCRETE.CAP(CHIPS)':
 C_PATH='@baseboard_fab2_lib.baseboard_fab2(sch_1):page139_i136@mstr_discrete.ca~
p(chips)',
 P_PATH='@baseboard_fab2_lib.baseboard_fab2(sch_1):page139_i136@mstr_discrete.ca~
p(chips)',
 PATH='I136',
 DRAWING='@BASEBOARD_FAB2_LIB.BASEBOARD_FAB2(SCH_1):PAGE139',
 TOLERANCE='20%',
 SEC_TYPE='0603',
 MATERIAL='X6S',
 BOM_COST='NT_GBE_BASE',
 PHYS_PAGE='139',
 XY='(-6950,3750)',
 ROT='0',
 VER='1',
 VALUE='10UF',
 PACK_TYPE='0603',
 PART_NUMBER='E15431-002',
 LOCATION='C1R22',
 ROOM='NIC_SPRV',
 GROUP='NI_I210&RJ45',
 SEC='1',
 CDS_LIB='mstr_discrete',
 CDS_PART_NAME='CAP_0603-10UF,6.3V,20%,X6S,E15A',
 VOLTAGE='6.3V',
 PRIM_FILE='./archive_libs/mstr_discrete/cap/chips/chips.prt';

PART_NAME
 C1R23 'CAPP_3018-68UF,16V,20%,TANT,72A':;

SECTION_NUMBER 1
 '@BASEBOARD_FAB2_LIB.BASEBOARD_FAB2(SCH_1):PAGE195_I101@MSTR_DISCRETE.CAPP(CHIPS)':
 C_PATH='@baseboard_fab2_lib.baseboard_fab2(sch_1):page195_i101@mstr_discrete.ca~
pp(chips)',
 P_PATH='@baseboard_fab2_lib.baseboard_fab2(sch_1):page195_i101@mstr_discrete.ca~
pp(chips)',
 PATH='I101',
 DRAWING='@BASEBOARD_FAB2_LIB.BASEBOARD_FAB2(SCH_1):PAGE195',
 TOLERANCE='20%',
 SEC_TYPE='3018',
 MATERIAL='TANT',
 PHYS_PAGE='195',
 XY='(-6175,775)',
 ROT='0',
 VER='1',
 VALUE='68UF',
 PACK_TYPE='3018',
 PART_NUMBER='724613-112',
 LOCATION='C1R23',
 SEC='1',
 CDS_LIB='mstr_discrete',
 CDS_PART_NAME='CAPP_3018-68UF,16V,20%,TANT,72A',
 VOLTAGE='16V',
 PRIM_FILE='./archive_libs/mstr_discrete/capp/chips/chips.prt';

PART_NAME
 C1R24 'CAP_A_0402V-0.1UF,16V,10%,X7R,A':
 GROUP='NI_I210&RJ45',
 ROOM='NIC_SPRV';

SECTION_NUMBER 1
 '@BASEBOARD_FAB2_LIB.BASEBOARD_FAB2(SCH_1):PAGE139_I159@DEV_DISCRETE.CAP_A(CHIPS)':
 C_PATH='@baseboard_fab2_lib.baseboard_fab2(sch_1):page139_i159@dev_discrete.cap~
_a(chips)',
 P_PATH='@baseboard_fab2_lib.baseboard_fab2(sch_1):page139_i159@dev_discrete.cap~
_a(chips)',
 PATH='I159',
 DRAWING='@BASEBOARD_FAB2_LIB.BASEBOARD_FAB2(SCH_1):PAGE139',
 TOLERANCE='10%',
 MATERIAL='X7R',
 BOM_COST='NT_GBE_BASE',
 PHYS_PAGE='139',
 XY='(-850,875)',
 ROT='0',
 VER='1',
 VALUE='0.1UF',
 PACK_TYPE='0402V',
 PART_NUMBER='A36096-030',
 LOCATION='C1R24',
 ROOM='NIC_SPRV',
 GROUP='NI_I210&RJ45',
 CDS_LIB='dev_discrete',
 CDS_PART_NAME='CAP_A_0402V-0.1UF,16V,10%,X7R,A',
 VOLTAGE='16V',
 PRIM_FILE='./archive_libs/discrete/cap_a/chips/chips.prt';

PART_NAME
 C1R25 'CAP_A_0402V-0.1UF,16V,10%,X7R,A':
 GROUP='NI_I210&RJ45',
 ROOM='NIC_SPRV';

SECTION_NUMBER 1
 '@BASEBOARD_FAB2_LIB.BASEBOARD_FAB2(SCH_1):PAGE140_I3@DEV_DISCRETE.CAP_A(CHIPS)':
 C_PATH='@baseboard_fab2_lib.baseboard_fab2(sch_1):page140_i3@dev_discrete.cap_a~
(chips)',
 P_PATH='@baseboard_fab2_lib.baseboard_fab2(sch_1):page140_i3@dev_discrete.cap_a~
(chips)',
 PATH='I3',
 DRAWING='@BASEBOARD_FAB2_LIB.BASEBOARD_FAB2(SCH_1):PAGE140',
 TOLERANCE='10%',
 SEC_TYPE='0402V',
 MATERIAL='X7R',
 BOM_COST='NT_GBE_BASE',
 PHYS_PAGE='140',
 XY='(-2475,3375)',
 ROT='0',
 VER='1',
 VALUE='0.1UF',
 PACK_TYPE='0402V',
 PART_NUMBER='A36096-030',
 LOCATION='C1R25',
 ROOM='NIC_SPRV',
 GROUP='NI_I210&RJ45',
 SEC='1',
 CDS_LIB='dev_discrete',
 CDS_PART_NAME='CAP_A_0402V-0.1UF,16V,10%,X7R,A',
 VOLTAGE='16V',
 PRIM_FILE='./archive_libs/discrete/cap_a/chips/chips.prt';

PART_NAME
 C1R26 'CAP_A_0402V-0.1UF,16V,10%,X7R,A':
 GROUP='NI_I210&RJ45',
 ROOM='NIC_SPRV';

SECTION_NUMBER 1
 '@BASEBOARD_FAB2_LIB.BASEBOARD_FAB2(SCH_1):PAGE139_I149@DEV_DISCRETE.CAP_A(CHIPS)':
 C_PATH='@baseboard_fab2_lib.baseboard_fab2(sch_1):page139_i149@dev_discrete.cap~
_a(chips)',
 P_PATH='@baseboard_fab2_lib.baseboard_fab2(sch_1):page139_i149@dev_discrete.cap~
_a(chips)',
 PATH='I149',
 DRAWING='@BASEBOARD_FAB2_LIB.BASEBOARD_FAB2(SCH_1):PAGE139',
 TOLERANCE='10%',
 MATERIAL='X7R',
 BOM_COST='NT_GBE_BASE',
 PHYS_PAGE='139',
 XY='(-2325,875)',
 ROT='0',
 VER='1',
 VALUE='0.1UF',
 PACK_TYPE='0402V',
 PART_NUMBER='A36096-030',
 LOCATION='C1R26',
 ROOM='NIC_SPRV',
 GROUP='NI_I210&RJ45',
 CDS_LIB='dev_discrete',
 CDS_PART_NAME='CAP_A_0402V-0.1UF,16V,10%,X7R,A',
 VOLTAGE='16V',
 PRIM_FILE='./archive_libs/discrete/cap_a/chips/chips.prt';

PART_NAME
 C1R27 'CAP_A_0402V-0.1UF,16V,10%,X7R,A':
 ROOM='FAST_PROCHOT';

SECTION_NUMBER 1
 '@BASEBOARD_FAB2_LIB.BASEBOARD_FAB2(SCH_1):PAGE170_I30@DEV_DISCRETE.CAP_A(CHIPS)':
 C_PATH='@baseboard_fab2_lib.baseboard_fab2(sch_1):page170_i30@dev_discrete.cap_~
a(chips)',
 P_PATH='@baseboard_fab2_lib.baseboard_fab2(sch_1):page170_i30@dev_discrete.cap_~
a(chips)',
 PATH='I30',
 DRAWING='@BASEBOARD_FAB2_LIB.BASEBOARD_FAB2(SCH_1):PAGE170',
 TOLERANCE='10%',
 SEC_TYPE='0402V',
 MATERIAL='X7R',
 BOM_COST='FAST_PROCHOT',
 PHYS_PAGE='170',
 XY='(-5150,1325)',
 ROT='0',
 VER='1',
 VALUE='0.1UF',
 PACK_TYPE='0402V',
 PART_NUMBER='A36096-030',
 LOCATION='C1R27',
 ROOM='FAST_PROCHOT',
 SEC='1',
 CDS_LIB='dev_discrete',
 CDS_PART_NAME='CAP_A_0402V-0.1UF,16V,10%,X7R,A',
 VOLTAGE='16V',
 PRIM_FILE='./archive_libs/discrete/cap_a/chips/chips.prt';

PART_NAME
 C1R28 'CAP_A_0402V-0.1UF,16V,10%,X7R,A':
 ROOM='FAST_PROCHOT';

SECTION_NUMBER 1
 '@BASEBOARD_FAB2_LIB.BASEBOARD_FAB2(SCH_1):PAGE170_I49@DEV_DISCRETE.CAP_A(CHIPS)':
 C_PATH='@baseboard_fab2_lib.baseboard_fab2(sch_1):page170_i49@dev_discrete.cap_~
a(chips)',
 P_PATH='@baseboard_fab2_lib.baseboard_fab2(sch_1):page170_i49@dev_discrete.cap_~
a(chips)',
 PATH='I49',
 DRAWING='@BASEBOARD_FAB2_LIB.BASEBOARD_FAB2(SCH_1):PAGE170',
 TOLERANCE='10%',
 SEC_TYPE='0402V',
 MATERIAL='X7R',
 BOM_COST='FAST_PROCHOT',
 PHYS_PAGE='170',
 XY='(-1600,1700)',
 ROT='0',
 VER='1',
 VALUE='0.1UF',
 PACK_TYPE='0402V',
 PART_NUMBER='A36096-030',
 LOCATION='C1R28',
 ROOM='FAST_PROCHOT',
 SEC='1',
 CDS_LIB='dev_discrete',
 CDS_PART_NAME='CAP_A_0402V-0.1UF,16V,10%,X7R,A',
 VOLTAGE='16V',
 PRIM_FILE='./archive_libs/discrete/cap_a/chips/chips.prt';

PART_NAME
 C1R29 'CAP_A_0402V-0.1UF,16V,10%,X7R,A':
 GROUP='NI_I210&RJ45',
 ROOM='NIC_SPRV';

SECTION_NUMBER 1
 '@BASEBOARD_FAB2_LIB.BASEBOARD_FAB2(SCH_1):PAGE139_I150@DEV_DISCRETE.CAP_A(CHIPS)':
 C_PATH='@baseboard_fab2_lib.baseboard_fab2(sch_1):page139_i150@dev_discrete.cap~
_a(chips)',
 P_PATH='@baseboard_fab2_lib.baseboard_fab2(sch_1):page139_i150@dev_discrete.cap~
_a(chips)',
 PATH='I150',
 DRAWING='@BASEBOARD_FAB2_LIB.BASEBOARD_FAB2(SCH_1):PAGE139',
 TOLERANCE='10%',
 MATERIAL='X7R',
 BOM_COST='NT_GBE_BASE',
 PHYS_PAGE='139',
 XY='(-2575,875)',
 ROT='0',
 VER='1',
 VALUE='0.1UF',
 PACK_TYPE='0402V',
 PART_NUMBER='A36096-030',
 LOCATION='C1R29',
 ROOM='NIC_SPRV',
 GROUP='NI_I210&RJ45',
 CDS_LIB='dev_discrete',
 CDS_PART_NAME='CAP_A_0402V-0.1UF,16V,10%,X7R,A',
 VOLTAGE='16V',
 PRIM_FILE='./archive_libs/discrete/cap_a/chips/chips.prt';

PART_NAME
 C1R30 'CAP_0603-10UF,6.3V,20%,X6S,E15A':
 GROUP='NI_I210&RJ45',
 ROOM='NIC_SPRV';

SECTION_NUMBER 1
 '@BASEBOARD_FAB2_LIB.BASEBOARD_FAB2(SCH_1):PAGE139_I135@MSTR_DISCRETE.CAP(CHIPS)':
 C_PATH='@baseboard_fab2_lib.baseboard_fab2(sch_1):page139_i135@mstr_discrete.ca~
p(chips)',
 P_PATH='@baseboard_fab2_lib.baseboard_fab2(sch_1):page139_i135@mstr_discrete.ca~
p(chips)',
 PATH='I135',
 DRAWING='@BASEBOARD_FAB2_LIB.BASEBOARD_FAB2(SCH_1):PAGE139',
 TOLERANCE='20%',
 SEC_TYPE='0603',
 MATERIAL='X6S',
 BOM_COST='NT_GBE_BASE',
 PHYS_PAGE='139',
 XY='(-6375,3975)',
 ROT='0',
 VER='1',
 VALUE='10UF',
 PACK_TYPE='0603',
 PART_NUMBER='E15431-002',
 LOCATION='C1R30',
 ROOM='NIC_SPRV',
 GROUP='NI_I210&RJ45',
 SEC='1',
 CDS_LIB='mstr_discrete',
 CDS_PART_NAME='CAP_0603-10UF,6.3V,20%,X6S,E15A',
 VOLTAGE='6.3V',
 PRIM_FILE='./archive_libs/mstr_discrete/cap/chips/chips.prt';

PART_NAME
 C1R31 'CAP_A_0402V-0.1UF,16V,10%,X7R,A':
 GROUP='NI_I210&RJ45',
 ROOM='NIC_SPRV';

SECTION_NUMBER 1
 '@BASEBOARD_FAB2_LIB.BASEBOARD_FAB2(SCH_1):PAGE139_I152@DEV_DISCRETE.CAP_A(CHIPS)':
 C_PATH='@baseboard_fab2_lib.baseboard_fab2(sch_1):page139_i152@dev_discrete.cap~
_a(chips)',
 P_PATH='@baseboard_fab2_lib.baseboard_fab2(sch_1):page139_i152@dev_discrete.cap~
_a(chips)',
 PATH='I152',
 DRAWING='@BASEBOARD_FAB2_LIB.BASEBOARD_FAB2(SCH_1):PAGE139',
 TOLERANCE='10%',
 MATERIAL='X7R',
 BOM_COST='NT_GBE_BASE',
 PHYS_PAGE='139',
 XY='(-3075,875)',
 ROT='0',
 VER='1',
 VALUE='0.1UF',
 PACK_TYPE='0402V',
 PART_NUMBER='A36096-030',
 LOCATION='C1R31',
 ROOM='NIC_SPRV',
 GROUP='NI_I210&RJ45',
 CDS_LIB='dev_discrete',
 CDS_PART_NAME='CAP_A_0402V-0.1UF,16V,10%,X7R,A',
 VOLTAGE='16V',
 PRIM_FILE='./archive_libs/discrete/cap_a/chips/chips.prt';

PART_NAME
 C1T3 'CAP_A_0402V-0.1UF,16V,10%,X7R,A':
 GROUP='NI_I210&RJ45',
 ROOM='NIC_SPRV';

SECTION_NUMBER 1
 '@BASEBOARD_FAB2_LIB.BASEBOARD_FAB2(SCH_1):PAGE139_I144@DEV_DISCRETE.CAP_A(CHIPS)':
 C_PATH='@baseboard_fab2_lib.baseboard_fab2(sch_1):page139_i144@dev_discrete.cap~
_a(chips)',
 P_PATH='@baseboard_fab2_lib.baseboard_fab2(sch_1):page139_i144@dev_discrete.cap~
_a(chips)',
 PATH='I144',
 DRAWING='@BASEBOARD_FAB2_LIB.BASEBOARD_FAB2(SCH_1):PAGE139',
 TOLERANCE='10%',
 MATERIAL='X7R',
 BOM_COST='NT_GBE_BASE',
 PHYS_PAGE='139',
 XY='(-4950,850)',
 ROT='0',
 VER='1',
 VALUE='0.1UF',
 PACK_TYPE='0402V',
 PART_NUMBER='A36096-030',
 LOCATION='C1T3',
 ROOM='NIC_SPRV',
 GROUP='NI_I210&RJ45',
 CDS_LIB='dev_discrete',
 CDS_PART_NAME='CAP_A_0402V-0.1UF,16V,10%,X7R,A',
 VOLTAGE='16V',
 PRIM_FILE='./archive_libs/discrete/cap_a/chips/chips.prt';

PART_NAME
 C1T4 'CAP_0603-10UF,6.3V,20%,X6S,E15A':
 GROUP='NI_I210&RJ45',
 ROOM='NIC_SPRV';

SECTION_NUMBER 1
 '@BASEBOARD_FAB2_LIB.BASEBOARD_FAB2(SCH_1):PAGE139_I134@MSTR_DISCRETE.CAP(CHIPS)':
 C_PATH='@baseboard_fab2_lib.baseboard_fab2(sch_1):page139_i134@mstr_discrete.ca~
p(chips)',
 P_PATH='@baseboard_fab2_lib.baseboard_fab2(sch_1):page139_i134@mstr_discrete.ca~
p(chips)',
 PATH='I134',
 DRAWING='@BASEBOARD_FAB2_LIB.BASEBOARD_FAB2(SCH_1):PAGE139',
 TOLERANCE='20%',
 SEC_TYPE='0603',
 MATERIAL='X6S',
 BOM_COST='NT_GBE_BASE',
 PHYS_PAGE='139',
 XY='(-5975,4275)',
 ROT='0',
 VER='1',
 VALUE='10UF',
 PACK_TYPE='0603',
 PART_NUMBER='E15431-002',
 LOCATION='C1T4',
 ROOM='NIC_SPRV',
 GROUP='NI_I210&RJ45',
 SEC='1',
 CDS_LIB='mstr_discrete',
 CDS_PART_NAME='CAP_0603-10UF,6.3V,20%,X6S,E15A',
 VOLTAGE='6.3V',
 PRIM_FILE='./archive_libs/mstr_discrete/cap/chips/chips.prt';

PART_NAME
 C1T5 'CAP_A_0402V-0.1UF,16V,10%,X7R,A':
 GROUP='NI_I210&RJ45',
 ROOM='NIC_SPRV';

SECTION_NUMBER 1
 '@BASEBOARD_FAB2_LIB.BASEBOARD_FAB2(SCH_1):PAGE139_I158@DEV_DISCRETE.CAP_A(CHIPS)':
 C_PATH='@baseboard_fab2_lib.baseboard_fab2(sch_1):page139_i158@dev_discrete.cap~
_a(chips)',
 P_PATH='@baseboard_fab2_lib.baseboard_fab2(sch_1):page139_i158@dev_discrete.cap~
_a(chips)',
 PATH='I158',
 DRAWING='@BASEBOARD_FAB2_LIB.BASEBOARD_FAB2(SCH_1):PAGE139',
 TOLERANCE='10%',
 MATERIAL='X7R',
 BOM_COST='NT_GBE_BASE',
 PHYS_PAGE='139',
 XY='(-600,875)',
 ROT='0',
 VER='1',
 VALUE='0.1UF',
 PACK_TYPE='0402V',
 PART_NUMBER='A36096-030',
 LOCATION='C1T5',
 ROOM='NIC_SPRV',
 GROUP='NI_I210&RJ45',
 CDS_LIB='dev_discrete',
 CDS_PART_NAME='CAP_A_0402V-0.1UF,16V,10%,X7R,A',
 VOLTAGE='16V',
 PRIM_FILE='./archive_libs/discrete/cap_a/chips/chips.prt';

PART_NAME
 C1T7 'CAP_0603-10UF,6.3V,20%,X6S,E15A':
 ROOM='P1V538_BMC_STBY_VR';

SECTION_NUMBER 1
 '@BASEBOARD_FAB2_LIB.BASEBOARD_FAB2(SCH_1):PAGE239_I22@MSTR_DISCRETE.CAP(CHIPS)':
 C_PATH='@baseboard_fab2_lib.baseboard_fab2(sch_1):page239_i22@mstr_discrete.cap~
(chips)',
 P_PATH='@baseboard_fab2_lib.baseboard_fab2(sch_1):page239_i22@mstr_discrete.cap~
(chips)',
 PATH='I22',
 DRAWING='@BASEBOARD_FAB2_LIB.BASEBOARD_FAB2(SCH_1):PAGE239',
 TOLERANCE='20%',
 SEC_TYPE='0603',
 MATERIAL='X6S',
 BOM_COST='P1V538_BMC_STBY_VR',
 PHYS_PAGE='239',
 XY='(5750,4150)',
 ROT='0',
 VER='1',
 VALUE='10UF',
 PACK_TYPE='0603',
 PART_NUMBER='E15431-002',
 LOCATION='C1T7',
 ROOM='P1V538_BMC_STBY_VR',
 SEC='1',
 CDS_LIB='mstr_discrete',
 CDS_PART_NAME='CAP_0603-10UF,6.3V,20%,X6S,E15A',
 VOLTAGE='6.3V',
 PRIM_FILE='./archive_libs/mstr_discrete/cap/chips/chips.prt';

PART_NAME
 C1T10 'CAP_A_0402V-0.1UF,16V,10%,X7R,A':
 ROOM='UART_MUX';

SECTION_NUMBER 1
 '@BASEBOARD_FAB2_LIB.BASEBOARD_FAB2(SCH_1):PAGE158_I70@DEV_DISCRETE.CAP_A(CHIPS)':
 C_PATH='@baseboard_fab2_lib.baseboard_fab2(sch_1):page158_i70@dev_discrete.cap_~
a(chips)',
 P_PATH='@baseboard_fab2_lib.baseboard_fab2(sch_1):page158_i70@dev_discrete.cap_~
a(chips)',
 PATH='I70',
 DRAWING='@BASEBOARD_FAB2_LIB.BASEBOARD_FAB2(SCH_1):PAGE158',
 TOLERANCE='10%',
 SEC_TYPE='0402V',
 MATERIAL='X7R',
 BOM_COST='DEBUG',
 PHYS_PAGE='158',
 XY='(-1675,2950)',
 ROT='0',
 VER='1',
 VALUE='0.1UF',
 PACK_TYPE='0402V',
 PART_NUMBER='A36096-030',
 LOCATION='C1T10',
 ROOM='UART_MUX',
 SEC='1',
 CDS_LIB='dev_discrete',
 CDS_PART_NAME='CAP_A_0402V-0.1UF,16V,10%,X7R,A',
 VOLTAGE='16V',
 PRIM_FILE='./archive_libs/discrete/cap_a/chips/chips.prt';

PART_NAME
 C1T11 'CAP_A_0402V-0.1UF,16V,10%,X7R,A':
 ROOM='UART_MUX';

SECTION_NUMBER 1
 '@BASEBOARD_FAB2_LIB.BASEBOARD_FAB2(SCH_1):PAGE158_I97@DEV_DISCRETE.CAP_A(CHIPS)':
 C_PATH='@baseboard_fab2_lib.baseboard_fab2(sch_1):page158_i97@dev_discrete.cap_~
a(chips)',
 P_PATH='@baseboard_fab2_lib.baseboard_fab2(sch_1):page158_i97@dev_discrete.cap_~
a(chips)',
 PATH='I97',
 DRAWING='@BASEBOARD_FAB2_LIB.BASEBOARD_FAB2(SCH_1):PAGE158',
 TOLERANCE='10%',
 SEC_TYPE='0402V',
 MATERIAL='X7R',
 BOM_COST='DEBUG',
 PHYS_PAGE='158',
 XY='(-3475,1200)',
 ROT='0',
 VER='1',
 VALUE='0.1UF',
 PACK_TYPE='0402V',
 PART_NUMBER='A36096-030',
 LOCATION='C1T11',
 ROOM='UART_MUX',
 SEC='1',
 CDS_LIB='dev_discrete',
 CDS_PART_NAME='CAP_A_0402V-0.1UF,16V,10%,X7R,A',
 VOLTAGE='16V',
 PRIM_FILE='./archive_libs/discrete/cap_a/chips/chips.prt';

PART_NAME
 C1T15 'CAP_0603-10UF,6.3V,20%,X6S,E15A':
 ROOM='P1V538_BMC_STBY_VR';

SECTION_NUMBER 1
 '@BASEBOARD_FAB2_LIB.BASEBOARD_FAB2(SCH_1):PAGE239_I12@MSTR_DISCRETE.CAP(CHIPS)':
 C_PATH='@baseboard_fab2_lib.baseboard_fab2(sch_1):page239_i12@mstr_discrete.cap~
(chips)',
 P_PATH='@baseboard_fab2_lib.baseboard_fab2(sch_1):page239_i12@mstr_discrete.cap~
(chips)',
 PATH='I12',
 DRAWING='@BASEBOARD_FAB2_LIB.BASEBOARD_FAB2(SCH_1):PAGE239',
 TOLERANCE='20%',
 SEC_TYPE='0603',
 MATERIAL='X6S',
 BOM_COST='P1V538_BMC_STBY_VR',
 PHYS_PAGE='239',
 XY='(10875,3625)',
 ROT='0',
 VER='1',
 VALUE='10UF',
 PACK_TYPE='0603',
 PART_NUMBER='E15431-002',
 LOCATION='C1T15',
 ROOM='P1V538_BMC_STBY_VR',
 SEC='1',
 CDS_LIB='mstr_discrete',
 CDS_PART_NAME='CAP_0603-10UF,6.3V,20%,X6S,E15A',
 VOLTAGE='6.3V',
 PRIM_FILE='./archive_libs/mstr_discrete/cap/chips/chips.prt';

PART_NAME
 C1T21 'CAP_A_0402V-1.0UF,6.3V,10%,X6SA':
 ROOM='BMC';

SECTION_NUMBER 1
 '@BASEBOARD_FAB2_LIB.BASEBOARD_FAB2(SCH_1):PAGE148_I20@DEV_DISCRETE.CAP_A(CHIPS)':
 C_PATH='@baseboard_fab2_lib.baseboard_fab2(sch_1):page148_i20@dev_discrete.cap_~
a(chips)',
 P_PATH='@baseboard_fab2_lib.baseboard_fab2(sch_1):page148_i20@dev_discrete.cap_~
a(chips)',
 PATH='I20',
 DRAWING='@BASEBOARD_FAB2_LIB.BASEBOARD_FAB2(SCH_1):PAGE148',
 TOLERANCE='10%',
 SEC_TYPE='0402V',
 MATERIAL='X6S',
 BOM_COST='SM_CONTROLLER',
 PHYS_PAGE='148',
 XY='(-7350,2125)',
 ROT='0',
 VER='1',
 VALUE='1.0UF',
 PACK_TYPE='0402V',
 PART_NUMBER='D97712-004',
 LOCATION='C1T21',
 ROOM='BMC',
 SEC='1',
 CDS_LIB='dev_discrete',
 CDS_PART_NAME='CAP_A_0402V-1.0UF,6.3V,10%,X6SA',
 VOLTAGE='6.3V',
 PRIM_FILE='./archive_libs/discrete/cap_a/chips/chips.prt';

PART_NAME
 C1T56 'CAP_A_0402V-0.1UF,16V,10%,X7R,A':
 ROOM='BMC_DEBUG_HEADER';

SECTION_NUMBER 1
 '@BASEBOARD_FAB2_LIB.BASEBOARD_FAB2(SCH_1):PAGE155_I184@DEV_DISCRETE.CAP_A(CHIPS)':
 C_PATH='@baseboard_fab2_lib.baseboard_fab2(sch_1):page155_i184@dev_discrete.cap~
_a(chips)',
 P_PATH='@baseboard_fab2_lib.baseboard_fab2(sch_1):page155_i184@dev_discrete.cap~
_a(chips)',
 PATH='I184',
 DRAWING='@BASEBOARD_FAB2_LIB.BASEBOARD_FAB2(SCH_1):PAGE155',
 TOLERANCE='10%',
 SEC_TYPE='0402V',
 MATERIAL='X7R',
 BOM_COST='DEBUG',
 PHYS_PAGE='155',
 XY='(-1550,3025)',
 ROT='0',
 VER='1',
 VALUE='0.1UF',
 PACK_TYPE='0402V',
 PART_NUMBER='A36096-030',
 LOCATION='C1T56',
 ROOM='BMC_DEBUG_HEADER',
 SEC='1',
 CDS_LIB='dev_discrete',
 CDS_PART_NAME='CAP_A_0402V-0.1UF,16V,10%,X7R,A',
 VOLTAGE='16V',
 PRIM_FILE='./archive_libs/discrete/cap_a/chips/chips.prt';

PART_NAME
 C1U19 'CAP_0402-1.0UF,16V,10%,X6S,D97A':
 ROOM='PROC_SIDEBAND';

SECTION_NUMBER 1
 '@BASEBOARD_FAB2_LIB.BASEBOARD_FAB2(SCH_1):PAGE152_I18@MSTR_DISCRETE.CAP(CHIPS)':
 C_PATH='@baseboard_fab2_lib.baseboard_fab2(sch_1):page152_i18@mstr_discrete.cap~
(chips)',
 P_PATH='@baseboard_fab2_lib.baseboard_fab2(sch_1):page152_i18@mstr_discrete.cap~
(chips)',
 PATH='I18',
 DRAWING='@BASEBOARD_FAB2_LIB.BASEBOARD_FAB2(SCH_1):PAGE152',
 TOLERANCE='10%',
 SEC_TYPE='0402',
 MATERIAL='X6S',
 BOM_COST='PROC_SIDEBAND',
 PHYS_PAGE='152',
 XY='(-4525,4650)',
 ROT='0',
 VER='1',
 VALUE='1.0UF',
 PACK_TYPE='0402',
 PART_NUMBER='D97712-011',
 LOCATION='C1U19',
 ROOM='PROC_SIDEBAND',
 SEC='1',
 CDS_LIB='mstr_discrete',
 CDS_PART_NAME='CAP_0402-1.0UF,16V,10%,X6S,D97A',
 VOLTAGE='16V',
 PRIM_FILE='./archive_libs/mstr_discrete/cap/chips/chips.prt';

PART_NAME
 C1U21 'CAP_0402LF-47.0PF,50V,5%,COG,AA':
 ROOM='BMC_VOLT_MONITOR';

SECTION_NUMBER 1
 '@BASEBOARD_FAB2_LIB.BASEBOARD_FAB2(SCH_1):PAGE169_I56@MSTR_DISCRETE.CAP(CHIPS)':
 C_PATH='@baseboard_fab2_lib.baseboard_fab2(sch_1):page169_i56@mstr_discrete.cap~
(chips)',
 P_PATH='@baseboard_fab2_lib.baseboard_fab2(sch_1):page169_i56@mstr_discrete.cap~
(chips)',
 PATH='I56',
 DRAWING='@BASEBOARD_FAB2_LIB.BASEBOARD_FAB2(SCH_1):PAGE169',
 TOLERANCE='5%',
 SEC_TYPE='0402LF',
 MATERIAL='COG',
 BOM_COST='SM_HM',
 PHYS_PAGE='169',
 XY='(-4825,3250)',
 ROT='0',
 VER='1',
 VALUE='47.0PF',
 PACK_TYPE='0402LF',
 PART_NUMBER='A36095-025',
 LOCATION='C1U21',
 ROOM='BMC_VOLT_MONITOR',
 SEC='1',
 CDS_LIB='mstr_discrete',
 CDS_PART_NAME='CAP_0402LF-47.0PF,50V,5%,COG,AA',
 VOLTAGE='50V',
 PRIM_FILE='./archive_libs/mstr_discrete/cap/chips/chips.prt';

PART_NAME
 C1U22 'CAP_A_0402V-0.1UF,16V,10%,X7R,A':
 ROOM='PROC_SIDEBAND';

SECTION_NUMBER 1
 '@BASEBOARD_FAB2_LIB.BASEBOARD_FAB2(SCH_1):PAGE152_I27@DEV_DISCRETE.CAP_A(CHIPS)':
 C_PATH='@baseboard_fab2_lib.baseboard_fab2(sch_1):page152_i27@dev_discrete.cap_~
a(chips)',
 P_PATH='@baseboard_fab2_lib.baseboard_fab2(sch_1):page152_i27@dev_discrete.cap_~
a(chips)',
 PATH='I27',
 DRAWING='@BASEBOARD_FAB2_LIB.BASEBOARD_FAB2(SCH_1):PAGE152',
 TOLERANCE='10%',
 SEC_TYPE='0402V',
 MATERIAL='X7R',
 BOM_COST='PROC_SIDEBAND',
 PHYS_PAGE='152',
 XY='(-2925,1600)',
 ROT='0',
 VER='1',
 VALUE='0.1UF',
 PACK_TYPE='0402V',
 PART_NUMBER='A36096-030',
 LOCATION='C1U22',
 ROOM='PROC_SIDEBAND',
 SEC='1',
 CDS_LIB='dev_discrete',
 CDS_PART_NAME='CAP_A_0402V-0.1UF,16V,10%,X7R,A',
 VOLTAGE='16V',
 PRIM_FILE='./archive_libs/discrete/cap_a/chips/chips.prt';

PART_NAME
 C1W7 'CAP_0603-10UF,6.3V,20%,X6S,E15A':
 ROOM='P1V538_BMC_STBY_VR';

SECTION_NUMBER 1
 '@BASEBOARD_FAB2_LIB.BASEBOARD_FAB2(SCH_1):PAGE239_I92@MSTR_DISCRETE.CAP(CHIPS)':
 C_PATH='@baseboard_fab2_lib.baseboard_fab2(sch_1):page239_i92@mstr_discrete.cap~
(chips)',
 P_PATH='@baseboard_fab2_lib.baseboard_fab2(sch_1):page239_i92@mstr_discrete.cap~
(chips)',
 PATH='I92',
 DRAWING='@BASEBOARD_FAB2_LIB.BASEBOARD_FAB2(SCH_1):PAGE239',
 TOLERANCE='20%',
 SEC_TYPE='0603',
 MATERIAL='X6S',
 BOM_COST='P1V538_BMC_STBY_VR',
 PHYS_PAGE='239',
 XY='(5575,2075)',
 ROT='0',
 VER='1',
 VALUE='10UF',
 PACK_TYPE='0603',
 PART_NUMBER='E15431-002',
 LOCATION='C1W7',
 ROOM='P1V538_BMC_STBY_VR',
 SEC='1',
 CDS_LIB='mstr_discrete',
 CDS_PART_NAME='CAP_0603-10UF,6.3V,20%,X6S,E15A',
 VOLTAGE='6.3V',
 PRIM_FILE='./archive_libs/mstr_discrete/cap/chips/chips.prt';

PART_NAME
 C1W15 'CAP_0603-10UF,6.3V,20%,X6S,E15A':
 ROOM='P1V538_BMC_STBY_VR';

SECTION_NUMBER 1
 '@BASEBOARD_FAB2_LIB.BASEBOARD_FAB2(SCH_1):PAGE239_I83@MSTR_DISCRETE.CAP(CHIPS)':
 C_PATH='@baseboard_fab2_lib.baseboard_fab2(sch_1):page239_i83@mstr_discrete.cap~
(chips)',
 P_PATH='@baseboard_fab2_lib.baseboard_fab2(sch_1):page239_i83@mstr_discrete.cap~
(chips)',
 PATH='I83',
 DRAWING='@BASEBOARD_FAB2_LIB.BASEBOARD_FAB2(SCH_1):PAGE239',
 TOLERANCE='20%',
 SEC_TYPE='0603',
 MATERIAL='X6S',
 BOM_COST='P1V538_BMC_STBY_VR',
 PHYS_PAGE='239',
 XY='(10450,1500)',
 ROT='0',
 VER='1',
 VALUE='10UF',
 PACK_TYPE='0603',
 PART_NUMBER='E15431-002',
 LOCATION='C1W15',
 ROOM='P1V538_BMC_STBY_VR',
 SEC='1',
 CDS_LIB='mstr_discrete',
 CDS_PART_NAME='CAP_0603-10UF,6.3V,20%,X6S,E15A',
 VOLTAGE='6.3V',
 PRIM_FILE='./archive_libs/mstr_discrete/cap/chips/chips.prt';

PART_NAME
 C1W16 'CAP_0402LF-1000PF,50V,10%,X7R,A':
 ROOM='PVCCIN_CPU0_VR';

SECTION_NUMBER 1
 '@BASEBOARD_FAB2_LIB.BASEBOARD_FAB2(SCH_1):PAGE199_I132@MSTR_DISCRETE.CAP(CHIPS)':
 C_PATH='@baseboard_fab2_lib.baseboard_fab2(sch_1):page199_i132@mstr_discrete.ca~
p(chips)',
 P_PATH='@baseboard_fab2_lib.baseboard_fab2(sch_1):page199_i132@mstr_discrete.ca~
p(chips)',
 PATH='I132',
 DRAWING='@BASEBOARD_FAB2_LIB.BASEBOARD_FAB2(SCH_1):PAGE199',
 TOLERANCE='10%',
 SEC_TYPE='0402LF',
 MATERIAL='X7R',
 PHYS_PAGE='199',
 XY='(-1500,1700)',
 ROT='2',
 VER='1',
 VALUE='1000PF',
 PACK_TYPE='0402LF',
 PART_NUMBER='A36096-046',
 LOCATION='C1W16',
 ROOM='PVCCIN_CPU0_VR',
 SEC='1',
 CDS_LIB='mstr_discrete',
 CDS_PART_NAME='CAP_0402LF-1000PF,50V,10%,X7R,A',
 VOLTAGE='50V',
 PRIM_FILE='./archive_libs/mstr_discrete/cap/chips/chips.prt';

PART_NAME
 C1W17 'CAP_0805-10UF,16V,10%,EMPTY,C9A':;

SECTION_NUMBER 1
 '@BASEBOARD_FAB2_LIB.BASEBOARD_FAB2(SCH_1):PAGE101_I139@MSTR_DISCRETE.CAP(CHIPS)':
 C_PATH='@baseboard_fab2_lib.baseboard_fab2(sch_1):page101_i139@mstr_discrete.ca~
p(chips)',
 P_PATH='@baseboard_fab2_lib.baseboard_fab2(sch_1):page101_i139@mstr_discrete.ca~
p(chips)',
 PATH='I139',
 DRAWING='@BASEBOARD_FAB2_LIB.BASEBOARD_FAB2(SCH_1):PAGE101',
 TOLERANCE='10%',
 SEC_TYPE='0805',
 MATERIAL='EMPTY',
 PHYS_PAGE='101',
 XY='(-1900,4000)',
 ROT='0',
 VER='1',
 VALUE='10UF',
 PACK_TYPE='0805',
 PART_NUMBER='C95333-007',
 LOCATION='C1W17',
 SEC='1',
 CDS_LIB='mstr_discrete',
 CDS_PART_NAME='CAP_0805-10UF,16V,10%,EMPTY,C9A',
 VOLTAGE='16V',
 PRIM_FILE='./archive_libs/mstr_discrete/cap/chips/chips.prt';

PART_NAME
 C1W18 'CAP_A_0402V-0.1UF,16V,10%,X7R,A':
 ROOM='MEM',
 SIGNAL_MODEL='DEFAULT_CAPACITOR_100000pF_2_1';

SECTION_NUMBER 1
 '@BASEBOARD_FAB2_LIB.BASEBOARD_FAB2(SCH_1):PAGE176_I163@DEV_DISCRETE.CAP_A(CHIPS)':
 C_PATH='@baseboard_fab2_lib.baseboard_fab2(sch_1):page176_i163@dev_discrete.cap~
_a(chips)',
 P_PATH='@baseboard_fab2_lib.baseboard_fab2(sch_1):page176_i163@dev_discrete.cap~
_a(chips)',
 PATH='I163',
 DRAWING='@BASEBOARD_FAB2_LIB.BASEBOARD_FAB2(SCH_1):PAGE176',
 CD_SEC='1',
 TOLERANCE='10%',
 MATERIAL='X7R',
 BOM_COST='SM_CONTROLLER',
 PHYS_PAGE='176',
 XY='(-4175,1650)',
 ROT='0',
 VER='1',
 VALUE='0.1UF',
 PACK_TYPE='0402V',
 PART_NUMBER='A36096-030',
 LOCATION='C1W18',
 SIGNAL_MODEL='DEFAULT_CAPACITOR_100000pF_2_1',
 ROOM='MEM',
 CDS_LIB='dev_discrete',
 CDS_PART_NAME='CAP_A_0402V-0.1UF,16V,10%,X7R,A',
 VOLTAGE='16V',
 PRIM_FILE='./archive_libs/discrete/cap_a/chips/chips.prt';

PART_NAME
 C1W19 'CAP_A_0402V-0.1UF,16V,10%,X7R,A':
 ROOM='MEM',
 SIGNAL_MODEL='DEFAULT_CAPACITOR_100000pF_2_1';

SECTION_NUMBER 1
 '@BASEBOARD_FAB2_LIB.BASEBOARD_FAB2(SCH_1):PAGE176_I166@DEV_DISCRETE.CAP_A(CHIPS)':
 C_PATH='@baseboard_fab2_lib.baseboard_fab2(sch_1):page176_i166@dev_discrete.cap~
_a(chips)',
 P_PATH='@baseboard_fab2_lib.baseboard_fab2(sch_1):page176_i166@dev_discrete.cap~
_a(chips)',
 PATH='I166',
 DRAWING='@BASEBOARD_FAB2_LIB.BASEBOARD_FAB2(SCH_1):PAGE176',
 CD_SEC='1',
 TOLERANCE='10%',
 MATERIAL='X7R',
 BOM_COST='SM_CONTROLLER',
 PHYS_PAGE='176',
 XY='(-3775,1650)',
 ROT='0',
 VER='1',
 VALUE='0.1UF',
 PACK_TYPE='0402V',
 PART_NUMBER='A36096-030',
 LOCATION='C1W19',
 SIGNAL_MODEL='DEFAULT_CAPACITOR_100000pF_2_1',
 ROOM='MEM',
 CDS_LIB='dev_discrete',
 CDS_PART_NAME='CAP_A_0402V-0.1UF,16V,10%,X7R,A',
 VOLTAGE='16V',
 PRIM_FILE='./archive_libs/discrete/cap_a/chips/chips.prt';

PART_NAME
 C1W20 'CAP_0402-0.22UF,16V,10%,X7R,A3A':
 ROOM='OCP_STEERING';

SECTION_NUMBER 1
 '@BASEBOARD_FAB2_LIB.BASEBOARD_FAB2(SCH_1):PAGE151_I220@MSTR_DISCRETE.CAP(CHIPS)':
 C_PATH='@baseboard_fab2_lib.baseboard_fab2(sch_1):page151_i220@mstr_discrete.ca~
p(chips)',
 P_PATH='@baseboard_fab2_lib.baseboard_fab2(sch_1):page151_i220@mstr_discrete.ca~
p(chips)',
 PATH='I220',
 DRAWING='@BASEBOARD_FAB2_LIB.BASEBOARD_FAB2(SCH_1):PAGE151',
 TOLERANCE='10%',
 SEC_TYPE='0402',
 MATERIAL='X7R',
 PHYS_PAGE='151',
 XY='(1950,-1900)',
 ROT='2',
 VER='1',
 VALUE='0.22UF',
 PACK_TYPE='0402',
 PART_NUMBER='A36096-155',
 LOCATION='C1W20',
 ROOM='OCP_STEERING',
 SEC='1',
 CDS_LIB='mstr_discrete',
 CDS_PART_NAME='CAP_0402-0.22UF,16V,10%,X7R,A3A',
 VOLTAGE='16V',
 PRIM_FILE='./archive_libs/mstr_discrete/cap/chips/chips.prt';

PART_NAME
 C1W21 'CAP_0603LF-0.033UF,50V,10%,X7RA':
 ROOM='HOT_SWAP';

SECTION_NUMBER 1
 '@BASEBOARD_FAB2_LIB.BASEBOARD_FAB2(SCH_1):PAGE146_I160@MSTR_DISCRETE.CAP(CHIPS)':
 C_PATH='@baseboard_fab2_lib.baseboard_fab2(sch_1):page146_i160@mstr_discrete.ca~
p(chips)',
 P_PATH='@baseboard_fab2_lib.baseboard_fab2(sch_1):page146_i160@mstr_discrete.ca~
p(chips)',
 PATH='I160',
 DRAWING='@BASEBOARD_FAB2_LIB.BASEBOARD_FAB2(SCH_1):PAGE146',
 TOLERANCE='10%',
 SEC_TYPE='0603LF',
 MATERIAL='X7R',
 PHYS_PAGE='146',
 XY='(-550,4350)',
 ROT='1',
 VER='1',
 VALUE='0.033UF',
 PACK_TYPE='0603LF',
 PART_NUMBER='603269-064',
 LOCATION='C1W21',
 ROOM='HOT_SWAP',
 SEC='1',
 CDS_LIB='mstr_discrete',
 CDS_PART_NAME='CAP_0603LF-0.033UF,50V,10%,X7RA',
 VOLTAGE='50V',
 PRIM_FILE='./archive_libs/mstr_discrete/cap/chips/chips.prt';

PART_NAME
 C2A1 'CAP_A_0603V-47UF,4V,20%,X5R,60A':
 GROUP='PWR_MLCC_CAP';

SECTION_NUMBER 1
 '@BASEBOARD_FAB2_LIB.BASEBOARD_FAB2(SCH_1):PAGE228_I282@DEV_DISCRETE.CAP_A(CHIPS)':
 C_PATH='@baseboard_fab2_lib.baseboard_fab2(sch_1):page228_i282@dev_discrete.cap~
_a(chips)',
 P_PATH='@baseboard_fab2_lib.baseboard_fab2(sch_1):page228_i282@dev_discrete.cap~
_a(chips)',
 PATH='I282',
 DRAWING='@BASEBOARD_FAB2_LIB.BASEBOARD_FAB2(SCH_1):PAGE228',
 BOM_SS='E15431-004',
 TOLERANCE='20%',
 SEC_TYPE='0603V',
 MATERIAL='X5R',
 PHYS_PAGE='228',
 XY='(1850,-75)',
 ROT='0',
 VER='1',
 VALUE='47UF',
 PACK_TYPE='0603V',
 PART_NUMBER='602433-106',
 LOCATION='C2A1',
 GROUP='PWR_MLCC_CAP',
 SEC='1',
 CDS_LIB='dev_discrete',
 CDS_PART_NAME='CAP_A_0603V-47UF,4V,20%,X5R,60A',
 VOLTAGE='4V',
 PRIM_FILE='./archive_libs/discrete/cap_a/chips/chips.prt';

PART_NAME
 C2A2 'CAP_A_0603V-47UF,4V,20%,X5R,60A':
 GROUP='PWR_MLCC_CAP';

SECTION_NUMBER 1
 '@BASEBOARD_FAB2_LIB.BASEBOARD_FAB2(SCH_1):PAGE228_I283@DEV_DISCRETE.CAP_A(CHIPS)':
 C_PATH='@baseboard_fab2_lib.baseboard_fab2(sch_1):page228_i283@dev_discrete.cap~
_a(chips)',
 P_PATH='@baseboard_fab2_lib.baseboard_fab2(sch_1):page228_i283@dev_discrete.cap~
_a(chips)',
 PATH='I283',
 DRAWING='@BASEBOARD_FAB2_LIB.BASEBOARD_FAB2(SCH_1):PAGE228',
 BOM_SS='E15431-004',
 TOLERANCE='20%',
 SEC_TYPE='0603V',
 MATERIAL='X5R',
 PHYS_PAGE='228',
 XY='(2125,-75)',
 ROT='0',
 VER='1',
 VALUE='47UF',
 PACK_TYPE='0603V',
 PART_NUMBER='602433-106',
 LOCATION='C2A2',
 GROUP='PWR_MLCC_CAP',
 SEC='1',
 CDS_LIB='dev_discrete',
 CDS_PART_NAME='CAP_A_0603V-47UF,4V,20%,X5R,60A',
 VOLTAGE='4V',
 PRIM_FILE='./archive_libs/discrete/cap_a/chips/chips.prt';

PART_NAME
 C2A3 'CAP_A_0603V-47UF,4V,20%,X5R,60A':
 GROUP='PWR_MLCC_CAP';

SECTION_NUMBER 1
 '@BASEBOARD_FAB2_LIB.BASEBOARD_FAB2(SCH_1):PAGE228_I296@DEV_DISCRETE.CAP_A(CHIPS)':
 C_PATH='@baseboard_fab2_lib.baseboard_fab2(sch_1):page228_i296@dev_discrete.cap~
_a(chips)',
 P_PATH='@baseboard_fab2_lib.baseboard_fab2(sch_1):page228_i296@dev_discrete.cap~
_a(chips)',
 PATH='I296',
 DRAWING='@BASEBOARD_FAB2_LIB.BASEBOARD_FAB2(SCH_1):PAGE228',
 BOM_SS='E15431-004',
 TOLERANCE='20%',
 SEC_TYPE='0603V',
 MATERIAL='X5R',
 PHYS_PAGE='228',
 XY='(1275,-775)',
 ROT='0',
 VER='1',
 VALUE='47UF',
 PACK_TYPE='0603V',
 PART_NUMBER='602433-106',
 LOCATION='C2A3',
 GROUP='PWR_MLCC_CAP',
 SEC='1',
 CDS_LIB='dev_discrete',
 CDS_PART_NAME='CAP_A_0603V-47UF,4V,20%,X5R,60A',
 VOLTAGE='4V',
 PRIM_FILE='./archive_libs/discrete/cap_a/chips/chips.prt';

PART_NAME
 C2A4 'CAP_A_0603V-47UF,4V,20%,X5R,60A':
 GROUP='PWR_MLCC_CAP';

SECTION_NUMBER 1
 '@BASEBOARD_FAB2_LIB.BASEBOARD_FAB2(SCH_1):PAGE228_I292@DEV_DISCRETE.CAP_A(CHIPS)':
 C_PATH='@baseboard_fab2_lib.baseboard_fab2(sch_1):page228_i292@dev_discrete.cap~
_a(chips)',
 P_PATH='@baseboard_fab2_lib.baseboard_fab2(sch_1):page228_i292@dev_discrete.cap~
_a(chips)',
 PATH='I292',
 DRAWING='@BASEBOARD_FAB2_LIB.BASEBOARD_FAB2(SCH_1):PAGE228',
 BOM_SS='E15431-004',
 TOLERANCE='20%',
 SEC_TYPE='0603V',
 MATERIAL='X5R',
 PHYS_PAGE='228',
 XY='(125,-775)',
 ROT='0',
 VER='1',
 VALUE='47UF',
 PACK_TYPE='0603V',
 PART_NUMBER='602433-106',
 LOCATION='C2A4',
 GROUP='PWR_MLCC_CAP',
 SEC='1',
 CDS_LIB='dev_discrete',
 CDS_PART_NAME='CAP_A_0603V-47UF,4V,20%,X5R,60A',
 VOLTAGE='4V',
 PRIM_FILE='./archive_libs/discrete/cap_a/chips/chips.prt';

PART_NAME
 C2A5 'CAP_A_0603V-47UF,4V,20%,X5R,60A':
 GROUP='PWR_MLCC_CAP';

SECTION_NUMBER 1
 '@BASEBOARD_FAB2_LIB.BASEBOARD_FAB2(SCH_1):PAGE228_I199@DEV_DISCRETE.CAP_A(CHIPS)':
 C_PATH='@baseboard_fab2_lib.baseboard_fab2(sch_1):page228_i199@dev_discrete.cap~
_a(chips)',
 P_PATH='@baseboard_fab2_lib.baseboard_fab2(sch_1):page228_i199@dev_discrete.cap~
_a(chips)',
 PATH='I199',
 DRAWING='@BASEBOARD_FAB2_LIB.BASEBOARD_FAB2(SCH_1):PAGE228',
 BOM_SS='NOPOP',
 TOLERANCE='20%',
 SEC_TYPE='0603V',
 MATERIAL='X5R',
 PHYS_PAGE='228',
 XY='(2900,725)',
 ROT='0',
 VER='1',
 VALUE='47UF',
 PACK_TYPE='0603V',
 PART_NUMBER='602433-106',
 LOCATION='C2A5',
 GROUP='PWR_MLCC_CAP',
 SEC='1',
 CDS_LIB='dev_discrete',
 CDS_PART_NAME='CAP_A_0603V-47UF,4V,20%,X5R,60A',
 VOLTAGE='4V',
 PRIM_FILE='./archive_libs/discrete/cap_a/chips/chips.prt';

PART_NAME
 C2A6 'CAP_A_0603V-47UF,4V,20%,X5R,60A':
 GROUP='PWR_MLCC_CAP';

SECTION_NUMBER 1
 '@BASEBOARD_FAB2_LIB.BASEBOARD_FAB2(SCH_1):PAGE228_I273@DEV_DISCRETE.CAP_A(CHIPS)':
 C_PATH='@baseboard_fab2_lib.baseboard_fab2(sch_1):page228_i273@dev_discrete.cap~
_a(chips)',
 P_PATH='@baseboard_fab2_lib.baseboard_fab2(sch_1):page228_i273@dev_discrete.cap~
_a(chips)',
 PATH='I273',
 DRAWING='@BASEBOARD_FAB2_LIB.BASEBOARD_FAB2(SCH_1):PAGE228',
 BOM_SS='E15431-004',
 TOLERANCE='20%',
 SEC_TYPE='0603V',
 MATERIAL='X5R',
 PHYS_PAGE='228',
 XY='(-800,-75)',
 ROT='0',
 VER='1',
 VALUE='47UF',
 PACK_TYPE='0603V',
 PART_NUMBER='602433-106',
 LOCATION='C2A6',
 GROUP='PWR_MLCC_CAP',
 SEC='1',
 CDS_LIB='dev_discrete',
 CDS_PART_NAME='CAP_A_0603V-47UF,4V,20%,X5R,60A',
 VOLTAGE='4V',
 PRIM_FILE='./archive_libs/discrete/cap_a/chips/chips.prt';

PART_NAME
 C2A7 'CAP_A_0603V-47UF,4V,20%,X5R,60A':
 GROUP='PWR_MLCC_CAP';

SECTION_NUMBER 1
 '@BASEBOARD_FAB2_LIB.BASEBOARD_FAB2(SCH_1):PAGE228_I274@DEV_DISCRETE.CAP_A(CHIPS)':
 C_PATH='@baseboard_fab2_lib.baseboard_fab2(sch_1):page228_i274@dev_discrete.cap~
_a(chips)',
 P_PATH='@baseboard_fab2_lib.baseboard_fab2(sch_1):page228_i274@dev_discrete.cap~
_a(chips)',
 PATH='I274',
 DRAWING='@BASEBOARD_FAB2_LIB.BASEBOARD_FAB2(SCH_1):PAGE228',
 BOM_SS='E15431-004',
 TOLERANCE='20%',
 SEC_TYPE='0603V',
 MATERIAL='X5R',
 PHYS_PAGE='228',
 XY='(-500,-75)',
 ROT='0',
 VER='1',
 VALUE='47UF',
 PACK_TYPE='0603V',
 PART_NUMBER='602433-106',
 LOCATION='C2A7',
 GROUP='PWR_MLCC_CAP',
 SEC='1',
 CDS_LIB='dev_discrete',
 CDS_PART_NAME='CAP_A_0603V-47UF,4V,20%,X5R,60A',
 VOLTAGE='4V',
 PRIM_FILE='./archive_libs/discrete/cap_a/chips/chips.prt';

PART_NAME
 C2A8 'CAP_0805-100UF,4V,20%,X5R,6024A':
 GROUP='PWR_MLCC_CAP',
 ROOM='VDDQ_ABC_PWR_VR';

SECTION_NUMBER 1
 '@BASEBOARD_FAB2_LIB.BASEBOARD_FAB2(SCH_1):PAGE228_I309@MSTR_DISCRETE.CAP(CHIPS)':
 C_PATH='@baseboard_fab2_lib.baseboard_fab2(sch_1):page228_i309@mstr_discrete.ca~
p(chips)',
 P_PATH='@baseboard_fab2_lib.baseboard_fab2(sch_1):page228_i309@mstr_discrete.ca~
p(chips)',
 PATH='I309',
 DRAWING='@BASEBOARD_FAB2_LIB.BASEBOARD_FAB2(SCH_1):PAGE228',
 NEW_PN='078.1071T.M002',
 NEW_MATERIAL='X6S',
 BOM_SS='NOPOP',
 TOLERANCE='20%',
 SEC_TYPE='0805',
 MATERIAL='X5R',
 BOM_COST='MEM_VRD_PVDDQ_CD',
 PHYS_PAGE='228',
 XY='(4950,2825)',
 ROT='0',
 VER='1',
 VALUE='100UF',
 PACK_TYPE='0805',
 PART_NUMBER='602433-112',
 LOCATION='C2A8',
 ROOM='VDDQ_ABC_PWR_VR',
 GROUP='PWR_MLCC_CAP',
 SEC='1',
 CDS_LIB='mstr_discrete',
 CDS_PART_NAME='CAP_0805-100UF,4V,20%,X5R,6024A',
 VOLTAGE='4V',
 PRIM_FILE='./archive_libs/mstr_discrete/cap/chips/chips.prt';

PART_NAME
 C2A9 'CAP_A_0603V-47UF,4V,20%,X5R,60A':
 GROUP='PWR_MLCC_CAP';

SECTION_NUMBER 1
 '@BASEBOARD_FAB2_LIB.BASEBOARD_FAB2(SCH_1):PAGE228_I277@DEV_DISCRETE.CAP_A(CHIPS)':
 C_PATH='@baseboard_fab2_lib.baseboard_fab2(sch_1):page228_i277@dev_discrete.cap~
_a(chips)',
 P_PATH='@baseboard_fab2_lib.baseboard_fab2(sch_1):page228_i277@dev_discrete.cap~
_a(chips)',
 PATH='I277',
 DRAWING='@BASEBOARD_FAB2_LIB.BASEBOARD_FAB2(SCH_1):PAGE228',
 BOM_SS='E15431-004',
 TOLERANCE='20%',
 SEC_TYPE='0603V',
 MATERIAL='X5R',
 PHYS_PAGE='228',
 XY='(400,-75)',
 ROT='0',
 VER='1',
 VALUE='47UF',
 PACK_TYPE='0603V',
 PART_NUMBER='602433-106',
 LOCATION='C2A9',
 GROUP='PWR_MLCC_CAP',
 SEC='1',
 CDS_LIB='dev_discrete',
 CDS_PART_NAME='CAP_A_0603V-47UF,4V,20%,X5R,60A',
 VOLTAGE='4V',
 PRIM_FILE='./archive_libs/discrete/cap_a/chips/chips.prt';

PART_NAME
 C2A10 'CAP_A_0603V-47UF,4V,20%,X5R,60A':
 GROUP='PWR_MLCC_CAP';

SECTION_NUMBER 1
 '@BASEBOARD_FAB2_LIB.BASEBOARD_FAB2(SCH_1):PAGE228_I278@DEV_DISCRETE.CAP_A(CHIPS)':
 C_PATH='@baseboard_fab2_lib.baseboard_fab2(sch_1):page228_i278@dev_discrete.cap~
_a(chips)',
 P_PATH='@baseboard_fab2_lib.baseboard_fab2(sch_1):page228_i278@dev_discrete.cap~
_a(chips)',
 PATH='I278',
 DRAWING='@BASEBOARD_FAB2_LIB.BASEBOARD_FAB2(SCH_1):PAGE228',
 BOM_SS='E15431-004',
 TOLERANCE='20%',
 SEC_TYPE='0603V',
 MATERIAL='X5R',
 PHYS_PAGE='228',
 XY='(700,-75)',
 ROT='0',
 VER='1',
 VALUE='47UF',
 PACK_TYPE='0603V',
 PART_NUMBER='602433-106',
 LOCATION='C2A10',
 GROUP='PWR_MLCC_CAP',
 SEC='1',
 CDS_LIB='dev_discrete',
 CDS_PART_NAME='CAP_A_0603V-47UF,4V,20%,X5R,60A',
 VOLTAGE='4V',
 PRIM_FILE='./archive_libs/discrete/cap_a/chips/chips.prt';

PART_NAME
 C2A11 'CAP_A_0603V-47UF,4V,20%,X5R,60A':
 GROUP='PWR_MLCC_CAP';

SECTION_NUMBER 1
 '@BASEBOARD_FAB2_LIB.BASEBOARD_FAB2(SCH_1):PAGE228_I279@DEV_DISCRETE.CAP_A(CHIPS)':
 C_PATH='@baseboard_fab2_lib.baseboard_fab2(sch_1):page228_i279@dev_discrete.cap~
_a(chips)',
 P_PATH='@baseboard_fab2_lib.baseboard_fab2(sch_1):page228_i279@dev_discrete.cap~
_a(chips)',
 PATH='I279',
 DRAWING='@BASEBOARD_FAB2_LIB.BASEBOARD_FAB2(SCH_1):PAGE228',
 BOM_SS='E15431-004',
 TOLERANCE='20%',
 SEC_TYPE='0603V',
 MATERIAL='X5R',
 PHYS_PAGE='228',
 XY='(975,-75)',
 ROT='0',
 VER='1',
 VALUE='47UF',
 PACK_TYPE='0603V',
 PART_NUMBER='602433-106',
 LOCATION='C2A11',
 GROUP='PWR_MLCC_CAP',
 SEC='1',
 CDS_LIB='dev_discrete',
 CDS_PART_NAME='CAP_A_0603V-47UF,4V,20%,X5R,60A',
 VOLTAGE='4V',
 PRIM_FILE='./archive_libs/discrete/cap_a/chips/chips.prt';

PART_NAME
 C2A12 'CAP_A_0603V-47UF,4V,20%,X5R,60A':
 GROUP='PWR_MLCC_CAP';

SECTION_NUMBER 1
 '@BASEBOARD_FAB2_LIB.BASEBOARD_FAB2(SCH_1):PAGE228_I281@DEV_DISCRETE.CAP_A(CHIPS)':
 C_PATH='@baseboard_fab2_lib.baseboard_fab2(sch_1):page228_i281@dev_discrete.cap~
_a(chips)',
 P_PATH='@baseboard_fab2_lib.baseboard_fab2(sch_1):page228_i281@dev_discrete.cap~
_a(chips)',
 PATH='I281',
 DRAWING='@BASEBOARD_FAB2_LIB.BASEBOARD_FAB2(SCH_1):PAGE228',
 BOM_SS='E15431-004',
 TOLERANCE='20%',
 SEC_TYPE='0603V',
 MATERIAL='X5R',
 PHYS_PAGE='228',
 XY='(1550,-75)',
 ROT='0',
 VER='1',
 VALUE='47UF',
 PACK_TYPE='0603V',
 PART_NUMBER='602433-106',
 LOCATION='C2A12',
 GROUP='PWR_MLCC_CAP',
 SEC='1',
 CDS_LIB='dev_discrete',
 CDS_PART_NAME='CAP_A_0603V-47UF,4V,20%,X5R,60A',
 VOLTAGE='4V',
 PRIM_FILE='./archive_libs/discrete/cap_a/chips/chips.prt';

PART_NAME
 C2A13 'CAP_A_0603V-47UF,4V,20%,X5R,60A':
 GROUP='PWR_MLCC_CAP';

SECTION_NUMBER 1
 '@BASEBOARD_FAB2_LIB.BASEBOARD_FAB2(SCH_1):PAGE228_I280@DEV_DISCRETE.CAP_A(CHIPS)':
 C_PATH='@baseboard_fab2_lib.baseboard_fab2(sch_1):page228_i280@dev_discrete.cap~
_a(chips)',
 P_PATH='@baseboard_fab2_lib.baseboard_fab2(sch_1):page228_i280@dev_discrete.cap~
_a(chips)',
 PATH='I280',
 DRAWING='@BASEBOARD_FAB2_LIB.BASEBOARD_FAB2(SCH_1):PAGE228',
 BOM_SS='E15431-004',
 TOLERANCE='20%',
 SEC_TYPE='0603V',
 MATERIAL='X5R',
 PHYS_PAGE='228',
 XY='(1250,-75)',
 ROT='0',
 VER='1',
 VALUE='47UF',
 PACK_TYPE='0603V',
 PART_NUMBER='602433-106',
 LOCATION='C2A13',
 GROUP='PWR_MLCC_CAP',
 SEC='1',
 CDS_LIB='dev_discrete',
 CDS_PART_NAME='CAP_A_0603V-47UF,4V,20%,X5R,60A',
 VOLTAGE='4V',
 PRIM_FILE='./archive_libs/discrete/cap_a/chips/chips.prt';

PART_NAME
 C2A14 'CAP_A_0603V-47UF,4V,20%,X5R,60A':
 GROUP='PWR_MLCC_CAP';

SECTION_NUMBER 1
 '@BASEBOARD_FAB2_LIB.BASEBOARD_FAB2(SCH_1):PAGE228_I272@DEV_DISCRETE.CAP_A(CHIPS)':
 C_PATH='@baseboard_fab2_lib.baseboard_fab2(sch_1):page228_i272@dev_discrete.cap~
_a(chips)',
 P_PATH='@baseboard_fab2_lib.baseboard_fab2(sch_1):page228_i272@dev_discrete.cap~
_a(chips)',
 PATH='I272',
 DRAWING='@BASEBOARD_FAB2_LIB.BASEBOARD_FAB2(SCH_1):PAGE228',
 BOM_SS='E15431-004',
 TOLERANCE='20%',
 SEC_TYPE='0603V',
 MATERIAL='X5R',
 PHYS_PAGE='228',
 XY='(-1100,-75)',
 ROT='0',
 VER='1',
 VALUE='47UF',
 PACK_TYPE='0603V',
 PART_NUMBER='602433-106',
 LOCATION='C2A14',
 GROUP='PWR_MLCC_CAP',
 SEC='1',
 CDS_LIB='dev_discrete',
 CDS_PART_NAME='CAP_A_0603V-47UF,4V,20%,X5R,60A',
 VOLTAGE='4V',
 PRIM_FILE='./archive_libs/discrete/cap_a/chips/chips.prt';

PART_NAME
 C2A15 'CAP_A_0603V-47UF,4V,20%,X5R,60A':
 GROUP='PWR_MLCC_CAP';

SECTION_NUMBER 1
 '@BASEBOARD_FAB2_LIB.BASEBOARD_FAB2(SCH_1):PAGE228_I271@DEV_DISCRETE.CAP_A(CHIPS)':
 C_PATH='@baseboard_fab2_lib.baseboard_fab2(sch_1):page228_i271@dev_discrete.cap~
_a(chips)',
 P_PATH='@baseboard_fab2_lib.baseboard_fab2(sch_1):page228_i271@dev_discrete.cap~
_a(chips)',
 PATH='I271',
 DRAWING='@BASEBOARD_FAB2_LIB.BASEBOARD_FAB2(SCH_1):PAGE228',
 BOM_SS='E15431-004',
 TOLERANCE='20%',
 SEC_TYPE='0603V',
 MATERIAL='X5R',
 PHYS_PAGE='228',
 XY='(-1375,-75)',
 ROT='0',
 VER='1',
 VALUE='47UF',
 PACK_TYPE='0603V',
 PART_NUMBER='602433-106',
 LOCATION='C2A15',
 GROUP='PWR_MLCC_CAP',
 SEC='1',
 CDS_LIB='dev_discrete',
 CDS_PART_NAME='CAP_A_0603V-47UF,4V,20%,X5R,60A',
 VOLTAGE='4V',
 PRIM_FILE='./archive_libs/discrete/cap_a/chips/chips.prt';

PART_NAME
 C2A16 'CAP_0805-100UF,4V,20%,X5R,6024A':
 GROUP='PWR_MLCC_CAP',
 ROOM='VDDQ_ABC_PWR_VR';

SECTION_NUMBER 1
 '@BASEBOARD_FAB2_LIB.BASEBOARD_FAB2(SCH_1):PAGE228_I313@MSTR_DISCRETE.CAP(CHIPS)':
 C_PATH='@baseboard_fab2_lib.baseboard_fab2(sch_1):page228_i313@mstr_discrete.ca~
p(chips)',
 P_PATH='@baseboard_fab2_lib.baseboard_fab2(sch_1):page228_i313@mstr_discrete.ca~
p(chips)',
 PATH='I313',
 DRAWING='@BASEBOARD_FAB2_LIB.BASEBOARD_FAB2(SCH_1):PAGE228',
 NEW_PN='078.1071T.M002',
 NEW_MATERIAL='X6S',
 BOM_SS='NOPOP',
 TOLERANCE='20%',
 SEC_TYPE='0805',
 MATERIAL='X5R',
 BOM_COST='MEM_VRD_PVDDQ_CD',
 PHYS_PAGE='228',
 XY='(3850,2825)',
 ROT='0',
 VER='1',
 VALUE='100UF',
 PACK_TYPE='0805',
 PART_NUMBER='602433-112',
 LOCATION='C2A16',
 ROOM='VDDQ_ABC_PWR_VR',
 GROUP='PWR_MLCC_CAP',
 SEC='1',
 CDS_LIB='mstr_discrete',
 CDS_PART_NAME='CAP_0805-100UF,4V,20%,X5R,6024A',
 VOLTAGE='4V',
 PRIM_FILE='./archive_libs/mstr_discrete/cap/chips/chips.prt';

PART_NAME
 C2B1 'CAP_A_0603V-47UF,4V,20%,X5R,60A':
 GROUP='PWR_MLCC_CAP';

SECTION_NUMBER 1
 '@BASEBOARD_FAB2_LIB.BASEBOARD_FAB2(SCH_1):PAGE228_I200@DEV_DISCRETE.CAP_A(CHIPS)':
 C_PATH='@baseboard_fab2_lib.baseboard_fab2(sch_1):page228_i200@dev_discrete.cap~
_a(chips)',
 P_PATH='@baseboard_fab2_lib.baseboard_fab2(sch_1):page228_i200@dev_discrete.cap~
_a(chips)',
 PATH='I200',
 DRAWING='@BASEBOARD_FAB2_LIB.BASEBOARD_FAB2(SCH_1):PAGE228',
 BOM_SS='NOPOP',
 TOLERANCE='20%',
 SEC_TYPE='0603V',
 MATERIAL='X5R',
 PHYS_PAGE='228',
 XY='(3300,725)',
 ROT='0',
 VER='1',
 VALUE='47UF',
 PACK_TYPE='0603V',
 PART_NUMBER='602433-106',
 LOCATION='C2B1',
 GROUP='PWR_MLCC_CAP',
 SEC='1',
 CDS_LIB='dev_discrete',
 CDS_PART_NAME='CAP_A_0603V-47UF,4V,20%,X5R,60A',
 VOLTAGE='4V',
 PRIM_FILE='./archive_libs/discrete/cap_a/chips/chips.prt';

PART_NAME
 C2B2 'CAP_A_0603V-47UF,4V,20%,X5R,60A':
 GROUP='PWR_MLCC_CAP';

SECTION_NUMBER 1
 '@BASEBOARD_FAB2_LIB.BASEBOARD_FAB2(SCH_1):PAGE228_I204@DEV_DISCRETE.CAP_A(CHIPS)':
 C_PATH='@baseboard_fab2_lib.baseboard_fab2(sch_1):page228_i204@dev_discrete.cap~
_a(chips)',
 P_PATH='@baseboard_fab2_lib.baseboard_fab2(sch_1):page228_i204@dev_discrete.cap~
_a(chips)',
 PATH='I204',
 DRAWING='@BASEBOARD_FAB2_LIB.BASEBOARD_FAB2(SCH_1):PAGE228',
 BOM_SS='NOPOP',
 TOLERANCE='20%',
 SEC_TYPE='0603V',
 MATERIAL='X5R',
 PHYS_PAGE='228',
 XY='(3625,1425)',
 ROT='0',
 VER='1',
 VALUE='47UF',
 PACK_TYPE='0603V',
 PART_NUMBER='602433-106',
 LOCATION='C2B2',
 GROUP='PWR_MLCC_CAP',
 SEC='1',
 CDS_LIB='dev_discrete',
 CDS_PART_NAME='CAP_A_0603V-47UF,4V,20%,X5R,60A',
 VOLTAGE='4V',
 PRIM_FILE='./archive_libs/discrete/cap_a/chips/chips.prt';

PART_NAME
 C2D1 'CAP_A_0603V-22.0UF,4V,20%,X6S,A':
 GROUP='PWR_MLCC_CAP',
 ROOM='PVCCIN_CPU1_DECAP_VR';

SECTION_NUMBER 1
 '@BASEBOARD_FAB2_LIB.BASEBOARD_FAB2(SCH_1):PAGE228_I258@DEV_DISCRETE.CAP_A(CHIPS)':
 C_PATH='@baseboard_fab2_lib.baseboard_fab2(sch_1):page228_i258@dev_discrete.cap~
_a(chips)',
 P_PATH='@baseboard_fab2_lib.baseboard_fab2(sch_1):page228_i258@dev_discrete.cap~
_a(chips)',
 PATH='I258',
 DRAWING='@BASEBOARD_FAB2_LIB.BASEBOARD_FAB2(SCH_1):PAGE228',
 TOLERANCE='20%',
 MATERIAL='X6S',
 BOM_COST='PROC',
 PHYS_PAGE='228',
 XY='(600,1800)',
 ROT='0',
 VER='1',
 VALUE='22.0UF',
 PACK_TYPE='0603V',
 PART_NUMBER='E15431-004',
 LOCATION='C2D1',
 ROOM='PVCCIN_CPU1_DECAP_VR',
 GROUP='PWR_MLCC_CAP',
 CDS_LIB='dev_discrete',
 CDS_PART_NAME='CAP_A_0603V-22.0UF,4V,20%,X6S,A',
 VOLTAGE='4V',
 PRIM_FILE='./archive_libs/discrete/cap_a/chips/chips.prt';

PART_NAME
 C2D2 'CAP_A_0603V-22.0UF,4V,20%,X6S,A':
 GROUP='PWR_MLCC_CAP',
 ROOM='PVCCIN_CPU1_DECAP_VR';

SECTION_NUMBER 1
 '@BASEBOARD_FAB2_LIB.BASEBOARD_FAB2(SCH_1):PAGE228_I257@DEV_DISCRETE.CAP_A(CHIPS)':
 C_PATH='@baseboard_fab2_lib.baseboard_fab2(sch_1):page228_i257@dev_discrete.cap~
_a(chips)',
 P_PATH='@baseboard_fab2_lib.baseboard_fab2(sch_1):page228_i257@dev_discrete.cap~
_a(chips)',
 PATH='I257',
 DRAWING='@BASEBOARD_FAB2_LIB.BASEBOARD_FAB2(SCH_1):PAGE228',
 TOLERANCE='20%',
 SEC_TYPE='0603V',
 MATERIAL='X6S',
 BOM_COST='PROC',
 PHYS_PAGE='228',
 XY='(950,1800)',
 ROT='0',
 VER='1',
 VALUE='22.0UF',
 PACK_TYPE='0603V',
 PART_NUMBER='E15431-004',
 LOCATION='C2D2',
 ROOM='PVCCIN_CPU1_DECAP_VR',
 GROUP='PWR_MLCC_CAP',
 SEC='1',
 CDS_LIB='dev_discrete',
 CDS_PART_NAME='CAP_A_0603V-22.0UF,4V,20%,X6S,A',
 VOLTAGE='4V',
 PRIM_FILE='./archive_libs/discrete/cap_a/chips/chips.prt';

PART_NAME
 C2D3 'CAP_A_0603V-22.0UF,4V,20%,X6S,A':
 GROUP='PWR_MLCC_CAP',
 ROOM='PVCCIN_CPU1_DECAP_VR';

SECTION_NUMBER 1
 '@BASEBOARD_FAB2_LIB.BASEBOARD_FAB2(SCH_1):PAGE228_I256@DEV_DISCRETE.CAP_A(CHIPS)':
 C_PATH='@baseboard_fab2_lib.baseboard_fab2(sch_1):page228_i256@dev_discrete.cap~
_a(chips)',
 P_PATH='@baseboard_fab2_lib.baseboard_fab2(sch_1):page228_i256@dev_discrete.cap~
_a(chips)',
 PATH='I256',
 DRAWING='@BASEBOARD_FAB2_LIB.BASEBOARD_FAB2(SCH_1):PAGE228',
 TOLERANCE='20%',
 SEC_TYPE='0603V',
 MATERIAL='X6S',
 BOM_COST='PROC',
 PHYS_PAGE='228',
 XY='(1300,1800)',
 ROT='0',
 VER='1',
 VALUE='22.0UF',
 PACK_TYPE='0603V',
 PART_NUMBER='E15431-004',
 LOCATION='C2D3',
 ROOM='PVCCIN_CPU1_DECAP_VR',
 GROUP='PWR_MLCC_CAP',
 SEC='1',
 CDS_LIB='dev_discrete',
 CDS_PART_NAME='CAP_A_0603V-22.0UF,4V,20%,X6S,A',
 VOLTAGE='4V',
 PRIM_FILE='./archive_libs/discrete/cap_a/chips/chips.prt';

PART_NAME
 C2D4 'CAP_A_0603V-22.0UF,4V,20%,X6S,A':
 GROUP='PWR_MLCC_CAP',
 ROOM='PVCCIN_CPU0_DECAP_VR';

SECTION_NUMBER 1
 '@BASEBOARD_FAB2_LIB.BASEBOARD_FAB2(SCH_1):PAGE228_I265@DEV_DISCRETE.CAP_A(CHIPS)':
 C_PATH='@baseboard_fab2_lib.baseboard_fab2(sch_1):page228_i265@dev_discrete.cap~
_a(chips)',
 P_PATH='@baseboard_fab2_lib.baseboard_fab2(sch_1):page228_i265@dev_discrete.cap~
_a(chips)',
 PATH='I265',
 DRAWING='@BASEBOARD_FAB2_LIB.BASEBOARD_FAB2(SCH_1):PAGE228',
 TOLERANCE='20%',
 MATERIAL='X6S',
 BOM_COST='PROC_SOCKET',
 PHYS_PAGE='228',
 XY='(-950,2975)',
 ROT='0',
 VER='1',
 VALUE='22.0UF',
 PACK_TYPE='0603V',
 PART_NUMBER='E15431-004',
 LOCATION='C2D4',
 ROOM='PVCCIN_CPU0_DECAP_VR',
 GROUP='PWR_MLCC_CAP',
 CDS_LIB='dev_discrete',
 CDS_PART_NAME='CAP_A_0603V-22.0UF,4V,20%,X6S,A',
 VOLTAGE='4V',
 PRIM_FILE='./archive_libs/discrete/cap_a/chips/chips.prt';

PART_NAME
 C2D5 'CAP_A_0603V-22.0UF,4V,20%,X6S,A':
 GROUP='PWR_MLCC_CAP',
 ROOM='PVCCIN_CPU0_DECAP_VR';

SECTION_NUMBER 1
 '@BASEBOARD_FAB2_LIB.BASEBOARD_FAB2(SCH_1):PAGE228_I266@DEV_DISCRETE.CAP_A(CHIPS)':
 C_PATH='@baseboard_fab2_lib.baseboard_fab2(sch_1):page228_i266@dev_discrete.cap~
_a(chips)',
 P_PATH='@baseboard_fab2_lib.baseboard_fab2(sch_1):page228_i266@dev_discrete.cap~
_a(chips)',
 PATH='I266',
 DRAWING='@BASEBOARD_FAB2_LIB.BASEBOARD_FAB2(SCH_1):PAGE228',
 TOLERANCE='20%',
 MATERIAL='X6S',
 BOM_COST='PROC_SOCKET',
 PHYS_PAGE='228',
 XY='(-600,2975)',
 ROT='0',
 VER='1',
 VALUE='22.0UF',
 PACK_TYPE='0603V',
 PART_NUMBER='E15431-004',
 LOCATION='C2D5',
 ROOM='PVCCIN_CPU0_DECAP_VR',
 GROUP='PWR_MLCC_CAP',
 CDS_LIB='dev_discrete',
 CDS_PART_NAME='CAP_A_0603V-22.0UF,4V,20%,X6S,A',
 VOLTAGE='4V',
 PRIM_FILE='./archive_libs/discrete/cap_a/chips/chips.prt';

PART_NAME
 C2D6 'CAP_A_0603V-22.0UF,4V,20%,X6S,A':
 GROUP='PWR_MLCC_CAP',
 ROOM='PVCCIN_CPU0_DECAP_VR';

SECTION_NUMBER 1
 '@BASEBOARD_FAB2_LIB.BASEBOARD_FAB2(SCH_1):PAGE228_I267@DEV_DISCRETE.CAP_A(CHIPS)':
 C_PATH='@baseboard_fab2_lib.baseboard_fab2(sch_1):page228_i267@dev_discrete.cap~
_a(chips)',
 P_PATH='@baseboard_fab2_lib.baseboard_fab2(sch_1):page228_i267@dev_discrete.cap~
_a(chips)',
 PATH='I267',
 DRAWING='@BASEBOARD_FAB2_LIB.BASEBOARD_FAB2(SCH_1):PAGE228',
 TOLERANCE='20%',
 MATERIAL='X6S',
 BOM_COST='PROC_SOCKET',
 PHYS_PAGE='228',
 XY='(-250,2975)',
 ROT='0',
 VER='1',
 VALUE='22.0UF',
 PACK_TYPE='0603V',
 PART_NUMBER='E15431-004',
 LOCATION='C2D6',
 ROOM='PVCCIN_CPU0_DECAP_VR',
 GROUP='PWR_MLCC_CAP',
 CDS_LIB='dev_discrete',
 CDS_PART_NAME='CAP_A_0603V-22.0UF,4V,20%,X6S,A',
 VOLTAGE='4V',
 PRIM_FILE='./archive_libs/discrete/cap_a/chips/chips.prt';

PART_NAME
 C2D7 'CAP_A_0603V-22.0UF,4V,20%,X6S,A':
 GROUP='PWR_MLCC_CAP',
 ROOM='PVCCIN_CPU0_DECAP_VR';

SECTION_NUMBER 1
 '@BASEBOARD_FAB2_LIB.BASEBOARD_FAB2(SCH_1):PAGE228_I264@DEV_DISCRETE.CAP_A(CHIPS)':
 C_PATH='@baseboard_fab2_lib.baseboard_fab2(sch_1):page228_i264@dev_discrete.cap~
_a(chips)',
 P_PATH='@baseboard_fab2_lib.baseboard_fab2(sch_1):page228_i264@dev_discrete.cap~
_a(chips)',
 PATH='I264',
 DRAWING='@BASEBOARD_FAB2_LIB.BASEBOARD_FAB2(SCH_1):PAGE228',
 TOLERANCE='20%',
 MATERIAL='X6S',
 BOM_COST='PROC_SOCKET',
 PHYS_PAGE='228',
 XY='(-1300,2975)',
 ROT='0',
 VER='1',
 VALUE='22.0UF',
 PACK_TYPE='0603V',
 PART_NUMBER='E15431-004',
 LOCATION='C2D7',
 ROOM='PVCCIN_CPU0_DECAP_VR',
 GROUP='PWR_MLCC_CAP',
 CDS_LIB='dev_discrete',
 CDS_PART_NAME='CAP_A_0603V-22.0UF,4V,20%,X6S,A',
 VOLTAGE='4V',
 PRIM_FILE='./archive_libs/discrete/cap_a/chips/chips.prt';

PART_NAME
 C2D8 'CAP_0603LF-10UF,4V,20%,X6S,E15A':
 GROUP='PWR_MLCC_CAP',
 ROOM='PVCCIN_CPU1_DECAP_VR';

SECTION_NUMBER 1
 '@BASEBOARD_FAB2_LIB.BASEBOARD_FAB2(SCH_1):PAGE76_I33@MSTR_DISCRETE.CAP(CHIPS)':
 C_PATH='@baseboard_fab2_lib.baseboard_fab2(sch_1):page76_i33@mstr_discrete.cap(~
chips)',
 P_PATH='@baseboard_fab2_lib.baseboard_fab2(sch_1):page76_i33@mstr_discrete.cap(~
chips)',
 PATH='I33',
 DRAWING='@BASEBOARD_FAB2_LIB.BASEBOARD_FAB2(SCH_1):PAGE76',
 TOLERANCE='20%',
 MATERIAL='X6S',
 BOM_COST='PROC',
 PHYS_PAGE='76',
 XY='(-3050,3100)',
 ROT='0',
 VER='1',
 VALUE='10UF',
 PACK_TYPE='0603LF',
 PART_NUMBER='E15431-001',
 LOCATION='C2D8',
 ROOM='PVCCIN_CPU1_DECAP_VR',
 GROUP='PWR_MLCC_CAP',
 CDS_LIB='mstr_discrete',
 CDS_PART_NAME='CAP_0603LF-10UF,4V,20%,X6S,E15A',
 VOLTAGE='4V',
 PRIM_FILE='./archive_libs/mstr_discrete/cap/chips/chips.prt';

PART_NAME
 C2D9 'CAP_0603LF-10UF,4V,20%,X6S,E15A':
 GROUP='PWR_MLCC_CAP',
 ROOM='PVCCIN_CPU1_DECAP_VR';

SECTION_NUMBER 1
 '@BASEBOARD_FAB2_LIB.BASEBOARD_FAB2(SCH_1):PAGE76_I43@MSTR_DISCRETE.CAP(CHIPS)':
 C_PATH='@baseboard_fab2_lib.baseboard_fab2(sch_1):page76_i43@mstr_discrete.cap(~
chips)',
 P_PATH='@baseboard_fab2_lib.baseboard_fab2(sch_1):page76_i43@mstr_discrete.cap(~
chips)',
 PATH='I43',
 DRAWING='@BASEBOARD_FAB2_LIB.BASEBOARD_FAB2(SCH_1):PAGE76',
 TOLERANCE='20%',
 MATERIAL='X6S',
 BOM_COST='PROC',
 PHYS_PAGE='76',
 XY='(-3950,3100)',
 ROT='0',
 VER='1',
 VALUE='10UF',
 PACK_TYPE='0603LF',
 PART_NUMBER='E15431-001',
 LOCATION='C2D9',
 ROOM='PVCCIN_CPU1_DECAP_VR',
 GROUP='PWR_MLCC_CAP',
 CDS_LIB='mstr_discrete',
 CDS_PART_NAME='CAP_0603LF-10UF,4V,20%,X6S,E15A',
 VOLTAGE='4V',
 PRIM_FILE='./archive_libs/mstr_discrete/cap/chips/chips.prt';

PART_NAME
 C2D10 'CAP_0603LF-10UF,4V,20%,X6S,E15A':
 GROUP='PWR_MLCC_CAP',
 ROOM='PVCCIN_CPU1_DECAP_VR';

SECTION_NUMBER 1
 '@BASEBOARD_FAB2_LIB.BASEBOARD_FAB2(SCH_1):PAGE76_I37@MSTR_DISCRETE.CAP(CHIPS)':
 C_PATH='@baseboard_fab2_lib.baseboard_fab2(sch_1):page76_i37@mstr_discrete.cap(~
chips)',
 P_PATH='@baseboard_fab2_lib.baseboard_fab2(sch_1):page76_i37@mstr_discrete.cap(~
chips)',
 PATH='I37',
 DRAWING='@BASEBOARD_FAB2_LIB.BASEBOARD_FAB2(SCH_1):PAGE76',
 TOLERANCE='20%',
 MATERIAL='X6S',
 BOM_COST='PROC',
 PHYS_PAGE='76',
 XY='(-3350,3100)',
 ROT='0',
 VER='1',
 VALUE='10UF',
 PACK_TYPE='0603LF',
 PART_NUMBER='E15431-001',
 LOCATION='C2D10',
 ROOM='PVCCIN_CPU1_DECAP_VR',
 GROUP='PWR_MLCC_CAP',
 CDS_LIB='mstr_discrete',
 CDS_PART_NAME='CAP_0603LF-10UF,4V,20%,X6S,E15A',
 VOLTAGE='4V',
 PRIM_FILE='./archive_libs/mstr_discrete/cap/chips/chips.prt';

PART_NAME
 C2D11 'CAP_0603LF-10UF,4V,20%,X6S,E15A':
 GROUP='PWR_MLCC_CAP',
 ROOM='PVCCIN_CPU1_DECAP_VR';

SECTION_NUMBER 1
 '@BASEBOARD_FAB2_LIB.BASEBOARD_FAB2(SCH_1):PAGE76_I42@MSTR_DISCRETE.CAP(CHIPS)':
 C_PATH='@baseboard_fab2_lib.baseboard_fab2(sch_1):page76_i42@mstr_discrete.cap(~
chips)',
 P_PATH='@baseboard_fab2_lib.baseboard_fab2(sch_1):page76_i42@mstr_discrete.cap(~
chips)',
 PATH='I42',
 DRAWING='@BASEBOARD_FAB2_LIB.BASEBOARD_FAB2(SCH_1):PAGE76',
 TOLERANCE='20%',
 MATERIAL='X6S',
 BOM_COST='PROC',
 PHYS_PAGE='76',
 XY='(-3650,3100)',
 ROT='0',
 VER='1',
 VALUE='10UF',
 PACK_TYPE='0603LF',
 PART_NUMBER='E15431-001',
 LOCATION='C2D11',
 ROOM='PVCCIN_CPU1_DECAP_VR',
 GROUP='PWR_MLCC_CAP',
 CDS_LIB='mstr_discrete',
 CDS_PART_NAME='CAP_0603LF-10UF,4V,20%,X6S,E15A',
 VOLTAGE='4V',
 PRIM_FILE='./archive_libs/mstr_discrete/cap/chips/chips.prt';

PART_NAME
 C2D12 'CAP_A_0603V-22.0UF,4V,20%,X6S,A':
 GROUP='PWR_MLCC_CAP',
 ROOM='PVCCIN_CPU1_DECAP_VR';

SECTION_NUMBER 1
 '@BASEBOARD_FAB2_LIB.BASEBOARD_FAB2(SCH_1):PAGE76_I59@DEV_DISCRETE.CAP_A(CHIPS)':
 C_PATH='@baseboard_fab2_lib.baseboard_fab2(sch_1):page76_i59@dev_discrete.cap_a~
(chips)',
 P_PATH='@baseboard_fab2_lib.baseboard_fab2(sch_1):page76_i59@dev_discrete.cap_a~
(chips)',
 PATH='I59',
 DRAWING='@BASEBOARD_FAB2_LIB.BASEBOARD_FAB2(SCH_1):PAGE76',
 TOLERANCE='20%',
 MATERIAL='X6S',
 BOM_COST='PROC',
 PHYS_PAGE='76',
 XY='(-4800,4450)',
 ROT='0',
 VER='1',
 VALUE='22.0UF',
 PACK_TYPE='0603V',
 PART_NUMBER='E15431-004',
 LOCATION='C2D12',
 ROOM='PVCCIN_CPU1_DECAP_VR',
 GROUP='PWR_MLCC_CAP',
 CDS_LIB='dev_discrete',
 CDS_PART_NAME='CAP_A_0603V-22.0UF,4V,20%,X6S,A',
 VOLTAGE='4V',
 PRIM_FILE='./archive_libs/discrete/cap_a/chips/chips.prt';

PART_NAME
 C2D13 'CAP_A_0603V-22.0UF,4V,20%,X6S,A':
 GROUP='PWR_MLCC_CAP',
 ROOM='PVCCIN_CPU1_DECAP_VR';

SECTION_NUMBER 1
 '@BASEBOARD_FAB2_LIB.BASEBOARD_FAB2(SCH_1):PAGE76_I73@DEV_DISCRETE.CAP_A(CHIPS)':
 C_PATH='@baseboard_fab2_lib.baseboard_fab2(sch_1):page76_i73@dev_discrete.cap_a~
(chips)',
 P_PATH='@baseboard_fab2_lib.baseboard_fab2(sch_1):page76_i73@dev_discrete.cap_a~
(chips)',
 PATH='I73',
 DRAWING='@BASEBOARD_FAB2_LIB.BASEBOARD_FAB2(SCH_1):PAGE76',
 TOLERANCE='20%',
 MATERIAL='X6S',
 BOM_COST='PROC',
 PHYS_PAGE='76',
 XY='(-4700,3750)',
 ROT='0',
 VER='1',
 VALUE='22.0UF',
 PACK_TYPE='0603V',
 PART_NUMBER='E15431-004',
 LOCATION='C2D13',
 ROOM='PVCCIN_CPU1_DECAP_VR',
 GROUP='PWR_MLCC_CAP',
 CDS_LIB='dev_discrete',
 CDS_PART_NAME='CAP_A_0603V-22.0UF,4V,20%,X6S,A',
 VOLTAGE='4V',
 PRIM_FILE='./archive_libs/discrete/cap_a/chips/chips.prt';

PART_NAME
 C2D14 'CAP_A_0603V-22.0UF,4V,20%,X6S,A':
 GROUP='PWR_MLCC_CAP',
 ROOM='PVCCIN_CPU1_DECAP_VR';

SECTION_NUMBER 1
 '@BASEBOARD_FAB2_LIB.BASEBOARD_FAB2(SCH_1):PAGE76_I76@DEV_DISCRETE.CAP_A(CHIPS)':
 C_PATH='@baseboard_fab2_lib.baseboard_fab2(sch_1):page76_i76@dev_discrete.cap_a~
(chips)',
 P_PATH='@baseboard_fab2_lib.baseboard_fab2(sch_1):page76_i76@dev_discrete.cap_a~
(chips)',
 PATH='I76',
 DRAWING='@BASEBOARD_FAB2_LIB.BASEBOARD_FAB2(SCH_1):PAGE76',
 TOLERANCE='20%',
 MATERIAL='X6S',
 BOM_COST='PROC',
 PHYS_PAGE='76',
 XY='(-4800,3050)',
 ROT='0',
 VER='1',
 VALUE='22.0UF',
 PACK_TYPE='0603V',
 PART_NUMBER='E15431-004',
 LOCATION='C2D14',
 ROOM='PVCCIN_CPU1_DECAP_VR',
 GROUP='PWR_MLCC_CAP',
 CDS_LIB='dev_discrete',
 CDS_PART_NAME='CAP_A_0603V-22.0UF,4V,20%,X6S,A',
 VOLTAGE='4V',
 PRIM_FILE='./archive_libs/discrete/cap_a/chips/chips.prt';

PART_NAME
 C2D15 'CAP_A_0603V-22.0UF,4V,20%,X6S,A':
 GROUP='PWR_MLCC_CAP',
 ROOM='PVCCIN_CPU1_DECAP_VR';

SECTION_NUMBER 1
 '@BASEBOARD_FAB2_LIB.BASEBOARD_FAB2(SCH_1):PAGE76_I159@DEV_DISCRETE.CAP_A(CHIPS)':
 C_PATH='@baseboard_fab2_lib.baseboard_fab2(sch_1):page76_i159@dev_discrete.cap_~
a(chips)',
 P_PATH='@baseboard_fab2_lib.baseboard_fab2(sch_1):page76_i159@dev_discrete.cap_~
a(chips)',
 PATH='I159',
 DRAWING='@BASEBOARD_FAB2_LIB.BASEBOARD_FAB2(SCH_1):PAGE76',
 TOLERANCE='20%',
 MATERIAL='X6S',
 BOM_COST='PROC',
 PHYS_PAGE='76',
 XY='(-4500,4450)',
 ROT='0',
 VER='1',
 VALUE='22.0UF',
 PACK_TYPE='0603V',
 PART_NUMBER='E15431-004',
 LOCATION='C2D15',
 ROOM='PVCCIN_CPU1_DECAP_VR',
 GROUP='PWR_MLCC_CAP',
 CDS_LIB='dev_discrete',
 CDS_PART_NAME='CAP_A_0603V-22.0UF,4V,20%,X6S,A',
 VOLTAGE='4V',
 PRIM_FILE='./archive_libs/discrete/cap_a/chips/chips.prt';

PART_NAME
 C2D16 'CAP_A_0603V-22.0UF,4V,20%,X6S,A':
 GROUP='PWR_MLCC_CAP',
 ROOM='PVCCIN_CPU1_DECAP_VR';

SECTION_NUMBER 1
 '@BASEBOARD_FAB2_LIB.BASEBOARD_FAB2(SCH_1):PAGE76_I124@DEV_DISCRETE.CAP_A(CHIPS)':
 C_PATH='@baseboard_fab2_lib.baseboard_fab2(sch_1):page76_i124@dev_discrete.cap_~
a(chips)',
 P_PATH='@baseboard_fab2_lib.baseboard_fab2(sch_1):page76_i124@dev_discrete.cap_~
a(chips)',
 PATH='I124',
 DRAWING='@BASEBOARD_FAB2_LIB.BASEBOARD_FAB2(SCH_1):PAGE76',
 TOLERANCE='20%',
 MATERIAL='X6S',
 BOM_COST='PROC',
 PHYS_PAGE='76',
 XY='(-7750,3050)',
 ROT='0',
 VER='1',
 VALUE='22.0UF',
 PACK_TYPE='0603V',
 PART_NUMBER='E15431-004',
 LOCATION='C2D16',
 ROOM='PVCCIN_CPU1_DECAP_VR',
 GROUP='PWR_MLCC_CAP',
 CDS_LIB='dev_discrete',
 CDS_PART_NAME='CAP_A_0603V-22.0UF,4V,20%,X6S,A',
 VOLTAGE='4V',
 PRIM_FILE='./archive_libs/discrete/cap_a/chips/chips.prt';

PART_NAME
 C2D17 'CAP_A_0603V-22.0UF,4V,20%,X6S,A':
 GROUP='PWR_MLCC_CAP',
 ROOM='PVCCIN_CPU1_DECAP_VR';

SECTION_NUMBER 1
 '@BASEBOARD_FAB2_LIB.BASEBOARD_FAB2(SCH_1):PAGE76_I114@DEV_DISCRETE.CAP_A(CHIPS)':
 C_PATH='@baseboard_fab2_lib.baseboard_fab2(sch_1):page76_i114@dev_discrete.cap_~
a(chips)',
 P_PATH='@baseboard_fab2_lib.baseboard_fab2(sch_1):page76_i114@dev_discrete.cap_~
a(chips)',
 PATH='I114',
 DRAWING='@BASEBOARD_FAB2_LIB.BASEBOARD_FAB2(SCH_1):PAGE76',
 TOLERANCE='20%',
 MATERIAL='X6S',
 BOM_COST='PROC',
 PHYS_PAGE='76',
 XY='(-7050,3050)',
 ROT='0',
 VER='1',
 VALUE='22.0UF',
 PACK_TYPE='0603V',
 PART_NUMBER='E15431-004',
 LOCATION='C2D17',
 ROOM='PVCCIN_CPU1_DECAP_VR',
 GROUP='PWR_MLCC_CAP',
 CDS_LIB='dev_discrete',
 CDS_PART_NAME='CAP_A_0603V-22.0UF,4V,20%,X6S,A',
 VOLTAGE='4V',
 PRIM_FILE='./archive_libs/discrete/cap_a/chips/chips.prt';

PART_NAME
 C2D18 'CAP_A_0603V-22.0UF,4V,20%,X6S,A':
 GROUP='PWR_MCP_CAP',
 ROOM='PVCCIN_CPU1_DECAP_VR';

SECTION_NUMBER 1
 '@BASEBOARD_FAB2_LIB.BASEBOARD_FAB2(SCH_1):PAGE76_I197@DEV_DISCRETE.CAP_A(CHIPS)':
 C_PATH='@baseboard_fab2_lib.baseboard_fab2(sch_1):page76_i197@dev_discrete.cap_~
a(chips)',
 P_PATH='@baseboard_fab2_lib.baseboard_fab2(sch_1):page76_i197@dev_discrete.cap_~
a(chips)',
 PATH='I197',
 DRAWING='@BASEBOARD_FAB2_LIB.BASEBOARD_FAB2(SCH_1):PAGE76',
 TOLERANCE='20%',
 MATERIAL='X6S',
 BOM_COST='PROC',
 PHYS_PAGE='76',
 XY='(-1725,3775)',
 ROT='0',
 VER='1',
 VALUE='22.0UF',
 PACK_TYPE='0603V',
 PART_NUMBER='E15431-004',
 LOCATION='C2D18',
 ROOM='PVCCIN_CPU1_DECAP_VR',
 GROUP='PWR_MCP_CAP',
 CDS_LIB='dev_discrete',
 CDS_PART_NAME='CAP_A_0603V-22.0UF,4V,20%,X6S,A',
 VOLTAGE='4V',
 PRIM_FILE='./archive_libs/discrete/cap_a/chips/chips.prt';

PART_NAME
 C2D19 'CAP_A_0603V-22.0UF,4V,20%,X6S,A':
 GROUP='PWR_MLCC_CAP',
 ROOM='PVCCIN_CPU1_DECAP_VR';

SECTION_NUMBER 1
 '@BASEBOARD_FAB2_LIB.BASEBOARD_FAB2(SCH_1):PAGE76_I75@DEV_DISCRETE.CAP_A(CHIPS)':
 C_PATH='@baseboard_fab2_lib.baseboard_fab2(sch_1):page76_i75@dev_discrete.cap_a~
(chips)',
 P_PATH='@baseboard_fab2_lib.baseboard_fab2(sch_1):page76_i75@dev_discrete.cap_a~
(chips)',
 PATH='I75',
 DRAWING='@BASEBOARD_FAB2_LIB.BASEBOARD_FAB2(SCH_1):PAGE76',
 TOLERANCE='20%',
 MATERIAL='X6S',
 BOM_COST='PROC',
 PHYS_PAGE='76',
 XY='(-5000,3750)',
 ROT='0',
 VER='1',
 VALUE='22.0UF',
 PACK_TYPE='0603V',
 PART_NUMBER='E15431-004',
 LOCATION='C2D19',
 ROOM='PVCCIN_CPU1_DECAP_VR',
 GROUP='PWR_MLCC_CAP',
 CDS_LIB='dev_discrete',
 CDS_PART_NAME='CAP_A_0603V-22.0UF,4V,20%,X6S,A',
 VOLTAGE='4V',
 PRIM_FILE='./archive_libs/discrete/cap_a/chips/chips.prt';

PART_NAME
 C2D20 'CAP_A_0603V-22.0UF,4V,20%,X6S,A':
 GROUP='PWR_MLCC_CAP',
 ROOM='PVCCIN_CPU1_DECAP_VR';

SECTION_NUMBER 1
 '@BASEBOARD_FAB2_LIB.BASEBOARD_FAB2(SCH_1):PAGE76_I79@DEV_DISCRETE.CAP_A(CHIPS)':
 C_PATH='@baseboard_fab2_lib.baseboard_fab2(sch_1):page76_i79@dev_discrete.cap_a~
(chips)',
 P_PATH='@baseboard_fab2_lib.baseboard_fab2(sch_1):page76_i79@dev_discrete.cap_a~
(chips)',
 PATH='I79',
 DRAWING='@BASEBOARD_FAB2_LIB.BASEBOARD_FAB2(SCH_1):PAGE76',
 TOLERANCE='20%',
 MATERIAL='X6S',
 BOM_COST='PROC',
 PHYS_PAGE='76',
 XY='(-5100,3050)',
 ROT='0',
 VER='1',
 VALUE='22.0UF',
 PACK_TYPE='0603V',
 PART_NUMBER='E15431-004',
 LOCATION='C2D20',
 ROOM='PVCCIN_CPU1_DECAP_VR',
 GROUP='PWR_MLCC_CAP',
 CDS_LIB='dev_discrete',
 CDS_PART_NAME='CAP_A_0603V-22.0UF,4V,20%,X6S,A',
 VOLTAGE='4V',
 PRIM_FILE='./archive_libs/discrete/cap_a/chips/chips.prt';

PART_NAME
 C2D21 'CAP_A_0603V-22.0UF,4V,20%,X6S,A':
 GROUP='PWR_MLCC_CAP',
 ROOM='PVCCIN_CPU1_DECAP_VR';

SECTION_NUMBER 1
 '@BASEBOARD_FAB2_LIB.BASEBOARD_FAB2(SCH_1):PAGE76_I65@DEV_DISCRETE.CAP_A(CHIPS)':
 C_PATH='@baseboard_fab2_lib.baseboard_fab2(sch_1):page76_i65@dev_discrete.cap_a~
(chips)',
 P_PATH='@baseboard_fab2_lib.baseboard_fab2(sch_1):page76_i65@dev_discrete.cap_a~
(chips)',
 PATH='I65',
 DRAWING='@BASEBOARD_FAB2_LIB.BASEBOARD_FAB2(SCH_1):PAGE76',
 TOLERANCE='20%',
 MATERIAL='X6S',
 BOM_COST='PROC',
 PHYS_PAGE='76',
 XY='(-5900,4450)',
 ROT='0',
 VER='1',
 VALUE='22.0UF',
 PACK_TYPE='0603V',
 PART_NUMBER='E15431-004',
 LOCATION='C2D21',
 ROOM='PVCCIN_CPU1_DECAP_VR',
 GROUP='PWR_MLCC_CAP',
 CDS_LIB='dev_discrete',
 CDS_PART_NAME='CAP_A_0603V-22.0UF,4V,20%,X6S,A',
 VOLTAGE='4V',
 PRIM_FILE='./archive_libs/discrete/cap_a/chips/chips.prt';

PART_NAME
 C2D22 'CAP_A_0603V-22.0UF,4V,20%,X6S,A':
 GROUP='PWR_MLCC_CAP',
 ROOM='PVCCIN_CPU1_DECAP_VR';

SECTION_NUMBER 1
 '@BASEBOARD_FAB2_LIB.BASEBOARD_FAB2(SCH_1):PAGE76_I61@DEV_DISCRETE.CAP_A(CHIPS)':
 C_PATH='@baseboard_fab2_lib.baseboard_fab2(sch_1):page76_i61@dev_discrete.cap_a~
(chips)',
 P_PATH='@baseboard_fab2_lib.baseboard_fab2(sch_1):page76_i61@dev_discrete.cap_a~
(chips)',
 PATH='I61',
 DRAWING='@BASEBOARD_FAB2_LIB.BASEBOARD_FAB2(SCH_1):PAGE76',
 TOLERANCE='20%',
 MATERIAL='X6S',
 BOM_COST='PROC',
 PHYS_PAGE='76',
 XY='(-5100,4450)',
 ROT='0',
 VER='1',
 VALUE='22.0UF',
 PACK_TYPE='0603V',
 PART_NUMBER='E15431-004',
 LOCATION='C2D22',
 ROOM='PVCCIN_CPU1_DECAP_VR',
 GROUP='PWR_MLCC_CAP',
 CDS_LIB='dev_discrete',
 CDS_PART_NAME='CAP_A_0603V-22.0UF,4V,20%,X6S,A',
 VOLTAGE='4V',
 PRIM_FILE='./archive_libs/discrete/cap_a/chips/chips.prt';

PART_NAME
 C2D23 'CAP_A_0603V-22.0UF,4V,20%,X6S,A':
 GROUP='PWR_MLCC_CAP',
 ROOM='PVCCIN_CPU1_DECAP_VR';

SECTION_NUMBER 1
 '@BASEBOARD_FAB2_LIB.BASEBOARD_FAB2(SCH_1):PAGE76_I112@DEV_DISCRETE.CAP_A(CHIPS)':
 C_PATH='@baseboard_fab2_lib.baseboard_fab2(sch_1):page76_i112@dev_discrete.cap_~
a(chips)',
 P_PATH='@baseboard_fab2_lib.baseboard_fab2(sch_1):page76_i112@dev_discrete.cap_~
a(chips)',
 PATH='I112',
 DRAWING='@BASEBOARD_FAB2_LIB.BASEBOARD_FAB2(SCH_1):PAGE76',
 TOLERANCE='20%',
 MATERIAL='X6S',
 BOM_COST='PROC',
 PHYS_PAGE='76',
 XY='(-6750,3050)',
 ROT='0',
 VER='1',
 VALUE='22.0UF',
 PACK_TYPE='0603V',
 PART_NUMBER='E15431-004',
 LOCATION='C2D23',
 ROOM='PVCCIN_CPU1_DECAP_VR',
 GROUP='PWR_MLCC_CAP',
 CDS_LIB='dev_discrete',
 CDS_PART_NAME='CAP_A_0603V-22.0UF,4V,20%,X6S,A',
 VOLTAGE='4V',
 PRIM_FILE='./archive_libs/discrete/cap_a/chips/chips.prt';

PART_NAME
 C2D24 'CAP_A_0603V-22.0UF,4V,20%,X6S,A':
 GROUP='PWR_MLCC_CAP',
 ROOM='PVCCIN_CPU1_DECAP_VR';

SECTION_NUMBER 1
 '@BASEBOARD_FAB2_LIB.BASEBOARD_FAB2(SCH_1):PAGE76_I80@DEV_DISCRETE.CAP_A(CHIPS)':
 C_PATH='@baseboard_fab2_lib.baseboard_fab2(sch_1):page76_i80@dev_discrete.cap_a~
(chips)',
 P_PATH='@baseboard_fab2_lib.baseboard_fab2(sch_1):page76_i80@dev_discrete.cap_a~
(chips)',
 PATH='I80',
 DRAWING='@BASEBOARD_FAB2_LIB.BASEBOARD_FAB2(SCH_1):PAGE76',
 TOLERANCE='20%',
 MATERIAL='X6S',
 BOM_COST='PROC',
 PHYS_PAGE='76',
 XY='(-5400,3050)',
 ROT='0',
 VER='1',
 VALUE='22.0UF',
 PACK_TYPE='0603V',
 PART_NUMBER='E15431-004',
 LOCATION='C2D24',
 ROOM='PVCCIN_CPU1_DECAP_VR',
 GROUP='PWR_MLCC_CAP',
 CDS_LIB='dev_discrete',
 CDS_PART_NAME='CAP_A_0603V-22.0UF,4V,20%,X6S,A',
 VOLTAGE='4V',
 PRIM_FILE='./archive_libs/discrete/cap_a/chips/chips.prt';

PART_NAME
 C2D25 'CAP_A_0603V-22.0UF,4V,20%,X6S,A':
 GROUP='PWR_MLCC_CAP',
 ROOM='PVCCIN_CPU1_DECAP_VR';

SECTION_NUMBER 1
 '@BASEBOARD_FAB2_LIB.BASEBOARD_FAB2(SCH_1):PAGE76_I82@DEV_DISCRETE.CAP_A(CHIPS)':
 C_PATH='@baseboard_fab2_lib.baseboard_fab2(sch_1):page76_i82@dev_discrete.cap_a~
(chips)',
 P_PATH='@baseboard_fab2_lib.baseboard_fab2(sch_1):page76_i82@dev_discrete.cap_a~
(chips)',
 PATH='I82',
 DRAWING='@BASEBOARD_FAB2_LIB.BASEBOARD_FAB2(SCH_1):PAGE76',
 TOLERANCE='20%',
 MATERIAL='X6S',
 BOM_COST='PROC',
 PHYS_PAGE='76',
 XY='(-5300,3750)',
 ROT='0',
 VER='1',
 VALUE='22.0UF',
 PACK_TYPE='0603V',
 PART_NUMBER='E15431-004',
 LOCATION='C2D25',
 ROOM='PVCCIN_CPU1_DECAP_VR',
 GROUP='PWR_MLCC_CAP',
 CDS_LIB='dev_discrete',
 CDS_PART_NAME='CAP_A_0603V-22.0UF,4V,20%,X6S,A',
 VOLTAGE='4V',
 PRIM_FILE='./archive_libs/discrete/cap_a/chips/chips.prt';

PART_NAME
 C2D26 'CAP_A_0603V-22.0UF,4V,20%,X6S,A':
 GROUP='PWR_MLCC_CAP',
 ROOM='PVCCIN_CPU1_DECAP_VR';

SECTION_NUMBER 1
 '@BASEBOARD_FAB2_LIB.BASEBOARD_FAB2(SCH_1):PAGE76_I108@DEV_DISCRETE.CAP_A(CHIPS)':
 C_PATH='@baseboard_fab2_lib.baseboard_fab2(sch_1):page76_i108@dev_discrete.cap_~
a(chips)',
 P_PATH='@baseboard_fab2_lib.baseboard_fab2(sch_1):page76_i108@dev_discrete.cap_~
a(chips)',
 PATH='I108',
 DRAWING='@BASEBOARD_FAB2_LIB.BASEBOARD_FAB2(SCH_1):PAGE76',
 TOLERANCE='20%',
 MATERIAL='X6S',
 BOM_COST='PROC',
 PHYS_PAGE='76',
 XY='(-6750,3750)',
 ROT='0',
 VER='1',
 VALUE='22.0UF',
 PACK_TYPE='0603V',
 PART_NUMBER='E15431-004',
 LOCATION='C2D26',
 ROOM='PVCCIN_CPU1_DECAP_VR',
 GROUP='PWR_MLCC_CAP',
 CDS_LIB='dev_discrete',
 CDS_PART_NAME='CAP_A_0603V-22.0UF,4V,20%,X6S,A',
 VOLTAGE='4V',
 PRIM_FILE='./archive_libs/discrete/cap_a/chips/chips.prt';

PART_NAME
 C2D27 'CAP_A_0603V-22.0UF,4V,20%,X6S,A':
 GROUP='PWR_MLCC_CAP',
 ROOM='PVCCIN_CPU1_DECAP_VR';

SECTION_NUMBER 1
 '@BASEBOARD_FAB2_LIB.BASEBOARD_FAB2(SCH_1):PAGE76_I66@DEV_DISCRETE.CAP_A(CHIPS)':
 C_PATH='@baseboard_fab2_lib.baseboard_fab2(sch_1):page76_i66@dev_discrete.cap_a~
(chips)',
 P_PATH='@baseboard_fab2_lib.baseboard_fab2(sch_1):page76_i66@dev_discrete.cap_a~
(chips)',
 PATH='I66',
 DRAWING='@BASEBOARD_FAB2_LIB.BASEBOARD_FAB2(SCH_1):PAGE76',
 TOLERANCE='20%',
 MATERIAL='X6S',
 BOM_COST='PROC',
 PHYS_PAGE='76',
 XY='(-6650,4450)',
 ROT='0',
 VER='1',
 VALUE='22.0UF',
 PACK_TYPE='0603V',
 PART_NUMBER='E15431-004',
 LOCATION='C2D27',
 ROOM='PVCCIN_CPU1_DECAP_VR',
 GROUP='PWR_MLCC_CAP',
 CDS_LIB='dev_discrete',
 CDS_PART_NAME='CAP_A_0603V-22.0UF,4V,20%,X6S,A',
 VOLTAGE='4V',
 PRIM_FILE='./archive_libs/discrete/cap_a/chips/chips.prt';

PART_NAME
 C2D28 'CAP_A_0603V-22.0UF,4V,20%,X6S,A':
 GROUP='PWR_MCP_CAP',
 ROOM='PVCCIN_CPU1_DECAP_VR';

SECTION_NUMBER 1
 '@BASEBOARD_FAB2_LIB.BASEBOARD_FAB2(SCH_1):PAGE76_I198@DEV_DISCRETE.CAP_A(CHIPS)':
 C_PATH='@baseboard_fab2_lib.baseboard_fab2(sch_1):page76_i198@dev_discrete.cap_~
a(chips)',
 P_PATH='@baseboard_fab2_lib.baseboard_fab2(sch_1):page76_i198@dev_discrete.cap_~
a(chips)',
 PATH='I198',
 DRAWING='@BASEBOARD_FAB2_LIB.BASEBOARD_FAB2(SCH_1):PAGE76',
 TOLERANCE='20%',
 MATERIAL='X6S',
 BOM_COST='PROC',
 PHYS_PAGE='76',
 XY='(-1475,3775)',
 ROT='0',
 VER='1',
 VALUE='22.0UF',
 PACK_TYPE='0603V',
 PART_NUMBER='E15431-004',
 LOCATION='C2D28',
 ROOM='PVCCIN_CPU1_DECAP_VR',
 GROUP='PWR_MCP_CAP',
 CDS_LIB='dev_discrete',
 CDS_PART_NAME='CAP_A_0603V-22.0UF,4V,20%,X6S,A',
 VOLTAGE='4V',
 PRIM_FILE='./archive_libs/discrete/cap_a/chips/chips.prt';

PART_NAME
 C2D29 'CAP_A_0603V-22.0UF,4V,20%,X6S,A':
 GROUP='PWR_MCP_CAP',
 ROOM='PVCCIN_CPU1_DECAP_VR';

SECTION_NUMBER 1
 '@BASEBOARD_FAB2_LIB.BASEBOARD_FAB2(SCH_1):PAGE76_I199@DEV_DISCRETE.CAP_A(CHIPS)':
 C_PATH='@baseboard_fab2_lib.baseboard_fab2(sch_1):page76_i199@dev_discrete.cap_~
a(chips)',
 P_PATH='@baseboard_fab2_lib.baseboard_fab2(sch_1):page76_i199@dev_discrete.cap_~
a(chips)',
 PATH='I199',
 DRAWING='@BASEBOARD_FAB2_LIB.BASEBOARD_FAB2(SCH_1):PAGE76',
 TOLERANCE='20%',
 MATERIAL='X6S',
 BOM_COST='PROC',
 PHYS_PAGE='76',
 XY='(-1225,3775)',
 ROT='0',
 VER='1',
 VALUE='22.0UF',
 PACK_TYPE='0603V',
 PART_NUMBER='E15431-004',
 LOCATION='C2D29',
 ROOM='PVCCIN_CPU1_DECAP_VR',
 GROUP='PWR_MCP_CAP',
 CDS_LIB='dev_discrete',
 CDS_PART_NAME='CAP_A_0603V-22.0UF,4V,20%,X6S,A',
 VOLTAGE='4V',
 PRIM_FILE='./archive_libs/discrete/cap_a/chips/chips.prt';

PART_NAME
 C2D30 'CAP_A_0603V-22.0UF,4V,20%,X6S,A':
 GROUP='PWR_MLCC_CAP',
 ROOM='PVCCIN_CPU1_DECAP_VR';

SECTION_NUMBER 1
 '@BASEBOARD_FAB2_LIB.BASEBOARD_FAB2(SCH_1):PAGE76_I83@DEV_DISCRETE.CAP_A(CHIPS)':
 C_PATH='@baseboard_fab2_lib.baseboard_fab2(sch_1):page76_i83@dev_discrete.cap_a~
(chips)',
 P_PATH='@baseboard_fab2_lib.baseboard_fab2(sch_1):page76_i83@dev_discrete.cap_a~
(chips)',
 PATH='I83',
 DRAWING='@BASEBOARD_FAB2_LIB.BASEBOARD_FAB2(SCH_1):PAGE76',
 TOLERANCE='20%',
 MATERIAL='X6S',
 BOM_COST='PROC',
 PHYS_PAGE='76',
 XY='(-5600,3750)',
 ROT='0',
 VER='1',
 VALUE='22.0UF',
 PACK_TYPE='0603V',
 PART_NUMBER='E15431-004',
 LOCATION='C2D30',
 ROOM='PVCCIN_CPU1_DECAP_VR',
 GROUP='PWR_MLCC_CAP',
 CDS_LIB='dev_discrete',
 CDS_PART_NAME='CAP_A_0603V-22.0UF,4V,20%,X6S,A',
 VOLTAGE='4V',
 PRIM_FILE='./archive_libs/discrete/cap_a/chips/chips.prt';

PART_NAME
 C2D31 'CAP_A_0603V-22.0UF,4V,20%,X6S,A':
 GROUP='PWR_MLCC_CAP',
 ROOM='PVCCIN_CPU1_DECAP_VR';

SECTION_NUMBER 1
 '@BASEBOARD_FAB2_LIB.BASEBOARD_FAB2(SCH_1):PAGE76_I63@DEV_DISCRETE.CAP_A(CHIPS)':
 C_PATH='@baseboard_fab2_lib.baseboard_fab2(sch_1):page76_i63@dev_discrete.cap_a~
(chips)',
 P_PATH='@baseboard_fab2_lib.baseboard_fab2(sch_1):page76_i63@dev_discrete.cap_a~
(chips)',
 PATH='I63',
 DRAWING='@BASEBOARD_FAB2_LIB.BASEBOARD_FAB2(SCH_1):PAGE76',
 TOLERANCE='20%',
 MATERIAL='X6S',
 BOM_COST='PROC',
 PHYS_PAGE='76',
 XY='(-5600,4450)',
 ROT='0',
 VER='1',
 VALUE='22.0UF',
 PACK_TYPE='0603V',
 PART_NUMBER='E15431-004',
 LOCATION='C2D31',
 ROOM='PVCCIN_CPU1_DECAP_VR',
 GROUP='PWR_MLCC_CAP',
 CDS_LIB='dev_discrete',
 CDS_PART_NAME='CAP_A_0603V-22.0UF,4V,20%,X6S,A',
 VOLTAGE='4V',
 PRIM_FILE='./archive_libs/discrete/cap_a/chips/chips.prt';

PART_NAME
 C2D32 'CAP_A_0603V-22.0UF,4V,20%,X6S,A':
 GROUP='PWR_MLCC_CAP',
 ROOM='PVCCIN_CPU1_DECAP_VR';

SECTION_NUMBER 1
 '@BASEBOARD_FAB2_LIB.BASEBOARD_FAB2(SCH_1):PAGE76_I90@DEV_DISCRETE.CAP_A(CHIPS)':
 C_PATH='@baseboard_fab2_lib.baseboard_fab2(sch_1):page76_i90@dev_discrete.cap_a~
(chips)',
 P_PATH='@baseboard_fab2_lib.baseboard_fab2(sch_1):page76_i90@dev_discrete.cap_a~
(chips)',
 PATH='I90',
 DRAWING='@BASEBOARD_FAB2_LIB.BASEBOARD_FAB2(SCH_1):PAGE76',
 TOLERANCE='20%',
 MATERIAL='X6S',
 BOM_COST='PROC',
 PHYS_PAGE='76',
 XY='(-5900,3050)',
 ROT='0',
 VER='1',
 VALUE='22.0UF',
 PACK_TYPE='0603V',
 PART_NUMBER='E15431-004',
 LOCATION='C2D32',
 ROOM='PVCCIN_CPU1_DECAP_VR',
 GROUP='PWR_MLCC_CAP',
 CDS_LIB='dev_discrete',
 CDS_PART_NAME='CAP_A_0603V-22.0UF,4V,20%,X6S,A',
 VOLTAGE='4V',
 PRIM_FILE='./archive_libs/discrete/cap_a/chips/chips.prt';

PART_NAME
 C2D33 'CAP_A_0603V-22.0UF,4V,20%,X6S,A':
 GROUP='PWR_MLCC_CAP',
 ROOM='PVCCIN_CPU1_DECAP_VR';

SECTION_NUMBER 1
 '@BASEBOARD_FAB2_LIB.BASEBOARD_FAB2(SCH_1):PAGE76_I85@DEV_DISCRETE.CAP_A(CHIPS)':
 C_PATH='@baseboard_fab2_lib.baseboard_fab2(sch_1):page76_i85@dev_discrete.cap_a~
(chips)',
 P_PATH='@baseboard_fab2_lib.baseboard_fab2(sch_1):page76_i85@dev_discrete.cap_a~
(chips)',
 PATH='I85',
 DRAWING='@BASEBOARD_FAB2_LIB.BASEBOARD_FAB2(SCH_1):PAGE76',
 TOLERANCE='20%',
 MATERIAL='X6S',
 BOM_COST='PROC',
 PHYS_PAGE='76',
 XY='(-5900,3750)',
 ROT='0',
 VER='1',
 VALUE='22.0UF',
 PACK_TYPE='0603V',
 PART_NUMBER='E15431-004',
 LOCATION='C2D33',
 ROOM='PVCCIN_CPU1_DECAP_VR',
 GROUP='PWR_MLCC_CAP',
 CDS_LIB='dev_discrete',
 CDS_PART_NAME='CAP_A_0603V-22.0UF,4V,20%,X6S,A',
 VOLTAGE='4V',
 PRIM_FILE='./archive_libs/discrete/cap_a/chips/chips.prt';

PART_NAME
 C2D34 'CAP_A_0603V-22.0UF,4V,20%,X6S,A':
 GROUP='PWR_MLCC_CAP',
 ROOM='PVCCIN_CPU1_DECAP_VR';

SECTION_NUMBER 1
 '@BASEBOARD_FAB2_LIB.BASEBOARD_FAB2(SCH_1):PAGE76_I122@DEV_DISCRETE.CAP_A(CHIPS)':
 C_PATH='@baseboard_fab2_lib.baseboard_fab2(sch_1):page76_i122@dev_discrete.cap_~
a(chips)',
 P_PATH='@baseboard_fab2_lib.baseboard_fab2(sch_1):page76_i122@dev_discrete.cap_~
a(chips)',
 PATH='I122',
 DRAWING='@BASEBOARD_FAB2_LIB.BASEBOARD_FAB2(SCH_1):PAGE76',
 TOLERANCE='20%',
 MATERIAL='X6S',
 BOM_COST='PROC',
 PHYS_PAGE='76',
 XY='(-7750,3750)',
 ROT='0',
 VER='1',
 VALUE='22.0UF',
 PACK_TYPE='0603V',
 PART_NUMBER='E15431-004',
 LOCATION='C2D34',
 ROOM='PVCCIN_CPU1_DECAP_VR',
 GROUP='PWR_MLCC_CAP',
 CDS_LIB='dev_discrete',
 CDS_PART_NAME='CAP_A_0603V-22.0UF,4V,20%,X6S,A',
 VOLTAGE='4V',
 PRIM_FILE='./archive_libs/discrete/cap_a/chips/chips.prt';

PART_NAME
 C2D35 'CAP_A_0603V-22.0UF,4V,20%,X6S,A':
 GROUP='PWR_MLCC_CAP',
 ROOM='PVCCIN_CPU1_DECAP_VR';

SECTION_NUMBER 1
 '@BASEBOARD_FAB2_LIB.BASEBOARD_FAB2(SCH_1):PAGE76_I161@DEV_DISCRETE.CAP_A(CHIPS)':
 C_PATH='@baseboard_fab2_lib.baseboard_fab2(sch_1):page76_i161@dev_discrete.cap_~
a(chips)',
 P_PATH='@baseboard_fab2_lib.baseboard_fab2(sch_1):page76_i161@dev_discrete.cap_~
a(chips)',
 PATH='I161',
 DRAWING='@BASEBOARD_FAB2_LIB.BASEBOARD_FAB2(SCH_1):PAGE76',
 TOLERANCE='20%',
 MATERIAL='X6S',
 BOM_COST='PROC',
 PHYS_PAGE='76',
 XY='(-4500,3050)',
 ROT='0',
 VER='1',
 VALUE='22.0UF',
 PACK_TYPE='0603V',
 PART_NUMBER='E15431-004',
 LOCATION='C2D35',
 ROOM='PVCCIN_CPU1_DECAP_VR',
 GROUP='PWR_MLCC_CAP',
 CDS_LIB='dev_discrete',
 CDS_PART_NAME='CAP_A_0603V-22.0UF,4V,20%,X6S,A',
 VOLTAGE='4V',
 PRIM_FILE='./archive_libs/discrete/cap_a/chips/chips.prt';

PART_NAME
 C2D36 'CAP_A_0603V-22.0UF,4V,20%,X6S,A':
 GROUP='PWR_MLCC_CAP',
 ROOM='PVCCIN_CPU1_DECAP_VR';

SECTION_NUMBER 1
 '@BASEBOARD_FAB2_LIB.BASEBOARD_FAB2(SCH_1):PAGE76_I70@DEV_DISCRETE.CAP_A(CHIPS)':
 C_PATH='@baseboard_fab2_lib.baseboard_fab2(sch_1):page76_i70@dev_discrete.cap_a~
(chips)',
 P_PATH='@baseboard_fab2_lib.baseboard_fab2(sch_1):page76_i70@dev_discrete.cap_a~
(chips)',
 PATH='I70',
 DRAWING='@BASEBOARD_FAB2_LIB.BASEBOARD_FAB2(SCH_1):PAGE76',
 TOLERANCE='20%',
 MATERIAL='X6S',
 BOM_COST='PROC',
 PHYS_PAGE='76',
 XY='(-7650,4450)',
 ROT='0',
 VER='1',
 VALUE='22.0UF',
 PACK_TYPE='0603V',
 PART_NUMBER='E15431-004',
 LOCATION='C2D36',
 ROOM='PVCCIN_CPU1_DECAP_VR',
 GROUP='PWR_MLCC_CAP',
 CDS_LIB='dev_discrete',
 CDS_PART_NAME='CAP_A_0603V-22.0UF,4V,20%,X6S,A',
 VOLTAGE='4V',
 PRIM_FILE='./archive_libs/discrete/cap_a/chips/chips.prt';

PART_NAME
 C2D37 'CAP_A_0603V-22.0UF,4V,20%,X6S,A':
 GROUP='PWR_MLCC_CAP',
 ROOM='PVCCIN_CPU1_DECAP_VR';

SECTION_NUMBER 1
 '@BASEBOARD_FAB2_LIB.BASEBOARD_FAB2(SCH_1):PAGE76_I119@DEV_DISCRETE.CAP_A(CHIPS)':
 C_PATH='@baseboard_fab2_lib.baseboard_fab2(sch_1):page76_i119@dev_discrete.cap_~
a(chips)',
 P_PATH='@baseboard_fab2_lib.baseboard_fab2(sch_1):page76_i119@dev_discrete.cap_~
a(chips)',
 PATH='I119',
 DRAWING='@BASEBOARD_FAB2_LIB.BASEBOARD_FAB2(SCH_1):PAGE76',
 TOLERANCE='20%',
 MATERIAL='X6S',
 BOM_COST='PROC',
 PHYS_PAGE='76',
 XY='(-7450,3750)',
 ROT='0',
 VER='1',
 VALUE='22.0UF',
 PACK_TYPE='0603V',
 PART_NUMBER='E15431-004',
 LOCATION='C2D37',
 ROOM='PVCCIN_CPU1_DECAP_VR',
 GROUP='PWR_MLCC_CAP',
 CDS_LIB='dev_discrete',
 CDS_PART_NAME='CAP_A_0603V-22.0UF,4V,20%,X6S,A',
 VOLTAGE='4V',
 PRIM_FILE='./archive_libs/discrete/cap_a/chips/chips.prt';

PART_NAME
 C2D38 'CAP_A_0603V-22.0UF,4V,20%,X6S,A':
 GROUP='PWR_MLCC_CAP',
 ROOM='PVCCIN_CPU1_DECAP_VR';

SECTION_NUMBER 1
 '@BASEBOARD_FAB2_LIB.BASEBOARD_FAB2(SCH_1):PAGE76_I160@DEV_DISCRETE.CAP_A(CHIPS)':
 C_PATH='@baseboard_fab2_lib.baseboard_fab2(sch_1):page76_i160@dev_discrete.cap_~
a(chips)',
 P_PATH='@baseboard_fab2_lib.baseboard_fab2(sch_1):page76_i160@dev_discrete.cap_~
a(chips)',
 PATH='I160',
 DRAWING='@BASEBOARD_FAB2_LIB.BASEBOARD_FAB2(SCH_1):PAGE76',
 TOLERANCE='20%',
 MATERIAL='X6S',
 BOM_COST='PROC',
 PHYS_PAGE='76',
 XY='(-4400,3750)',
 ROT='0',
 VER='1',
 VALUE='22.0UF',
 PACK_TYPE='0603V',
 PART_NUMBER='E15431-004',
 LOCATION='C2D38',
 ROOM='PVCCIN_CPU1_DECAP_VR',
 GROUP='PWR_MLCC_CAP',
 CDS_LIB='dev_discrete',
 CDS_PART_NAME='CAP_A_0603V-22.0UF,4V,20%,X6S,A',
 VOLTAGE='4V',
 PRIM_FILE='./archive_libs/discrete/cap_a/chips/chips.prt';

PART_NAME
 C2D39 'CAP_A_0603V-22.0UF,4V,20%,X6S,A':
 GROUP='PWR_MCP_CAP',
 ROOM='PVCCIN_CPU1_DECAP_VR';

SECTION_NUMBER 1
 '@BASEBOARD_FAB2_LIB.BASEBOARD_FAB2(SCH_1):PAGE76_I165@DEV_DISCRETE.CAP_A(CHIPS)':
 C_PATH='@baseboard_fab2_lib.baseboard_fab2(sch_1):page76_i165@dev_discrete.cap_~
a(chips)',
 P_PATH='@baseboard_fab2_lib.baseboard_fab2(sch_1):page76_i165@dev_discrete.cap_~
a(chips)',
 PATH='I165',
 DRAWING='@BASEBOARD_FAB2_LIB.BASEBOARD_FAB2(SCH_1):PAGE76',
 TOLERANCE='20%',
 MATERIAL='X6S',
 BOM_COST='PROC',
 PHYS_PAGE='76',
 XY='(-3750,4450)',
 ROT='0',
 VER='1',
 VALUE='22.0UF',
 PACK_TYPE='0603V',
 PART_NUMBER='E15431-004',
 LOCATION='C2D39',
 ROOM='PVCCIN_CPU1_DECAP_VR',
 GROUP='PWR_MCP_CAP',
 CDS_LIB='dev_discrete',
 CDS_PART_NAME='CAP_A_0603V-22.0UF,4V,20%,X6S,A',
 VOLTAGE='4V',
 PRIM_FILE='./archive_libs/discrete/cap_a/chips/chips.prt';

PART_NAME
 C2D40 'CAP_A_0603V-22.0UF,4V,20%,X6S,A':
 GROUP='PWR_MCP_CAP',
 ROOM='PVCCIN_CPU1_DECAP_VR';

SECTION_NUMBER 1
 '@BASEBOARD_FAB2_LIB.BASEBOARD_FAB2(SCH_1):PAGE76_I10@DEV_DISCRETE.CAP_A(CHIPS)':
 C_PATH='@baseboard_fab2_lib.baseboard_fab2(sch_1):page76_i10@dev_discrete.cap_a~
(chips)',
 P_PATH='@baseboard_fab2_lib.baseboard_fab2(sch_1):page76_i10@dev_discrete.cap_a~
(chips)',
 PATH='I10',
 DRAWING='@BASEBOARD_FAB2_LIB.BASEBOARD_FAB2(SCH_1):PAGE76',
 TOLERANCE='20%',
 MATERIAL='X6S',
 BOM_COST='PROC',
 PHYS_PAGE='76',
 XY='(-3250,4450)',
 ROT='0',
 VER='1',
 VALUE='22.0UF',
 PACK_TYPE='0603V',
 PART_NUMBER='E15431-004',
 LOCATION='C2D40',
 ROOM='PVCCIN_CPU1_DECAP_VR',
 GROUP='PWR_MCP_CAP',
 CDS_LIB='dev_discrete',
 CDS_PART_NAME='CAP_A_0603V-22.0UF,4V,20%,X6S,A',
 VOLTAGE='4V',
 PRIM_FILE='./archive_libs/discrete/cap_a/chips/chips.prt';

PART_NAME
 C2D41 'CAP_A_0603V-22.0UF,4V,20%,X6S,A':
 GROUP='PWR_MLCC_CAP',
 ROOM='PVCCIN_CPU0_DECAP_VR';

SECTION_NUMBER 1
 '@BASEBOARD_FAB2_LIB.BASEBOARD_FAB2(SCH_1):PAGE225_I271@DEV_DISCRETE.CAP_A(CHIPS)':
 C_PATH='@baseboard_fab2_lib.baseboard_fab2(sch_1):page225_i271@dev_discrete.cap~
_a(chips)',
 P_PATH='@baseboard_fab2_lib.baseboard_fab2(sch_1):page225_i271@dev_discrete.cap~
_a(chips)',
 PATH='I271',
 DRAWING='@BASEBOARD_FAB2_LIB.BASEBOARD_FAB2(SCH_1):PAGE225',
 TOLERANCE='20%',
 MATERIAL='X6S',
 BOM_COST='PROC_SOCKET',
 PHYS_PAGE='225',
 XY='(-1100,3100)',
 ROT='0',
 VER='1',
 VALUE='22.0UF',
 PACK_TYPE='0603V',
 PART_NUMBER='E15431-004',
 LOCATION='C2D41',
 ROOM='PVCCIN_CPU0_DECAP_VR',
 GROUP='PWR_MLCC_CAP',
 CDS_LIB='dev_discrete',
 CDS_PART_NAME='CAP_A_0603V-22.0UF,4V,20%,X6S,A',
 VOLTAGE='4V',
 PRIM_FILE='./archive_libs/discrete/cap_a/chips/chips.prt';

PART_NAME
 C2D42 'CAP_A_0603V-22.0UF,4V,20%,X6S,A':
 GROUP='PWR_MLCC_CAP',
 ROOM='PVCCIN_CPU0_DECAP_VR';

SECTION_NUMBER 1
 '@BASEBOARD_FAB2_LIB.BASEBOARD_FAB2(SCH_1):PAGE225_I273@DEV_DISCRETE.CAP_A(CHIPS)':
 C_PATH='@baseboard_fab2_lib.baseboard_fab2(sch_1):page225_i273@dev_discrete.cap~
_a(chips)',
 P_PATH='@baseboard_fab2_lib.baseboard_fab2(sch_1):page225_i273@dev_discrete.cap~
_a(chips)',
 PATH='I273',
 DRAWING='@BASEBOARD_FAB2_LIB.BASEBOARD_FAB2(SCH_1):PAGE225',
 TOLERANCE='20%',
 MATERIAL='X6S',
 BOM_COST='PROC_SOCKET',
 PHYS_PAGE='225',
 XY='(-350,3100)',
 ROT='0',
 VER='1',
 VALUE='22.0UF',
 PACK_TYPE='0603V',
 PART_NUMBER='E15431-004',
 LOCATION='C2D42',
 ROOM='PVCCIN_CPU0_DECAP_VR',
 GROUP='PWR_MLCC_CAP',
 CDS_LIB='dev_discrete',
 CDS_PART_NAME='CAP_A_0603V-22.0UF,4V,20%,X6S,A',
 VOLTAGE='4V',
 PRIM_FILE='./archive_libs/discrete/cap_a/chips/chips.prt';

PART_NAME
 C2D43 'CAP_A_0603V-22.0UF,4V,20%,X6S,A':
 GROUP='PWR_MLCC_CAP',
 ROOM='PVCCIN_CPU0_DECAP_VR';

SECTION_NUMBER 1
 '@BASEBOARD_FAB2_LIB.BASEBOARD_FAB2(SCH_1):PAGE225_I270@DEV_DISCRETE.CAP_A(CHIPS)':
 C_PATH='@baseboard_fab2_lib.baseboard_fab2(sch_1):page225_i270@dev_discrete.cap~
_a(chips)',
 P_PATH='@baseboard_fab2_lib.baseboard_fab2(sch_1):page225_i270@dev_discrete.cap~
_a(chips)',
 PATH='I270',
 DRAWING='@BASEBOARD_FAB2_LIB.BASEBOARD_FAB2(SCH_1):PAGE225',
 TOLERANCE='20%',
 MATERIAL='X6S',
 BOM_COST='PROC_SOCKET',
 PHYS_PAGE='225',
 XY='(-1450,3100)',
 ROT='0',
 VER='1',
 VALUE='22.0UF',
 PACK_TYPE='0603V',
 PART_NUMBER='E15431-004',
 LOCATION='C2D43',
 ROOM='PVCCIN_CPU0_DECAP_VR',
 GROUP='PWR_MLCC_CAP',
 CDS_LIB='dev_discrete',
 CDS_PART_NAME='CAP_A_0603V-22.0UF,4V,20%,X6S,A',
 VOLTAGE='4V',
 PRIM_FILE='./archive_libs/discrete/cap_a/chips/chips.prt';

PART_NAME
 C2D44 'CAP_A_0603V-22.0UF,4V,20%,X6S,A':
 GROUP='PWR_MLCC_CAP',
 ROOM='PVCCIN_CPU0_DECAP_VR';

SECTION_NUMBER 1
 '@BASEBOARD_FAB2_LIB.BASEBOARD_FAB2(SCH_1):PAGE225_I272@DEV_DISCRETE.CAP_A(CHIPS)':
 C_PATH='@baseboard_fab2_lib.baseboard_fab2(sch_1):page225_i272@dev_discrete.cap~
_a(chips)',
 P_PATH='@baseboard_fab2_lib.baseboard_fab2(sch_1):page225_i272@dev_discrete.cap~
_a(chips)',
 PATH='I272',
 DRAWING='@BASEBOARD_FAB2_LIB.BASEBOARD_FAB2(SCH_1):PAGE225',
 TOLERANCE='20%',
 MATERIAL='X6S',
 BOM_COST='PROC_SOCKET',
 PHYS_PAGE='225',
 XY='(-750,3100)',
 ROT='0',
 VER='1',
 VALUE='22.0UF',
 PACK_TYPE='0603V',
 PART_NUMBER='E15431-004',
 LOCATION='C2D44',
 ROOM='PVCCIN_CPU0_DECAP_VR',
 GROUP='PWR_MLCC_CAP',
 CDS_LIB='dev_discrete',
 CDS_PART_NAME='CAP_A_0603V-22.0UF,4V,20%,X6S,A',
 VOLTAGE='4V',
 PRIM_FILE='./archive_libs/discrete/cap_a/chips/chips.prt';

PART_NAME
 C2D45 'CAP_A_0603V-22.0UF,4V,20%,X6S,A':
 GROUP='PWR_MLCC_CAP',
 ROOM='PVCCIN_CPU1_DECAP_VR';

SECTION_NUMBER 1
 '@BASEBOARD_FAB2_LIB.BASEBOARD_FAB2(SCH_1):PAGE225_I261@DEV_DISCRETE.CAP_A(CHIPS)':
 C_PATH='@baseboard_fab2_lib.baseboard_fab2(sch_1):page225_i261@dev_discrete.cap~
_a(chips)',
 P_PATH='@baseboard_fab2_lib.baseboard_fab2(sch_1):page225_i261@dev_discrete.cap~
_a(chips)',
 PATH='I261',
 DRAWING='@BASEBOARD_FAB2_LIB.BASEBOARD_FAB2(SCH_1):PAGE225',
 TOLERANCE='20%',
 MATERIAL='X6S',
 BOM_COST='PROC',
 PHYS_PAGE='225',
 XY='(700,2100)',
 ROT='0',
 VER='1',
 VALUE='22.0UF',
 PACK_TYPE='0603V',
 PART_NUMBER='E15431-004',
 LOCATION='C2D45',
 ROOM='PVCCIN_CPU1_DECAP_VR',
 GROUP='PWR_MLCC_CAP',
 CDS_LIB='dev_discrete',
 CDS_PART_NAME='CAP_A_0603V-22.0UF,4V,20%,X6S,A',
 VOLTAGE='4V',
 PRIM_FILE='./archive_libs/discrete/cap_a/chips/chips.prt';

PART_NAME
 C2D46 'CAP_A_0603V-22.0UF,4V,20%,X6S,A':
 GROUP='PWR_MLCC_CAP',
 ROOM='PVCCIN_CPU1_DECAP_VR';

SECTION_NUMBER 1
 '@BASEBOARD_FAB2_LIB.BASEBOARD_FAB2(SCH_1):PAGE225_I264@DEV_DISCRETE.CAP_A(CHIPS)':
 C_PATH='@baseboard_fab2_lib.baseboard_fab2(sch_1):page225_i264@dev_discrete.cap~
_a(chips)',
 P_PATH='@baseboard_fab2_lib.baseboard_fab2(sch_1):page225_i264@dev_discrete.cap~
_a(chips)',
 PATH='I264',
 DRAWING='@BASEBOARD_FAB2_LIB.BASEBOARD_FAB2(SCH_1):PAGE225',
 TOLERANCE='20%',
 SEC_TYPE='0603V',
 MATERIAL='X6S',
 BOM_COST='PROC',
 PHYS_PAGE='225',
 XY='(1000,2100)',
 ROT='0',
 VER='1',
 VALUE='22.0UF',
 PACK_TYPE='0603V',
 PART_NUMBER='E15431-004',
 LOCATION='C2D46',
 ROOM='PVCCIN_CPU1_DECAP_VR',
 GROUP='PWR_MLCC_CAP',
 SEC='1',
 CDS_LIB='dev_discrete',
 CDS_PART_NAME='CAP_A_0603V-22.0UF,4V,20%,X6S,A',
 VOLTAGE='4V',
 PRIM_FILE='./archive_libs/discrete/cap_a/chips/chips.prt';

PART_NAME
 C2D47 'CAP_A_0603V-22.0UF,4V,20%,X6S,A':
 GROUP='PWR_MLCC_CAP',
 ROOM='PVCCIN_CPU1_DECAP_VR';

SECTION_NUMBER 1
 '@BASEBOARD_FAB2_LIB.BASEBOARD_FAB2(SCH_1):PAGE225_I263@DEV_DISCRETE.CAP_A(CHIPS)':
 C_PATH='@baseboard_fab2_lib.baseboard_fab2(sch_1):page225_i263@dev_discrete.cap~
_a(chips)',
 P_PATH='@baseboard_fab2_lib.baseboard_fab2(sch_1):page225_i263@dev_discrete.cap~
_a(chips)',
 PATH='I263',
 DRAWING='@BASEBOARD_FAB2_LIB.BASEBOARD_FAB2(SCH_1):PAGE225',
 TOLERANCE='20%',
 SEC_TYPE='0603V',
 MATERIAL='X6S',
 BOM_COST='PROC',
 PHYS_PAGE='225',
 XY='(1300,2100)',
 ROT='0',
 VER='1',
 VALUE='22.0UF',
 PACK_TYPE='0603V',
 PART_NUMBER='E15431-004',
 LOCATION='C2D47',
 ROOM='PVCCIN_CPU1_DECAP_VR',
 GROUP='PWR_MLCC_CAP',
 SEC='1',
 CDS_LIB='dev_discrete',
 CDS_PART_NAME='CAP_A_0603V-22.0UF,4V,20%,X6S,A',
 VOLTAGE='4V',
 PRIM_FILE='./archive_libs/discrete/cap_a/chips/chips.prt';

PART_NAME
 C2F1 'CAP_A_0603V-47UF,4V,20%,X5R,60A':
 GROUP='PWR_MLCC_CAP';

SECTION_NUMBER 1
 '@BASEBOARD_FAB2_LIB.BASEBOARD_FAB2(SCH_1):PAGE225_I201@DEV_DISCRETE.CAP_A(CHIPS)':
 C_PATH='@baseboard_fab2_lib.baseboard_fab2(sch_1):page225_i201@dev_discrete.cap~
_a(chips)',
 P_PATH='@baseboard_fab2_lib.baseboard_fab2(sch_1):page225_i201@dev_discrete.cap~
_a(chips)',
 PATH='I201',
 DRAWING='@BASEBOARD_FAB2_LIB.BASEBOARD_FAB2(SCH_1):PAGE225',
 BOM_SS='NOPOP',
 TOLERANCE='20%',
 SEC_TYPE='0603V',
 MATERIAL='X5R',
 PHYS_PAGE='225',
 XY='(3300,1725)',
 ROT='0',
 VER='1',
 VALUE='47UF',
 PACK_TYPE='0603V',
 PART_NUMBER='602433-106',
 LOCATION='C2F1',
 GROUP='PWR_MLCC_CAP',
 SEC='1',
 CDS_LIB='dev_discrete',
 CDS_PART_NAME='CAP_A_0603V-47UF,4V,20%,X5R,60A',
 VOLTAGE='4V',
 PRIM_FILE='./archive_libs/discrete/cap_a/chips/chips.prt';

PART_NAME
 C2F2 'CAP_A_0603V-47UF,4V,20%,X5R,60A':
 GROUP='PWR_MLCC_CAP';

SECTION_NUMBER 1
 '@BASEBOARD_FAB2_LIB.BASEBOARD_FAB2(SCH_1):PAGE229_I28@DEV_DISCRETE.CAP_A(CHIPS)':
 C_PATH='@baseboard_fab2_lib.baseboard_fab2(sch_1):page229_i28@dev_discrete.cap_~
a(chips)',
 P_PATH='@baseboard_fab2_lib.baseboard_fab2(sch_1):page229_i28@dev_discrete.cap_~
a(chips)',
 PATH='I28',
 DRAWING='@BASEBOARD_FAB2_LIB.BASEBOARD_FAB2(SCH_1):PAGE229',
 TOLERANCE='20%',
 SEC_TYPE='0603V',
 MATERIAL='X5R',
 PHYS_PAGE='229',
 XY='(3400,3200)',
 ROT='0',
 VER='1',
 VALUE='47UF',
 PACK_TYPE='0603V',
 PART_NUMBER='602433-106',
 LOCATION='C2F2',
 GROUP='PWR_MLCC_CAP',
 SEC='1',
 CDS_LIB='dev_discrete',
 CDS_PART_NAME='CAP_A_0603V-47UF,4V,20%,X5R,60A',
 VOLTAGE='4V',
 PRIM_FILE='./archive_libs/discrete/cap_a/chips/chips.prt';

PART_NAME
 C2G1 'CAP_A_0603V-47UF,4V,20%,X5R,60A':
 GROUP='PWR_MLCC_CAP';

SECTION_NUMBER 1
 '@BASEBOARD_FAB2_LIB.BASEBOARD_FAB2(SCH_1):PAGE225_I277@DEV_DISCRETE.CAP_A(CHIPS)':
 C_PATH='@baseboard_fab2_lib.baseboard_fab2(sch_1):page225_i277@dev_discrete.cap~
_a(chips)',
 P_PATH='@baseboard_fab2_lib.baseboard_fab2(sch_1):page225_i277@dev_discrete.cap~
_a(chips)',
 PATH='I277',
 DRAWING='@BASEBOARD_FAB2_LIB.BASEBOARD_FAB2(SCH_1):PAGE225',
 BOM_SS='E15431-004',
 TOLERANCE='20%',
 SEC_TYPE='0603V',
 MATERIAL='X5R',
 PHYS_PAGE='225',
 XY='(-1400,250)',
 ROT='0',
 VER='1',
 VALUE='47UF',
 PACK_TYPE='0603V',
 PART_NUMBER='602433-106',
 LOCATION='C2G1',
 GROUP='PWR_MLCC_CAP',
 SEC='1',
 CDS_LIB='dev_discrete',
 CDS_PART_NAME='CAP_A_0603V-47UF,4V,20%,X5R,60A',
 VOLTAGE='4V',
 PRIM_FILE='./archive_libs/discrete/cap_a/chips/chips.prt';

PART_NAME
 C2G2 'CAP_A_0603V-47UF,4V,20%,X5R,60A':
 GROUP='PWR_MLCC_CAP';

SECTION_NUMBER 1
 '@BASEBOARD_FAB2_LIB.BASEBOARD_FAB2(SCH_1):PAGE225_I279@DEV_DISCRETE.CAP_A(CHIPS)':
 C_PATH='@baseboard_fab2_lib.baseboard_fab2(sch_1):page225_i279@dev_discrete.cap~
_a(chips)',
 P_PATH='@baseboard_fab2_lib.baseboard_fab2(sch_1):page225_i279@dev_discrete.cap~
_a(chips)',
 PATH='I279',
 DRAWING='@BASEBOARD_FAB2_LIB.BASEBOARD_FAB2(SCH_1):PAGE225',
 BOM_SS='E15431-004',
 TOLERANCE='20%',
 SEC_TYPE='0603V',
 MATERIAL='X5R',
 PHYS_PAGE='225',
 XY='(-825,250)',
 ROT='0',
 VER='1',
 VALUE='47UF',
 PACK_TYPE='0603V',
 PART_NUMBER='602433-106',
 LOCATION='C2G2',
 GROUP='PWR_MLCC_CAP',
 SEC='1',
 CDS_LIB='dev_discrete',
 CDS_PART_NAME='CAP_A_0603V-47UF,4V,20%,X5R,60A',
 VOLTAGE='4V',
 PRIM_FILE='./archive_libs/discrete/cap_a/chips/chips.prt';

PART_NAME
 C2G3 'CAP_A_0603V-47UF,4V,20%,X5R,60A':
 GROUP='PWR_MLCC_CAP';

SECTION_NUMBER 1
 '@BASEBOARD_FAB2_LIB.BASEBOARD_FAB2(SCH_1):PAGE225_I280@DEV_DISCRETE.CAP_A(CHIPS)':
 C_PATH='@baseboard_fab2_lib.baseboard_fab2(sch_1):page225_i280@dev_discrete.cap~
_a(chips)',
 P_PATH='@baseboard_fab2_lib.baseboard_fab2(sch_1):page225_i280@dev_discrete.cap~
_a(chips)',
 PATH='I280',
 DRAWING='@BASEBOARD_FAB2_LIB.BASEBOARD_FAB2(SCH_1):PAGE225',
 BOM_SS='E15431-004',
 TOLERANCE='20%',
 SEC_TYPE='0603V',
 MATERIAL='X5R',
 PHYS_PAGE='225',
 XY='(-525,250)',
 ROT='0',
 VER='1',
 VALUE='47UF',
 PACK_TYPE='0603V',
 PART_NUMBER='602433-106',
 LOCATION='C2G3',
 GROUP='PWR_MLCC_CAP',
 SEC='1',
 CDS_LIB='dev_discrete',
 CDS_PART_NAME='CAP_A_0603V-47UF,4V,20%,X5R,60A',
 VOLTAGE='4V',
 PRIM_FILE='./archive_libs/discrete/cap_a/chips/chips.prt';

PART_NAME
 C2G4 'CAP_A_0603V-47UF,4V,20%,X5R,60A':
 GROUP='PWR_MLCC_CAP';

SECTION_NUMBER 1
 '@BASEBOARD_FAB2_LIB.BASEBOARD_FAB2(SCH_1):PAGE225_I281@DEV_DISCRETE.CAP_A(CHIPS)':
 C_PATH='@baseboard_fab2_lib.baseboard_fab2(sch_1):page225_i281@dev_discrete.cap~
_a(chips)',
 P_PATH='@baseboard_fab2_lib.baseboard_fab2(sch_1):page225_i281@dev_discrete.cap~
_a(chips)',
 PATH='I281',
 DRAWING='@BASEBOARD_FAB2_LIB.BASEBOARD_FAB2(SCH_1):PAGE225',
 BOM_SS='E15431-004',
 TOLERANCE='20%',
 SEC_TYPE='0603V',
 MATERIAL='X5R',
 PHYS_PAGE='225',
 XY='(-250,250)',
 ROT='0',
 VER='1',
 VALUE='47UF',
 PACK_TYPE='0603V',
 PART_NUMBER='602433-106',
 LOCATION='C2G4',
 GROUP='PWR_MLCC_CAP',
 SEC='1',
 CDS_LIB='dev_discrete',
 CDS_PART_NAME='CAP_A_0603V-47UF,4V,20%,X5R,60A',
 VOLTAGE='4V',
 PRIM_FILE='./archive_libs/discrete/cap_a/chips/chips.prt';

PART_NAME
 C2G5 'CAP_A_0603V-47UF,4V,20%,X5R,60A':
 GROUP='PWR_MLCC_CAP';

SECTION_NUMBER 1
 '@BASEBOARD_FAB2_LIB.BASEBOARD_FAB2(SCH_1):PAGE225_I282@DEV_DISCRETE.CAP_A(CHIPS)':
 C_PATH='@baseboard_fab2_lib.baseboard_fab2(sch_1):page225_i282@dev_discrete.cap~
_a(chips)',
 P_PATH='@baseboard_fab2_lib.baseboard_fab2(sch_1):page225_i282@dev_discrete.cap~
_a(chips)',
 PATH='I282',
 DRAWING='@BASEBOARD_FAB2_LIB.BASEBOARD_FAB2(SCH_1):PAGE225',
 BOM_SS='E15431-004',
 TOLERANCE='20%',
 SEC_TYPE='0603V',
 MATERIAL='X5R',
 PHYS_PAGE='225',
 XY='(75,250)',
 ROT='0',
 VER='1',
 VALUE='47UF',
 PACK_TYPE='0603V',
 PART_NUMBER='602433-106',
 LOCATION='C2G5',
 GROUP='PWR_MLCC_CAP',
 SEC='1',
 CDS_LIB='dev_discrete',
 CDS_PART_NAME='CAP_A_0603V-47UF,4V,20%,X5R,60A',
 VOLTAGE='4V',
 PRIM_FILE='./archive_libs/discrete/cap_a/chips/chips.prt';

PART_NAME
 C2G6 'CAP_A_0603V-47UF,4V,20%,X5R,60A':
 GROUP='PWR_MLCC_CAP';

SECTION_NUMBER 1
 '@BASEBOARD_FAB2_LIB.BASEBOARD_FAB2(SCH_1):PAGE225_I283@DEV_DISCRETE.CAP_A(CHIPS)':
 C_PATH='@baseboard_fab2_lib.baseboard_fab2(sch_1):page225_i283@dev_discrete.cap~
_a(chips)',
 P_PATH='@baseboard_fab2_lib.baseboard_fab2(sch_1):page225_i283@dev_discrete.cap~
_a(chips)',
 PATH='I283',
 DRAWING='@BASEBOARD_FAB2_LIB.BASEBOARD_FAB2(SCH_1):PAGE225',
 BOM_SS='E15431-004',
 TOLERANCE='20%',
 SEC_TYPE='0603V',
 MATERIAL='X5R',
 PHYS_PAGE='225',
 XY='(375,250)',
 ROT='0',
 VER='1',
 VALUE='47UF',
 PACK_TYPE='0603V',
 PART_NUMBER='602433-106',
 LOCATION='C2G6',
 GROUP='PWR_MLCC_CAP',
 SEC='1',
 CDS_LIB='dev_discrete',
 CDS_PART_NAME='CAP_A_0603V-47UF,4V,20%,X5R,60A',
 VOLTAGE='4V',
 PRIM_FILE='./archive_libs/discrete/cap_a/chips/chips.prt';

PART_NAME
 C2G7 'CAP_0805-100UF,4V,20%,X5R,6024A':
 GROUP='PWR_MLCC_CAP',
 ROOM='VDDQ_ABC_PWR_VR';

SECTION_NUMBER 1
 '@BASEBOARD_FAB2_LIB.BASEBOARD_FAB2(SCH_1):PAGE225_I312@MSTR_DISCRETE.CAP(CHIPS)':
 C_PATH='@baseboard_fab2_lib.baseboard_fab2(sch_1):page225_i312@mstr_discrete.ca~
p(chips)',
 P_PATH='@baseboard_fab2_lib.baseboard_fab2(sch_1):page225_i312@mstr_discrete.ca~
p(chips)',
 PATH='I312',
 DRAWING='@BASEBOARD_FAB2_LIB.BASEBOARD_FAB2(SCH_1):PAGE225',
 NEW_PN='078.1071T.M002',
 NEW_MATERIAL='X6S',
 BOM_SS='NOPOP',
 TOLERANCE='20%',
 SEC_TYPE='0805',
 MATERIAL='X5R',
 BOM_COST='MEM_VRD_PVDDQ_CD',
 PHYS_PAGE='225',
 XY='(2750,2825)',
 ROT='0',
 VER='1',
 VALUE='100UF',
 PACK_TYPE='0805',
 PART_NUMBER='602433-112',
 LOCATION='C2G7',
 ROOM='VDDQ_ABC_PWR_VR',
 GROUP='PWR_MLCC_CAP',
 SEC='1',
 CDS_LIB='mstr_discrete',
 CDS_PART_NAME='CAP_0805-100UF,4V,20%,X5R,6024A',
 VOLTAGE='4V',
 PRIM_FILE='./archive_libs/mstr_discrete/cap/chips/chips.prt';

PART_NAME
 C2G8 'CAP_A_0603V-47UF,4V,20%,X5R,60A':
 GROUP='PWR_MLCC_CAP';

SECTION_NUMBER 1
 '@BASEBOARD_FAB2_LIB.BASEBOARD_FAB2(SCH_1):PAGE225_I197@DEV_DISCRETE.CAP_A(CHIPS)':
 C_PATH='@baseboard_fab2_lib.baseboard_fab2(sch_1):page225_i197@dev_discrete.cap~
_a(chips)',
 P_PATH='@baseboard_fab2_lib.baseboard_fab2(sch_1):page225_i197@dev_discrete.cap~
_a(chips)',
 PATH='I197',
 DRAWING='@BASEBOARD_FAB2_LIB.BASEBOARD_FAB2(SCH_1):PAGE225',
 BOM_SS='NOPOP',
 TOLERANCE='20%',
 SEC_TYPE='0603V',
 MATERIAL='X5R',
 PHYS_PAGE='225',
 XY='(2950,975)',
 ROT='0',
 VER='1',
 VALUE='47UF',
 PACK_TYPE='0603V',
 PART_NUMBER='602433-106',
 LOCATION='C2G8',
 GROUP='PWR_MLCC_CAP',
 SEC='1',
 CDS_LIB='dev_discrete',
 CDS_PART_NAME='CAP_A_0603V-47UF,4V,20%,X5R,60A',
 VOLTAGE='4V',
 PRIM_FILE='./archive_libs/discrete/cap_a/chips/chips.prt';

PART_NAME
 C2G9 'CAP_A_0603V-47UF,4V,20%,X5R,60A':
 GROUP='PWR_MLCC_CAP';

SECTION_NUMBER 1
 '@BASEBOARD_FAB2_LIB.BASEBOARD_FAB2(SCH_1):PAGE225_I278@DEV_DISCRETE.CAP_A(CHIPS)':
 C_PATH='@baseboard_fab2_lib.baseboard_fab2(sch_1):page225_i278@dev_discrete.cap~
_a(chips)',
 P_PATH='@baseboard_fab2_lib.baseboard_fab2(sch_1):page225_i278@dev_discrete.cap~
_a(chips)',
 PATH='I278',
 DRAWING='@BASEBOARD_FAB2_LIB.BASEBOARD_FAB2(SCH_1):PAGE225',
 BOM_SS='E15431-004',
 TOLERANCE='20%',
 SEC_TYPE='0603V',
 MATERIAL='X5R',
 PHYS_PAGE='225',
 XY='(-1125,250)',
 ROT='0',
 VER='1',
 VALUE='47UF',
 PACK_TYPE='0603V',
 PART_NUMBER='602433-106',
 LOCATION='C2G9',
 GROUP='PWR_MLCC_CAP',
 SEC='1',
 CDS_LIB='dev_discrete',
 CDS_PART_NAME='CAP_A_0603V-47UF,4V,20%,X5R,60A',
 VOLTAGE='4V',
 PRIM_FILE='./archive_libs/discrete/cap_a/chips/chips.prt';

PART_NAME
 C2G10 'CAP_A_0603V-47UF,4V,20%,X5R,60A':
 GROUP='PWR_MLCC_CAP';

SECTION_NUMBER 1
 '@BASEBOARD_FAB2_LIB.BASEBOARD_FAB2(SCH_1):PAGE225_I274@DEV_DISCRETE.CAP_A(CHIPS)':
 C_PATH='@baseboard_fab2_lib.baseboard_fab2(sch_1):page225_i274@dev_discrete.cap~
_a(chips)',
 P_PATH='@baseboard_fab2_lib.baseboard_fab2(sch_1):page225_i274@dev_discrete.cap~
_a(chips)',
 PATH='I274',
 DRAWING='@BASEBOARD_FAB2_LIB.BASEBOARD_FAB2(SCH_1):PAGE225',
 BOM_SS='E15431-004',
 TOLERANCE='20%',
 SEC_TYPE='0603V',
 MATERIAL='X5R',
 PHYS_PAGE='225',
 XY='(-2275,250)',
 ROT='0',
 VER='1',
 VALUE='47UF',
 PACK_TYPE='0603V',
 PART_NUMBER='602433-106',
 LOCATION='C2G10',
 GROUP='PWR_MLCC_CAP',
 SEC='1',
 CDS_LIB='dev_discrete',
 CDS_PART_NAME='CAP_A_0603V-47UF,4V,20%,X5R,60A',
 VOLTAGE='4V',
 PRIM_FILE='./archive_libs/discrete/cap_a/chips/chips.prt';

PART_NAME
 C2G11 'CAP_A_0603V-47UF,4V,20%,X5R,60A':
 GROUP='PWR_MLCC_CAP';

SECTION_NUMBER 1
 '@BASEBOARD_FAB2_LIB.BASEBOARD_FAB2(SCH_1):PAGE225_I275@DEV_DISCRETE.CAP_A(CHIPS)':
 C_PATH='@baseboard_fab2_lib.baseboard_fab2(sch_1):page225_i275@dev_discrete.cap~
_a(chips)',
 P_PATH='@baseboard_fab2_lib.baseboard_fab2(sch_1):page225_i275@dev_discrete.cap~
_a(chips)',
 PATH='I275',
 DRAWING='@BASEBOARD_FAB2_LIB.BASEBOARD_FAB2(SCH_1):PAGE225',
 BOM_SS='E15431-004',
 TOLERANCE='20%',
 SEC_TYPE='0603V',
 MATERIAL='X5R',
 PHYS_PAGE='225',
 XY='(-1975,250)',
 ROT='0',
 VER='1',
 VALUE='47UF',
 PACK_TYPE='0603V',
 PART_NUMBER='602433-106',
 LOCATION='C2G11',
 GROUP='PWR_MLCC_CAP',
 SEC='1',
 CDS_LIB='dev_discrete',
 CDS_PART_NAME='CAP_A_0603V-47UF,4V,20%,X5R,60A',
 VOLTAGE='4V',
 PRIM_FILE='./archive_libs/discrete/cap_a/chips/chips.prt';

PART_NAME
 C2G12 'CAP_A_0603V-47UF,4V,20%,X5R,60A':
 GROUP='PWR_MLCC_CAP';

SECTION_NUMBER 1
 '@BASEBOARD_FAB2_LIB.BASEBOARD_FAB2(SCH_1):PAGE225_I276@DEV_DISCRETE.CAP_A(CHIPS)':
 C_PATH='@baseboard_fab2_lib.baseboard_fab2(sch_1):page225_i276@dev_discrete.cap~
_a(chips)',
 P_PATH='@baseboard_fab2_lib.baseboard_fab2(sch_1):page225_i276@dev_discrete.cap~
_a(chips)',
 PATH='I276',
 DRAWING='@BASEBOARD_FAB2_LIB.BASEBOARD_FAB2(SCH_1):PAGE225',
 BOM_SS='E15431-004',
 TOLERANCE='20%',
 SEC_TYPE='0603V',
 MATERIAL='X5R',
 PHYS_PAGE='225',
 XY='(-1675,250)',
 ROT='0',
 VER='1',
 VALUE='47UF',
 PACK_TYPE='0603V',
 PART_NUMBER='602433-106',
 LOCATION='C2G12',
 GROUP='PWR_MLCC_CAP',
 SEC='1',
 CDS_LIB='dev_discrete',
 CDS_PART_NAME='CAP_A_0603V-47UF,4V,20%,X5R,60A',
 VOLTAGE='4V',
 PRIM_FILE='./archive_libs/discrete/cap_a/chips/chips.prt';

PART_NAME
 C2G13 'CAP_A_0603V-47UF,4V,20%,X5R,60A':
 GROUP='PWR_MLCC_CAP';

SECTION_NUMBER 1
 '@BASEBOARD_FAB2_LIB.BASEBOARD_FAB2(SCH_1):PAGE225_I286@DEV_DISCRETE.CAP_A(CHIPS)':
 C_PATH='@baseboard_fab2_lib.baseboard_fab2(sch_1):page225_i286@dev_discrete.cap~
_a(chips)',
 P_PATH='@baseboard_fab2_lib.baseboard_fab2(sch_1):page225_i286@dev_discrete.cap~
_a(chips)',
 PATH='I286',
 DRAWING='@BASEBOARD_FAB2_LIB.BASEBOARD_FAB2(SCH_1):PAGE225',
 BOM_SS='E15431-004',
 TOLERANCE='20%',
 SEC_TYPE='0603V',
 MATERIAL='X5R',
 PHYS_PAGE='225',
 XY='(1225,250)',
 ROT='0',
 VER='1',
 VALUE='47UF',
 PACK_TYPE='0603V',
 PART_NUMBER='602433-106',
 LOCATION='C2G13',
 GROUP='PWR_MLCC_CAP',
 SEC='1',
 CDS_LIB='dev_discrete',
 CDS_PART_NAME='CAP_A_0603V-47UF,4V,20%,X5R,60A',
 VOLTAGE='4V',
 PRIM_FILE='./archive_libs/discrete/cap_a/chips/chips.prt';

PART_NAME
 C2G14 'CAP_A_0603V-47UF,4V,20%,X5R,60A':
 GROUP='PWR_MLCC_CAP';

SECTION_NUMBER 1
 '@BASEBOARD_FAB2_LIB.BASEBOARD_FAB2(SCH_1):PAGE225_I287@DEV_DISCRETE.CAP_A(CHIPS)':
 C_PATH='@baseboard_fab2_lib.baseboard_fab2(sch_1):page225_i287@dev_discrete.cap~
_a(chips)',
 P_PATH='@baseboard_fab2_lib.baseboard_fab2(sch_1):page225_i287@dev_discrete.cap~
_a(chips)',
 PATH='I287',
 DRAWING='@BASEBOARD_FAB2_LIB.BASEBOARD_FAB2(SCH_1):PAGE225',
 BOM_SS='E15431-004',
 TOLERANCE='20%',
 SEC_TYPE='0603V',
 MATERIAL='X5R',
 PHYS_PAGE='225',
 XY='(1525,250)',
 ROT='0',
 VER='1',
 VALUE='47UF',
 PACK_TYPE='0603V',
 PART_NUMBER='602433-106',
 LOCATION='C2G14',
 GROUP='PWR_MLCC_CAP',
 SEC='1',
 CDS_LIB='dev_discrete',
 CDS_PART_NAME='CAP_A_0603V-47UF,4V,20%,X5R,60A',
 VOLTAGE='4V',
 PRIM_FILE='./archive_libs/discrete/cap_a/chips/chips.prt';

PART_NAME
 C2G15 'CAP_A_0603V-47UF,4V,20%,X5R,60A':
 GROUP='PWR_MLCC_CAP';

SECTION_NUMBER 1
 '@BASEBOARD_FAB2_LIB.BASEBOARD_FAB2(SCH_1):PAGE225_I200@DEV_DISCRETE.CAP_A(CHIPS)':
 C_PATH='@baseboard_fab2_lib.baseboard_fab2(sch_1):page225_i200@dev_discrete.cap~
_a(chips)',
 P_PATH='@baseboard_fab2_lib.baseboard_fab2(sch_1):page225_i200@dev_discrete.cap~
_a(chips)',
 PATH='I200',
 DRAWING='@BASEBOARD_FAB2_LIB.BASEBOARD_FAB2(SCH_1):PAGE225',
 BOM_SS='NOPOP',
 TOLERANCE='20%',
 SEC_TYPE='0603V',
 MATERIAL='X5R',
 PHYS_PAGE='225',
 XY='(2900,1725)',
 ROT='0',
 VER='1',
 VALUE='47UF',
 PACK_TYPE='0603V',
 PART_NUMBER='602433-106',
 LOCATION='C2G15',
 GROUP='PWR_MLCC_CAP',
 SEC='1',
 CDS_LIB='dev_discrete',
 CDS_PART_NAME='CAP_A_0603V-47UF,4V,20%,X5R,60A',
 VOLTAGE='4V',
 PRIM_FILE='./archive_libs/discrete/cap_a/chips/chips.prt';

PART_NAME
 C2G16 'CAP_0805-100UF,4V,20%,X5R,6024A':
 GROUP='PWR_MLCC_CAP',
 ROOM='VDDQ_ABC_PWR_VR';

SECTION_NUMBER 1
 '@BASEBOARD_FAB2_LIB.BASEBOARD_FAB2(SCH_1):PAGE225_I311@MSTR_DISCRETE.CAP(CHIPS)':
 C_PATH='@baseboard_fab2_lib.baseboard_fab2(sch_1):page225_i311@mstr_discrete.ca~
p(chips)',
 P_PATH='@baseboard_fab2_lib.baseboard_fab2(sch_1):page225_i311@mstr_discrete.ca~
p(chips)',
 PATH='I311',
 DRAWING='@BASEBOARD_FAB2_LIB.BASEBOARD_FAB2(SCH_1):PAGE225',
 NEW_PN='078.1071T.M002',
 NEW_MATERIAL='X6S',
 BOM_SS='NOPOP',
 TOLERANCE='20%',
 SEC_TYPE='0805',
 MATERIAL='X5R',
 BOM_COST='MEM_VRD_PVDDQ_CD',
 PHYS_PAGE='225',
 XY='(2400,2825)',
 ROT='0',
 VER='1',
 VALUE='100UF',
 PACK_TYPE='0805',
 PART_NUMBER='602433-112',
 LOCATION='C2G16',
 ROOM='VDDQ_ABC_PWR_VR',
 GROUP='PWR_MLCC_CAP',
 SEC='1',
 CDS_LIB='mstr_discrete',
 CDS_PART_NAME='CAP_0805-100UF,4V,20%,X5R,6024A',
 VOLTAGE='4V',
 PRIM_FILE='./archive_libs/mstr_discrete/cap/chips/chips.prt';

PART_NAME
 C2L2 'CAP_0402LF-220PF,50V,10%,X7R,AA':
 ROOM='PVNN_PCH_STBY',
 NO_XNET_CONNECTION='1';

SECTION_NUMBER 1
 '@BASEBOARD_FAB2_LIB.BASEBOARD_FAB2(SCH_1):PAGE235_I153@MSTR_DISCRETE.CAP(CHIPS)':
 C_PATH='@baseboard_fab2_lib.baseboard_fab2(sch_1):page235_i153@mstr_discrete.ca~
p(chips)',
 P_PATH='@baseboard_fab2_lib.baseboard_fab2(sch_1):page235_i153@mstr_discrete.ca~
p(chips)',
 PATH='I153',
 DRAWING='@BASEBOARD_FAB2_LIB.BASEBOARD_FAB2(SCH_1):PAGE235',
 TOLERANCE='10%',
 SEC_TYPE='0402LF',
 MATERIAL='X7R',
 NO_XNET_CONNECTION='1',
 PHYS_PAGE='235',
 XY='(-12475,2075)',
 ROT='0',
 VER='1',
 VALUE='220PF',
 PACK_TYPE='0402LF',
 PART_NUMBER='A36096-050',
 LOCATION='C2L2',
 ROOM='PVNN_PCH_STBY',
 SEC='1',
 CDS_LIB='mstr_discrete',
 CDS_PART_NAME='CAP_0402LF-220PF,50V,10%,X7R,AA',
 VOLTAGE='50V',
 PRIM_FILE='./archive_libs/mstr_discrete/cap/chips/chips.prt';

PART_NAME
 C2L3 'CAP_A_0402V-0.01UF,25V,10%,X7RA':
 ROOM='ST_SATA';

SECTION_NUMBER 1
 '@BASEBOARD_FAB2_LIB.BASEBOARD_FAB2(SCH_1):PAGE173_I194@DEV_DISCRETE.CAP_A(CHIPS)':
 C_PATH='@baseboard_fab2_lib.baseboard_fab2(sch_1):page173_i194@dev_discrete.cap~
_a(chips)',
 P_PATH='@baseboard_fab2_lib.baseboard_fab2(sch_1):page173_i194@dev_discrete.cap~
_a(chips)',
 PATH='I194',
 DRAWING='@BASEBOARD_FAB2_LIB.BASEBOARD_FAB2(SCH_1):PAGE173',
 TOLERANCE='10%',
 SEC_TYPE='0402V',
 MATERIAL='X7R',
 BOM_COST='ST_SATA',
 PHYS_PAGE='173',
 XY='(-4900,3200)',
 ROT='0',
 VER='2',
 VALUE='0.01UF',
 PACK_TYPE='0402V',
 PART_NUMBER='A36096-045',
 LOCATION='C2L3',
 ROOM='ST_SATA',
 SEC='1',
 CDS_LIB='dev_discrete',
 CDS_PART_NAME='CAP_A_0402V-0.01UF,25V,10%,X7RA',
 VOLTAGE='25V',
 PRIM_FILE='./archive_libs/discrete/cap_a/chips/chips.prt';

PART_NAME
 C2L4 'CAP_A_0402V-0.01UF,25V,10%,X7RA':
 ROOM='ST_SATA';

SECTION_NUMBER 1
 '@BASEBOARD_FAB2_LIB.BASEBOARD_FAB2(SCH_1):PAGE173_I192@DEV_DISCRETE.CAP_A(CHIPS)':
 C_PATH='@baseboard_fab2_lib.baseboard_fab2(sch_1):page173_i192@dev_discrete.cap~
_a(chips)',
 P_PATH='@baseboard_fab2_lib.baseboard_fab2(sch_1):page173_i192@dev_discrete.cap~
_a(chips)',
 PATH='I192',
 DRAWING='@BASEBOARD_FAB2_LIB.BASEBOARD_FAB2(SCH_1):PAGE173',
 TOLERANCE='10%',
 SEC_TYPE='0402V',
 MATERIAL='X7R',
 BOM_COST='ST_SATA',
 PHYS_PAGE='173',
 XY='(-4575,3350)',
 ROT='0',
 VER='2',
 VALUE='0.01UF',
 PACK_TYPE='0402V',
 PART_NUMBER='A36096-045',
 LOCATION='C2L4',
 ROOM='ST_SATA',
 SEC='1',
 CDS_LIB='dev_discrete',
 CDS_PART_NAME='CAP_A_0402V-0.01UF,25V,10%,X7RA',
 VOLTAGE='25V',
 PRIM_FILE='./archive_libs/discrete/cap_a/chips/chips.prt';

PART_NAME
 C2L5 'CAP_A_0402V-0.01UF,25V,10%,X7RA':
 ROOM='ST_SATA';

SECTION_NUMBER 1
 '@BASEBOARD_FAB2_LIB.BASEBOARD_FAB2(SCH_1):PAGE173_I209@DEV_DISCRETE.CAP_A(CHIPS)':
 C_PATH='@baseboard_fab2_lib.baseboard_fab2(sch_1):page173_i209@dev_discrete.cap~
_a(chips)',
 P_PATH='@baseboard_fab2_lib.baseboard_fab2(sch_1):page173_i209@dev_discrete.cap~
_a(chips)',
 PATH='I209',
 DRAWING='@BASEBOARD_FAB2_LIB.BASEBOARD_FAB2(SCH_1):PAGE173',
 TOLERANCE='10%',
 SEC_TYPE='0402V',
 MATERIAL='X7R',
 BOM_COST='ST_SATA',
 PHYS_PAGE='173',
 XY='(-4975,1500)',
 ROT='0',
 VER='2',
 VALUE='0.01UF',
 PACK_TYPE='0402V',
 PART_NUMBER='A36096-045',
 LOCATION='C2L5',
 ROOM='ST_SATA',
 SEC='1',
 CDS_LIB='dev_discrete',
 CDS_PART_NAME='CAP_A_0402V-0.01UF,25V,10%,X7RA',
 VOLTAGE='25V',
 PRIM_FILE='./archive_libs/discrete/cap_a/chips/chips.prt';

PART_NAME
 C2L6 'CAP_A_0402V-0.01UF,25V,10%,X7RA':
 ROOM='ST_SATA';

SECTION_NUMBER 1
 '@BASEBOARD_FAB2_LIB.BASEBOARD_FAB2(SCH_1):PAGE173_I166@DEV_DISCRETE.CAP_A(CHIPS)':
 C_PATH='@baseboard_fab2_lib.baseboard_fab2(sch_1):page173_i166@dev_discrete.cap~
_a(chips)',
 P_PATH='@baseboard_fab2_lib.baseboard_fab2(sch_1):page173_i166@dev_discrete.cap~
_a(chips)',
 PATH='I166',
 DRAWING='@BASEBOARD_FAB2_LIB.BASEBOARD_FAB2(SCH_1):PAGE173',
 TOLERANCE='10%',
 SEC_TYPE='0402V',
 MATERIAL='X7R',
 BOM_COST='ST_SATA',
 PHYS_PAGE='173',
 XY='(-4850,4050)',
 ROT='0',
 VER='2',
 VALUE='0.01UF',
 PACK_TYPE='0402V',
 PART_NUMBER='A36096-045',
 LOCATION='C2L6',
 ROOM='ST_SATA',
 SEC='1',
 CDS_LIB='dev_discrete',
 CDS_PART_NAME='CAP_A_0402V-0.01UF,25V,10%,X7RA',
 VOLTAGE='25V',
 PRIM_FILE='./archive_libs/discrete/cap_a/chips/chips.prt';

PART_NAME
 C2L7 'CAP_A_0402V-0.01UF,25V,10%,X7RA':
 ROOM='ST_SATA';

SECTION_NUMBER 1
 '@BASEBOARD_FAB2_LIB.BASEBOARD_FAB2(SCH_1):PAGE173_I206@DEV_DISCRETE.CAP_A(CHIPS)':
 C_PATH='@baseboard_fab2_lib.baseboard_fab2(sch_1):page173_i206@dev_discrete.cap~
_a(chips)',
 P_PATH='@baseboard_fab2_lib.baseboard_fab2(sch_1):page173_i206@dev_discrete.cap~
_a(chips)',
 PATH='I206',
 DRAWING='@BASEBOARD_FAB2_LIB.BASEBOARD_FAB2(SCH_1):PAGE173',
 TOLERANCE='10%',
 SEC_TYPE='0402V',
 MATERIAL='X7R',
 BOM_COST='ST_SATA',
 PHYS_PAGE='173',
 XY='(-4575,1700)',
 ROT='0',
 VER='2',
 VALUE='0.01UF',
 PACK_TYPE='0402V',
 PART_NUMBER='A36096-045',
 LOCATION='C2L7',
 ROOM='ST_SATA',
 SEC='1',
 CDS_LIB='dev_discrete',
 CDS_PART_NAME='CAP_A_0402V-0.01UF,25V,10%,X7RA',
 VOLTAGE='25V',
 PRIM_FILE='./archive_libs/discrete/cap_a/chips/chips.prt';

PART_NAME
 C2L8 'CAP_A_0402V-1.0UF,6.3V,10%,X6SA':
 ROOM='PVNN_PCH_STBY';

SECTION_NUMBER 1
 '@BASEBOARD_FAB2_LIB.BASEBOARD_FAB2(SCH_1):PAGE235_I151@DEV_DISCRETE.CAP_A(CHIPS)':
 C_PATH='@baseboard_fab2_lib.baseboard_fab2(sch_1):page235_i151@dev_discrete.cap~
_a(chips)',
 P_PATH='@baseboard_fab2_lib.baseboard_fab2(sch_1):page235_i151@dev_discrete.cap~
_a(chips)',
 PATH='I151',
 DRAWING='@BASEBOARD_FAB2_LIB.BASEBOARD_FAB2(SCH_1):PAGE235',
 TOLERANCE='10%',
 SEC_TYPE='0402V',
 MATERIAL='X6S',
 PHYS_PAGE='235',
 XY='(-9750,5075)',
 ROT='0',
 VER='1',
 VALUE='1.0UF',
 PACK_TYPE='0402V',
 PART_NUMBER='D97712-004',
 LOCATION='C2L8',
 ROOM='PVNN_PCH_STBY',
 SEC='1',
 CDS_LIB='dev_discrete',
 CDS_PART_NAME='CAP_A_0402V-1.0UF,6.3V,10%,X6SA',
 VOLTAGE='6.3V',
 PRIM_FILE='./archive_libs/discrete/cap_a/chips/chips.prt';

PART_NAME
 C2L9 'CAP_A_0402V-0.01UF,25V,10%,X7RA':
 ROOM='ST_SATA';

SECTION_NUMBER 1
 '@BASEBOARD_FAB2_LIB.BASEBOARD_FAB2(SCH_1):PAGE173_I207@DEV_DISCRETE.CAP_A(CHIPS)':
 C_PATH='@baseboard_fab2_lib.baseboard_fab2(sch_1):page173_i207@dev_discrete.cap~
_a(chips)',
 P_PATH='@baseboard_fab2_lib.baseboard_fab2(sch_1):page173_i207@dev_discrete.cap~
_a(chips)',
 PATH='I207',
 DRAWING='@BASEBOARD_FAB2_LIB.BASEBOARD_FAB2(SCH_1):PAGE173',
 TOLERANCE='10%',
 SEC_TYPE='0402V',
 MATERIAL='X7R',
 BOM_COST='ST_SATA',
 PHYS_PAGE='173',
 XY='(-4950,2400)',
 ROT='0',
 VER='2',
 VALUE='0.01UF',
 PACK_TYPE='0402V',
 PART_NUMBER='A36096-045',
 LOCATION='C2L9',
 ROOM='ST_SATA',
 SEC='1',
 CDS_LIB='dev_discrete',
 CDS_PART_NAME='CAP_A_0402V-0.01UF,25V,10%,X7RA',
 VOLTAGE='25V',
 PRIM_FILE='./archive_libs/discrete/cap_a/chips/chips.prt';

PART_NAME
 C2L10 'CAP_A_0402V-0.01UF,25V,10%,X7RA':
 ROOM='ST_SATA';

SECTION_NUMBER 1
 '@BASEBOARD_FAB2_LIB.BASEBOARD_FAB2(SCH_1):PAGE173_I173@DEV_DISCRETE.CAP_A(CHIPS)':
 C_PATH='@baseboard_fab2_lib.baseboard_fab2(sch_1):page173_i173@dev_discrete.cap~
_a(chips)',
 P_PATH='@baseboard_fab2_lib.baseboard_fab2(sch_1):page173_i173@dev_discrete.cap~
_a(chips)',
 PATH='I173',
 DRAWING='@BASEBOARD_FAB2_LIB.BASEBOARD_FAB2(SCH_1):PAGE173',
 TOLERANCE='10%',
 SEC_TYPE='0402V',
 MATERIAL='X7R',
 BOM_COST='ST_SATA',
 PHYS_PAGE='173',
 XY='(-4575,4200)',
 ROT='0',
 VER='2',
 VALUE='0.01UF',
 PACK_TYPE='0402V',
 PART_NUMBER='A36096-045',
 LOCATION='C2L10',
 ROOM='ST_SATA',
 SEC='1',
 CDS_LIB='dev_discrete',
 CDS_PART_NAME='CAP_A_0402V-0.01UF,25V,10%,X7RA',
 VOLTAGE='25V',
 PRIM_FILE='./archive_libs/discrete/cap_a/chips/chips.prt';

PART_NAME
 C2L11 'CAP_A_0402V-0.1UF,16V,10%,X7R,A':
 ROOM='PVNN_PCH_STBY';

SECTION_NUMBER 1
 '@BASEBOARD_FAB2_LIB.BASEBOARD_FAB2(SCH_1):PAGE235_I169@DEV_DISCRETE.CAP_A(CHIPS)':
 C_PATH='@baseboard_fab2_lib.baseboard_fab2(sch_1):page235_i169@dev_discrete.cap~
_a(chips)',
 P_PATH='@baseboard_fab2_lib.baseboard_fab2(sch_1):page235_i169@dev_discrete.cap~
_a(chips)',
 PATH='I169',
 DRAWING='@BASEBOARD_FAB2_LIB.BASEBOARD_FAB2(SCH_1):PAGE235',
 TOLERANCE='10%',
 SEC_TYPE='0402V',
 MATERIAL='X7R',
 PHYS_PAGE='235',
 XY='(-10150,5075)',
 ROT='0',
 VER='1',
 VALUE='0.1UF',
 PACK_TYPE='0402V',
 PART_NUMBER='A36096-030',
 LOCATION='C2L11',
 ROOM='PVNN_PCH_STBY',
 SEC='1',
 CDS_LIB='dev_discrete',
 CDS_PART_NAME='CAP_A_0402V-0.1UF,16V,10%,X7R,A',
 VOLTAGE='16V',
 PRIM_FILE='./archive_libs/discrete/cap_a/chips/chips.prt';

PART_NAME
 C2L12 'CAP_A_0402V-0.01UF,25V,10%,X7RA':
 ROOM='ST_SATA';

SECTION_NUMBER 1
 '@BASEBOARD_FAB2_LIB.BASEBOARD_FAB2(SCH_1):PAGE173_I196@DEV_DISCRETE.CAP_A(CHIPS)':
 C_PATH='@baseboard_fab2_lib.baseboard_fab2(sch_1):page173_i196@dev_discrete.cap~
_a(chips)',
 P_PATH='@baseboard_fab2_lib.baseboard_fab2(sch_1):page173_i196@dev_discrete.cap~
_a(chips)',
 PATH='I196',
 DRAWING='@BASEBOARD_FAB2_LIB.BASEBOARD_FAB2(SCH_1):PAGE173',
 TOLERANCE='10%',
 SEC_TYPE='0402V',
 MATERIAL='X7R',
 BOM_COST='ST_SATA',
 PHYS_PAGE='173',
 XY='(-4575,2550)',
 ROT='0',
 VER='2',
 VALUE='0.01UF',
 PACK_TYPE='0402V',
 PART_NUMBER='A36096-045',
 LOCATION='C2L12',
 ROOM='ST_SATA',
 SEC='1',
 CDS_LIB='dev_discrete',
 CDS_PART_NAME='CAP_A_0402V-0.01UF,25V,10%,X7RA',
 VOLTAGE='25V',
 PRIM_FILE='./archive_libs/discrete/cap_a/chips/chips.prt';

PART_NAME
 C2L13 'CAP_A_0402V-0.01UF,25V,10%,X7RA':
 ROOM='ST_SATA';

SECTION_NUMBER 1
 '@BASEBOARD_FAB2_LIB.BASEBOARD_FAB2(SCH_1):PAGE173_I165@DEV_DISCRETE.CAP_A(CHIPS)':
 C_PATH='@baseboard_fab2_lib.baseboard_fab2(sch_1):page173_i165@dev_discrete.cap~
_a(chips)',
 P_PATH='@baseboard_fab2_lib.baseboard_fab2(sch_1):page173_i165@dev_discrete.cap~
_a(chips)',
 PATH='I165',
 DRAWING='@BASEBOARD_FAB2_LIB.BASEBOARD_FAB2(SCH_1):PAGE173',
 TOLERANCE='10%',
 SEC_TYPE='0402V',
 MATERIAL='X7R',
 BOM_COST='ST_SATA',
 PHYS_PAGE='173',
 XY='(-4900,3550)',
 ROT='0',
 VER='2',
 VALUE='0.01UF',
 PACK_TYPE='0402V',
 PART_NUMBER='A36096-045',
 LOCATION='C2L13',
 ROOM='ST_SATA',
 SEC='1',
 CDS_LIB='dev_discrete',
 CDS_PART_NAME='CAP_A_0402V-0.01UF,25V,10%,X7RA',
 VOLTAGE='25V',
 PRIM_FILE='./archive_libs/discrete/cap_a/chips/chips.prt';

PART_NAME
 C2L14 'CAP_A_0402V-0.01UF,25V,10%,X7RA':
 ROOM='ST_SATA';

SECTION_NUMBER 1
 '@BASEBOARD_FAB2_LIB.BASEBOARD_FAB2(SCH_1):PAGE173_I208@DEV_DISCRETE.CAP_A(CHIPS)':
 C_PATH='@baseboard_fab2_lib.baseboard_fab2(sch_1):page173_i208@dev_discrete.cap~
_a(chips)',
 P_PATH='@baseboard_fab2_lib.baseboard_fab2(sch_1):page173_i208@dev_discrete.cap~
_a(chips)',
 PATH='I208',
 DRAWING='@BASEBOARD_FAB2_LIB.BASEBOARD_FAB2(SCH_1):PAGE173',
 TOLERANCE='10%',
 SEC_TYPE='0402V',
 MATERIAL='X7R',
 BOM_COST='ST_SATA',
 PHYS_PAGE='173',
 XY='(-4975,1850)',
 ROT='0',
 VER='2',
 VALUE='0.01UF',
 PACK_TYPE='0402V',
 PART_NUMBER='A36096-045',
 LOCATION='C2L14',
 ROOM='ST_SATA',
 SEC='1',
 CDS_LIB='dev_discrete',
 CDS_PART_NAME='CAP_A_0402V-0.01UF,25V,10%,X7RA',
 VOLTAGE='25V',
 PRIM_FILE='./archive_libs/discrete/cap_a/chips/chips.prt';

PART_NAME
 C2L15 'CAP_A_0402V-0.01UF,25V,10%,X7RA':
 ROOM='ST_SATA';

SECTION_NUMBER 1
 '@BASEBOARD_FAB2_LIB.BASEBOARD_FAB2(SCH_1):PAGE173_I191@DEV_DISCRETE.CAP_A(CHIPS)':
 C_PATH='@baseboard_fab2_lib.baseboard_fab2(sch_1):page173_i191@dev_discrete.cap~
_a(chips)',
 P_PATH='@baseboard_fab2_lib.baseboard_fab2(sch_1):page173_i191@dev_discrete.cap~
_a(chips)',
 PATH='I191',
 DRAWING='@BASEBOARD_FAB2_LIB.BASEBOARD_FAB2(SCH_1):PAGE173',
 TOLERANCE='10%',
 SEC_TYPE='0402V',
 MATERIAL='X7R',
 BOM_COST='ST_SATA',
 PHYS_PAGE='173',
 XY='(-4575,3700)',
 ROT='0',
 VER='2',
 VALUE='0.01UF',
 PACK_TYPE='0402V',
 PART_NUMBER='A36096-045',
 LOCATION='C2L15',
 ROOM='ST_SATA',
 SEC='1',
 CDS_LIB='dev_discrete',
 CDS_PART_NAME='CAP_A_0402V-0.01UF,25V,10%,X7RA',
 VOLTAGE='25V',
 PRIM_FILE='./archive_libs/discrete/cap_a/chips/chips.prt';

PART_NAME
 C2L16 'CAP_A_0402V-0.01UF,25V,10%,X7RA':
 ROOM='ST_SATA';

SECTION_NUMBER 1
 '@BASEBOARD_FAB2_LIB.BASEBOARD_FAB2(SCH_1):PAGE173_I205@DEV_DISCRETE.CAP_A(CHIPS)':
 C_PATH='@baseboard_fab2_lib.baseboard_fab2(sch_1):page173_i205@dev_discrete.cap~
_a(chips)',
 P_PATH='@baseboard_fab2_lib.baseboard_fab2(sch_1):page173_i205@dev_discrete.cap~
_a(chips)',
 PATH='I205',
 DRAWING='@BASEBOARD_FAB2_LIB.BASEBOARD_FAB2(SCH_1):PAGE173',
 TOLERANCE='10%',
 SEC_TYPE='0402V',
 MATERIAL='X7R',
 BOM_COST='ST_SATA',
 PHYS_PAGE='173',
 XY='(-4575,2050)',
 ROT='0',
 VER='2',
 VALUE='0.01UF',
 PACK_TYPE='0402V',
 PART_NUMBER='A36096-045',
 LOCATION='C2L16',
 ROOM='ST_SATA',
 SEC='1',
 CDS_LIB='dev_discrete',
 CDS_PART_NAME='CAP_A_0402V-0.01UF,25V,10%,X7RA',
 VOLTAGE='25V',
 PRIM_FILE='./archive_libs/discrete/cap_a/chips/chips.prt';

PART_NAME
 C2L17 'CAP_A_0402V-0.01UF,25V,10%,X7RA':
 ROOM='ST_SATA';

SECTION_NUMBER 1
 '@BASEBOARD_FAB2_LIB.BASEBOARD_FAB2(SCH_1):PAGE173_I174@DEV_DISCRETE.CAP_A(CHIPS)':
 C_PATH='@baseboard_fab2_lib.baseboard_fab2(sch_1):page173_i174@dev_discrete.cap~
_a(chips)',
 P_PATH='@baseboard_fab2_lib.baseboard_fab2(sch_1):page173_i174@dev_discrete.cap~
_a(chips)',
 PATH='I174',
 DRAWING='@BASEBOARD_FAB2_LIB.BASEBOARD_FAB2(SCH_1):PAGE173',
 TOLERANCE='10%',
 SEC_TYPE='0402V',
 MATERIAL='X7R',
 BOM_COST='ST_SATA',
 PHYS_PAGE='173',
 XY='(-4850,4400)',
 ROT='0',
 VER='2',
 VALUE='0.01UF',
 PACK_TYPE='0402V',
 PART_NUMBER='A36096-045',
 LOCATION='C2L17',
 ROOM='ST_SATA',
 SEC='1',
 CDS_LIB='dev_discrete',
 CDS_PART_NAME='CAP_A_0402V-0.01UF,25V,10%,X7RA',
 VOLTAGE='25V',
 PRIM_FILE='./archive_libs/discrete/cap_a/chips/chips.prt';

PART_NAME
 C2L18 'CAP_A_0402V-0.01UF,25V,10%,X7RA':
 ROOM='ST_SATA';

SECTION_NUMBER 1
 '@BASEBOARD_FAB2_LIB.BASEBOARD_FAB2(SCH_1):PAGE173_I197@DEV_DISCRETE.CAP_A(CHIPS)':
 C_PATH='@baseboard_fab2_lib.baseboard_fab2(sch_1):page173_i197@dev_discrete.cap~
_a(chips)',
 P_PATH='@baseboard_fab2_lib.baseboard_fab2(sch_1):page173_i197@dev_discrete.cap~
_a(chips)',
 PATH='I197',
 DRAWING='@BASEBOARD_FAB2_LIB.BASEBOARD_FAB2(SCH_1):PAGE173',
 TOLERANCE='10%',
 SEC_TYPE='0402V',
 MATERIAL='X7R',
 BOM_COST='ST_SATA',
 PHYS_PAGE='173',
 XY='(-4950,2750)',
 ROT='0',
 VER='2',
 VALUE='0.01UF',
 PACK_TYPE='0402V',
 PART_NUMBER='A36096-045',
 LOCATION='C2L18',
 ROOM='ST_SATA',
 SEC='1',
 CDS_LIB='dev_discrete',
 CDS_PART_NAME='CAP_A_0402V-0.01UF,25V,10%,X7RA',
 VOLTAGE='25V',
 PRIM_FILE='./archive_libs/discrete/cap_a/chips/chips.prt';

PART_NAME
 C2L19 'CAP_A_0402V-0.01UF,25V,10%,X7RA':
 ROOM='ST_SATA';

SECTION_NUMBER 1
 '@BASEBOARD_FAB2_LIB.BASEBOARD_FAB2(SCH_1):PAGE173_I172@DEV_DISCRETE.CAP_A(CHIPS)':
 C_PATH='@baseboard_fab2_lib.baseboard_fab2(sch_1):page173_i172@dev_discrete.cap~
_a(chips)',
 P_PATH='@baseboard_fab2_lib.baseboard_fab2(sch_1):page173_i172@dev_discrete.cap~
_a(chips)',
 PATH='I172',
 DRAWING='@BASEBOARD_FAB2_LIB.BASEBOARD_FAB2(SCH_1):PAGE173',
 TOLERANCE='10%',
 SEC_TYPE='0402V',
 MATERIAL='X7R',
 BOM_COST='ST_SATA',
 PHYS_PAGE='173',
 XY='(-4575,4550)',
 ROT='0',
 VER='2',
 VALUE='0.01UF',
 PACK_TYPE='0402V',
 PART_NUMBER='A36096-045',
 LOCATION='C2L19',
 ROOM='ST_SATA',
 SEC='1',
 CDS_LIB='dev_discrete',
 CDS_PART_NAME='CAP_A_0402V-0.01UF,25V,10%,X7RA',
 VOLTAGE='25V',
 PRIM_FILE='./archive_libs/discrete/cap_a/chips/chips.prt';

PART_NAME
 C2L20 'CAP_A_0402V-0.01UF,25V,10%,X7RA':
 ROOM='ST_SATA';

SECTION_NUMBER 1
 '@BASEBOARD_FAB2_LIB.BASEBOARD_FAB2(SCH_1):PAGE173_I195@DEV_DISCRETE.CAP_A(CHIPS)':
 C_PATH='@baseboard_fab2_lib.baseboard_fab2(sch_1):page173_i195@dev_discrete.cap~
_a(chips)',
 P_PATH='@baseboard_fab2_lib.baseboard_fab2(sch_1):page173_i195@dev_discrete.cap~
_a(chips)',
 PATH='I195',
 DRAWING='@BASEBOARD_FAB2_LIB.BASEBOARD_FAB2(SCH_1):PAGE173',
 TOLERANCE='10%',
 SEC_TYPE='0402V',
 MATERIAL='X7R',
 BOM_COST='ST_SATA',
 PHYS_PAGE='173',
 XY='(-4600,2900)',
 ROT='0',
 VER='2',
 VALUE='0.01UF',
 PACK_TYPE='0402V',
 PART_NUMBER='A36096-045',
 LOCATION='C2L20',
 ROOM='ST_SATA',
 SEC='1',
 CDS_LIB='dev_discrete',
 CDS_PART_NAME='CAP_A_0402V-0.01UF,25V,10%,X7RA',
 VOLTAGE='25V',
 PRIM_FILE='./archive_libs/discrete/cap_a/chips/chips.prt';

PART_NAME
 C2L21 'CAP_A_0402V-0.01UF,25V,10%,X7RA':
 ROOM='ST_SATA';

SECTION_NUMBER 1
 '@BASEBOARD_FAB2_LIB.BASEBOARD_FAB2(SCH_1):PAGE173_I259@DEV_DISCRETE.CAP_A(CHIPS)':
 C_PATH='@baseboard_fab2_lib.baseboard_fab2(sch_1):page173_i259@dev_discrete.cap~
_a(chips)',
 P_PATH='@baseboard_fab2_lib.baseboard_fab2(sch_1):page173_i259@dev_discrete.cap~
_a(chips)',
 PATH='I259',
 DRAWING='@BASEBOARD_FAB2_LIB.BASEBOARD_FAB2(SCH_1):PAGE173',
 TOLERANCE='10%',
 SEC_TYPE='0402V',
 MATERIAL='X7R',
 BOM_COST='ST_SATA',
 PHYS_PAGE='173',
 XY='(1050,1550)',
 ROT='0',
 VER='2',
 VALUE='0.01UF',
 PACK_TYPE='0402V',
 PART_NUMBER='A36096-045',
 LOCATION='C2L21',
 ROOM='ST_SATA',
 SEC='1',
 CDS_LIB='dev_discrete',
 CDS_PART_NAME='CAP_A_0402V-0.01UF,25V,10%,X7RA',
 VOLTAGE='25V',
 PRIM_FILE='./archive_libs/discrete/cap_a/chips/chips.prt';

PART_NAME
 C2L22 'CAP_A_0402V-0.01UF,25V,10%,X7RA':
 ROOM='ST_SATA';

SECTION_NUMBER 1
 '@BASEBOARD_FAB2_LIB.BASEBOARD_FAB2(SCH_1):PAGE173_I234@DEV_DISCRETE.CAP_A(CHIPS)':
 C_PATH='@baseboard_fab2_lib.baseboard_fab2(sch_1):page173_i234@dev_discrete.cap~
_a(chips)',
 P_PATH='@baseboard_fab2_lib.baseboard_fab2(sch_1):page173_i234@dev_discrete.cap~
_a(chips)',
 PATH='I234',
 DRAWING='@BASEBOARD_FAB2_LIB.BASEBOARD_FAB2(SCH_1):PAGE173',
 TOLERANCE='10%',
 SEC_TYPE='0402V',
 MATERIAL='X7R',
 BOM_COST='ST_SATA',
 PHYS_PAGE='173',
 XY='(1025,3075)',
 ROT='0',
 VER='2',
 VALUE='0.01UF',
 PACK_TYPE='0402V',
 PART_NUMBER='A36096-045',
 LOCATION='C2L22',
 ROOM='ST_SATA',
 SEC='1',
 CDS_LIB='dev_discrete',
 CDS_PART_NAME='CAP_A_0402V-0.01UF,25V,10%,X7RA',
 VOLTAGE='25V',
 PRIM_FILE='./archive_libs/discrete/cap_a/chips/chips.prt';

PART_NAME
 C2L23 'CAP_A_0402V-0.01UF,25V,10%,X7RA':
 ROOM='ST_SATA';

SECTION_NUMBER 1
 '@BASEBOARD_FAB2_LIB.BASEBOARD_FAB2(SCH_1):PAGE173_I241@DEV_DISCRETE.CAP_A(CHIPS)':
 C_PATH='@baseboard_fab2_lib.baseboard_fab2(sch_1):page173_i241@dev_discrete.cap~
_a(chips)',
 P_PATH='@baseboard_fab2_lib.baseboard_fab2(sch_1):page173_i241@dev_discrete.cap~
_a(chips)',
 PATH='I241',
 DRAWING='@BASEBOARD_FAB2_LIB.BASEBOARD_FAB2(SCH_1):PAGE173',
 TOLERANCE='10%',
 SEC_TYPE='0402V',
 MATERIAL='X7R',
 BOM_COST='ST_SATA',
 PHYS_PAGE='173',
 XY='(625,3300)',
 ROT='0',
 VER='2',
 VALUE='0.01UF',
 PACK_TYPE='0402V',
 PART_NUMBER='A36096-045',
 LOCATION='C2L23',
 ROOM='ST_SATA',
 SEC='1',
 CDS_LIB='dev_discrete',
 CDS_PART_NAME='CAP_A_0402V-0.01UF,25V,10%,X7RA',
 VOLTAGE='25V',
 PRIM_FILE='./archive_libs/discrete/cap_a/chips/chips.prt';

PART_NAME
 C2L24 'CAP_A_0402V-0.01UF,25V,10%,X7RA':
 ROOM='ST_SATA';

SECTION_NUMBER 1
 '@BASEBOARD_FAB2_LIB.BASEBOARD_FAB2(SCH_1):PAGE173_I258@DEV_DISCRETE.CAP_A(CHIPS)':
 C_PATH='@baseboard_fab2_lib.baseboard_fab2(sch_1):page173_i258@dev_discrete.cap~
_a(chips)',
 P_PATH='@baseboard_fab2_lib.baseboard_fab2(sch_1):page173_i258@dev_discrete.cap~
_a(chips)',
 PATH='I258',
 DRAWING='@BASEBOARD_FAB2_LIB.BASEBOARD_FAB2(SCH_1):PAGE173',
 TOLERANCE='10%',
 SEC_TYPE='0402V',
 MATERIAL='X7R',
 BOM_COST='ST_SATA',
 PHYS_PAGE='173',
 XY='(650,1700)',
 ROT='0',
 VER='2',
 VALUE='0.01UF',
 PACK_TYPE='0402V',
 PART_NUMBER='A36096-045',
 LOCATION='C2L24',
 ROOM='ST_SATA',
 SEC='1',
 CDS_LIB='dev_discrete',
 CDS_PART_NAME='CAP_A_0402V-0.01UF,25V,10%,X7RA',
 VOLTAGE='25V',
 PRIM_FILE='./archive_libs/discrete/cap_a/chips/chips.prt';

PART_NAME
 C2L25 'CAPP_SM-470UF,2V,20%,ALUM,6990A':
 ROOM='P1V05_PCH_STBY';

SECTION_NUMBER 1
 '@BASEBOARD_FAB2_LIB.BASEBOARD_FAB2(SCH_1):PAGE236_I79@MSTR_DISCRETE.CAPP(CHIPS)':
 C_PATH='@baseboard_fab2_lib.baseboard_fab2(sch_1):page236_i79@mstr_discrete.cap~
p(chips)',
 P_PATH='@baseboard_fab2_lib.baseboard_fab2(sch_1):page236_i79@mstr_discrete.cap~
p(chips)',
 PATH='I79',
 DRAWING='@BASEBOARD_FAB2_LIB.BASEBOARD_FAB2(SCH_1):PAGE236',
 TOLERANCE='20%',
 SEC_TYPE='SM',
 MATERIAL='ALUM',
 PHYS_PAGE='236',
 XY='(12700,2050)',
 ROT='0',
 VER='1',
 VALUE='470UF',
 PACK_TYPE='SM',
 PART_NUMBER='699013-031',
 LOCATION='C2L25',
 ROOM='P1V05_PCH_STBY',
 SEC='1',
 CDS_LIB='mstr_discrete',
 CDS_PART_NAME='CAPP_SM-470UF,2V,20%,ALUM,6990A',
 VOLTAGE='2V',
 PRIM_FILE='./archive_libs/mstr_discrete/capp/chips/chips.prt';

PART_NAME
 C2L26 'CAP_A_0402V-0.01UF,25V,10%,X7RA':
 ROOM='ST_SATA';

SECTION_NUMBER 1
 '@BASEBOARD_FAB2_LIB.BASEBOARD_FAB2(SCH_1):PAGE173_I255@DEV_DISCRETE.CAP_A(CHIPS)':
 C_PATH='@baseboard_fab2_lib.baseboard_fab2(sch_1):page173_i255@dev_discrete.cap~
_a(chips)',
 P_PATH='@baseboard_fab2_lib.baseboard_fab2(sch_1):page173_i255@dev_discrete.cap~
_a(chips)',
 PATH='I255',
 DRAWING='@BASEBOARD_FAB2_LIB.BASEBOARD_FAB2(SCH_1):PAGE173',
 TOLERANCE='10%',
 SEC_TYPE='0402V',
 MATERIAL='X7R',
 BOM_COST='ST_SATA',
 PHYS_PAGE='173',
 XY='(1025,2350)',
 ROT='0',
 VER='2',
 VALUE='0.01UF',
 PACK_TYPE='0402V',
 PART_NUMBER='A36096-045',
 LOCATION='C2L26',
 ROOM='ST_SATA',
 SEC='1',
 CDS_LIB='dev_discrete',
 CDS_PART_NAME='CAP_A_0402V-0.01UF,25V,10%,X7RA',
 VOLTAGE='25V',
 PRIM_FILE='./archive_libs/discrete/cap_a/chips/chips.prt';

PART_NAME
 C2L27 'CAP_A_0402V-0.01UF,25V,10%,X7RA':
 ROOM='ST_SATA';

SECTION_NUMBER 1
 '@BASEBOARD_FAB2_LIB.BASEBOARD_FAB2(SCH_1):PAGE173_I240@DEV_DISCRETE.CAP_A(CHIPS)':
 C_PATH='@baseboard_fab2_lib.baseboard_fab2(sch_1):page173_i240@dev_discrete.cap~
_a(chips)',
 P_PATH='@baseboard_fab2_lib.baseboard_fab2(sch_1):page173_i240@dev_discrete.cap~
_a(chips)',
 PATH='I240',
 DRAWING='@BASEBOARD_FAB2_LIB.BASEBOARD_FAB2(SCH_1):PAGE173',
 TOLERANCE='10%',
 SEC_TYPE='0402V',
 MATERIAL='X7R',
 BOM_COST='ST_SATA',
 PHYS_PAGE='173',
 XY='(650,2500)',
 ROT='0',
 VER='2',
 VALUE='0.01UF',
 PACK_TYPE='0402V',
 PART_NUMBER='A36096-045',
 LOCATION='C2L27',
 ROOM='ST_SATA',
 SEC='1',
 CDS_LIB='dev_discrete',
 CDS_PART_NAME='CAP_A_0402V-0.01UF,25V,10%,X7RA',
 VOLTAGE='25V',
 PRIM_FILE='./archive_libs/discrete/cap_a/chips/chips.prt';

PART_NAME
 C2L32 'CAP_0805-47UF,4V,20%,X6S,C9533A':
 ROOM='P1V8_PCH_STBY_VR';

SECTION_NUMBER 1
 '@BASEBOARD_FAB2_LIB.BASEBOARD_FAB2(SCH_1):PAGE237_I79@MSTR_DISCRETE.CAP(CHIPS)':
 C_PATH='@baseboard_fab2_lib.baseboard_fab2(sch_1):page237_i79@mstr_discrete.cap~
(chips)',
 P_PATH='@baseboard_fab2_lib.baseboard_fab2(sch_1):page237_i79@mstr_discrete.cap~
(chips)',
 PATH='I79',
 DRAWING='@BASEBOARD_FAB2_LIB.BASEBOARD_FAB2(SCH_1):PAGE237',
 TOLERANCE='20%',
 SEC_TYPE='0805',
 MATERIAL='X6S',
 PHYS_PAGE='237',
 XY='(3900,1850)',
 ROT='0',
 VER='1',
 VALUE='47UF',
 PACK_TYPE='0805',
 PART_NUMBER='C95333-006',
 LOCATION='C2L32',
 ROOM='P1V8_PCH_STBY_VR',
 SEC='1',
 CDS_LIB='mstr_discrete',
 CDS_PART_NAME='CAP_0805-47UF,4V,20%,X6S,C9533A',
 VOLTAGE='4V',
 PRIM_FILE='./archive_libs/mstr_discrete/cap/chips/chips.prt';

PART_NAME
 C2L37 'CAP_A_0402V-0.01UF,25V,10%,X7RA':
 ROOM='ST_SATA';

SECTION_NUMBER 1
 '@BASEBOARD_FAB2_LIB.BASEBOARD_FAB2(SCH_1):PAGE173_I238@DEV_DISCRETE.CAP_A(CHIPS)':
 C_PATH='@baseboard_fab2_lib.baseboard_fab2(sch_1):page173_i238@dev_discrete.cap~
_a(chips)',
 P_PATH='@baseboard_fab2_lib.baseboard_fab2(sch_1):page173_i238@dev_discrete.cap~
_a(chips)',
 PATH='I238',
 DRAWING='@BASEBOARD_FAB2_LIB.BASEBOARD_FAB2(SCH_1):PAGE173',
 TOLERANCE='10%',
 SEC_TYPE='0402V',
 MATERIAL='X7R',
 BOM_COST='ST_SATA',
 PHYS_PAGE='173',
 XY='(1025,2725)',
 ROT='0',
 VER='2',
 VALUE='0.01UF',
 PACK_TYPE='0402V',
 PART_NUMBER='A36096-045',
 LOCATION='C2L37',
 ROOM='ST_SATA',
 SEC='1',
 CDS_LIB='dev_discrete',
 CDS_PART_NAME='CAP_A_0402V-0.01UF,25V,10%,X7RA',
 VOLTAGE='25V',
 PRIM_FILE='./archive_libs/discrete/cap_a/chips/chips.prt';

PART_NAME
 C2L38 'CAP_A_0402V-0.01UF,25V,10%,X7RA':
 ROOM='ST_SATA';

SECTION_NUMBER 1
 '@BASEBOARD_FAB2_LIB.BASEBOARD_FAB2(SCH_1):PAGE173_I256@DEV_DISCRETE.CAP_A(CHIPS)':
 C_PATH='@baseboard_fab2_lib.baseboard_fab2(sch_1):page173_i256@dev_discrete.cap~
_a(chips)',
 P_PATH='@baseboard_fab2_lib.baseboard_fab2(sch_1):page173_i256@dev_discrete.cap~
_a(chips)',
 PATH='I256',
 DRAWING='@BASEBOARD_FAB2_LIB.BASEBOARD_FAB2(SCH_1):PAGE173',
 TOLERANCE='10%',
 SEC_TYPE='0402V',
 MATERIAL='X7R',
 BOM_COST='ST_SATA',
 PHYS_PAGE='173',
 XY='(1050,1900)',
 ROT='0',
 VER='2',
 VALUE='0.01UF',
 PACK_TYPE='0402V',
 PART_NUMBER='A36096-045',
 LOCATION='C2L38',
 ROOM='ST_SATA',
 SEC='1',
 CDS_LIB='dev_discrete',
 CDS_PART_NAME='CAP_A_0402V-0.01UF,25V,10%,X7RA',
 VOLTAGE='25V',
 PRIM_FILE='./archive_libs/discrete/cap_a/chips/chips.prt';

PART_NAME
 C2L39 'CAP_A_0402V-0.01UF,25V,10%,X7RA':
 ROOM='ST_SATA';

SECTION_NUMBER 1
 '@BASEBOARD_FAB2_LIB.BASEBOARD_FAB2(SCH_1):PAGE173_I221@DEV_DISCRETE.CAP_A(CHIPS)':
 C_PATH='@baseboard_fab2_lib.baseboard_fab2(sch_1):page173_i221@dev_discrete.cap~
_a(chips)',
 P_PATH='@baseboard_fab2_lib.baseboard_fab2(sch_1):page173_i221@dev_discrete.cap~
_a(chips)',
 PATH='I221',
 DRAWING='@BASEBOARD_FAB2_LIB.BASEBOARD_FAB2(SCH_1):PAGE173',
 TOLERANCE='10%',
 SEC_TYPE='0402V',
 MATERIAL='X7R',
 BOM_COST='ST_SATA',
 PHYS_PAGE='173',
 XY='(650,4675)',
 ROT='0',
 VER='2',
 VALUE='0.01UF',
 PACK_TYPE='0402V',
 PART_NUMBER='A36096-045',
 LOCATION='C2L39',
 ROOM='ST_SATA',
 SEC='1',
 CDS_LIB='dev_discrete',
 CDS_PART_NAME='CAP_A_0402V-0.01UF,25V,10%,X7RA',
 VOLTAGE='25V',
 PRIM_FILE='./archive_libs/discrete/cap_a/chips/chips.prt';

PART_NAME
 C2L40 'CAP_A_0402V-0.01UF,25V,10%,X7RA':
 ROOM='ST_SATA';

SECTION_NUMBER 1
 '@BASEBOARD_FAB2_LIB.BASEBOARD_FAB2(SCH_1):PAGE173_I220@DEV_DISCRETE.CAP_A(CHIPS)':
 C_PATH='@baseboard_fab2_lib.baseboard_fab2(sch_1):page173_i220@dev_discrete.cap~
_a(chips)',
 P_PATH='@baseboard_fab2_lib.baseboard_fab2(sch_1):page173_i220@dev_discrete.cap~
_a(chips)',
 PATH='I220',
 DRAWING='@BASEBOARD_FAB2_LIB.BASEBOARD_FAB2(SCH_1):PAGE173',
 TOLERANCE='10%',
 SEC_TYPE='0402V',
 MATERIAL='X7R',
 BOM_COST='ST_SATA',
 PHYS_PAGE='173',
 XY='(1025,4525)',
 ROT='0',
 VER='2',
 VALUE='0.01UF',
 PACK_TYPE='0402V',
 PART_NUMBER='A36096-045',
 LOCATION='C2L40',
 ROOM='ST_SATA',
 SEC='1',
 CDS_LIB='dev_discrete',
 CDS_PART_NAME='CAP_A_0402V-0.01UF,25V,10%,X7RA',
 VOLTAGE='25V',
 PRIM_FILE='./archive_libs/discrete/cap_a/chips/chips.prt';

PART_NAME
 C2L41 'CAP_A_0402V-0.01UF,25V,10%,X7RA':
 ROOM='ST_SATA';

SECTION_NUMBER 1
 '@BASEBOARD_FAB2_LIB.BASEBOARD_FAB2(SCH_1):PAGE173_I242@DEV_DISCRETE.CAP_A(CHIPS)':
 C_PATH='@baseboard_fab2_lib.baseboard_fab2(sch_1):page173_i242@dev_discrete.cap~
_a(chips)',
 P_PATH='@baseboard_fab2_lib.baseboard_fab2(sch_1):page173_i242@dev_discrete.cap~
_a(chips)',
 PATH='I242',
 DRAWING='@BASEBOARD_FAB2_LIB.BASEBOARD_FAB2(SCH_1):PAGE173',
 TOLERANCE='10%',
 SEC_TYPE='0402V',
 MATERIAL='X7R',
 BOM_COST='ST_SATA',
 PHYS_PAGE='173',
 XY='(625,3650)',
 ROT='0',
 VER='2',
 VALUE='0.01UF',
 PACK_TYPE='0402V',
 PART_NUMBER='A36096-045',
 LOCATION='C2L41',
 ROOM='ST_SATA',
 SEC='1',
 CDS_LIB='dev_discrete',
 CDS_PART_NAME='CAP_A_0402V-0.01UF,25V,10%,X7RA',
 VOLTAGE='25V',
 PRIM_FILE='./archive_libs/discrete/cap_a/chips/chips.prt';

PART_NAME
 C2L42 'CAP_A_0402V-0.01UF,25V,10%,X7RA':
 ROOM='ST_SATA';

SECTION_NUMBER 1
 '@BASEBOARD_FAB2_LIB.BASEBOARD_FAB2(SCH_1):PAGE173_I233@DEV_DISCRETE.CAP_A(CHIPS)':
 C_PATH='@baseboard_fab2_lib.baseboard_fab2(sch_1):page173_i233@dev_discrete.cap~
_a(chips)',
 P_PATH='@baseboard_fab2_lib.baseboard_fab2(sch_1):page173_i233@dev_discrete.cap~
_a(chips)',
 PATH='I233',
 DRAWING='@BASEBOARD_FAB2_LIB.BASEBOARD_FAB2(SCH_1):PAGE173',
 TOLERANCE='10%',
 SEC_TYPE='0402V',
 MATERIAL='X7R',
 BOM_COST='ST_SATA',
 PHYS_PAGE='173',
 XY='(1000,3500)',
 ROT='0',
 VER='2',
 VALUE='0.01UF',
 PACK_TYPE='0402V',
 PART_NUMBER='A36096-045',
 LOCATION='C2L42',
 ROOM='ST_SATA',
 SEC='1',
 CDS_LIB='dev_discrete',
 CDS_PART_NAME='CAP_A_0402V-0.01UF,25V,10%,X7RA',
 VOLTAGE='25V',
 PRIM_FILE='./archive_libs/discrete/cap_a/chips/chips.prt';

PART_NAME
 C2L43 'CAP_A_0402V-0.01UF,25V,10%,X7RA':
 ROOM='ST_SATA';

SECTION_NUMBER 1
 '@BASEBOARD_FAB2_LIB.BASEBOARD_FAB2(SCH_1):PAGE173_I222@DEV_DISCRETE.CAP_A(CHIPS)':
 C_PATH='@baseboard_fab2_lib.baseboard_fab2(sch_1):page173_i222@dev_discrete.cap~
_a(chips)',
 P_PATH='@baseboard_fab2_lib.baseboard_fab2(sch_1):page173_i222@dev_discrete.cap~
_a(chips)',
 PATH='I222',
 DRAWING='@BASEBOARD_FAB2_LIB.BASEBOARD_FAB2(SCH_1):PAGE173',
 TOLERANCE='10%',
 SEC_TYPE='0402V',
 MATERIAL='X7R',
 BOM_COST='ST_SATA',
 PHYS_PAGE='173',
 XY='(650,4325)',
 ROT='0',
 VER='2',
 VALUE='0.01UF',
 PACK_TYPE='0402V',
 PART_NUMBER='A36096-045',
 LOCATION='C2L43',
 ROOM='ST_SATA',
 SEC='1',
 CDS_LIB='dev_discrete',
 CDS_PART_NAME='CAP_A_0402V-0.01UF,25V,10%,X7RA',
 VOLTAGE='25V',
 PRIM_FILE='./archive_libs/discrete/cap_a/chips/chips.prt';

PART_NAME
 C2L44 'CAP_A_0402V-0.01UF,25V,10%,X7RA':
 ROOM='ST_SATA';

SECTION_NUMBER 1
 '@BASEBOARD_FAB2_LIB.BASEBOARD_FAB2(SCH_1):PAGE173_I228@DEV_DISCRETE.CAP_A(CHIPS)':
 C_PATH='@baseboard_fab2_lib.baseboard_fab2(sch_1):page173_i228@dev_discrete.cap~
_a(chips)',
 P_PATH='@baseboard_fab2_lib.baseboard_fab2(sch_1):page173_i228@dev_discrete.cap~
_a(chips)',
 PATH='I228',
 DRAWING='@BASEBOARD_FAB2_LIB.BASEBOARD_FAB2(SCH_1):PAGE173',
 TOLERANCE='10%',
 SEC_TYPE='0402V',
 MATERIAL='X7R',
 BOM_COST='ST_SATA',
 PHYS_PAGE='173',
 XY='(1025,4175)',
 ROT='0',
 VER='2',
 VALUE='0.01UF',
 PACK_TYPE='0402V',
 PART_NUMBER='A36096-045',
 LOCATION='C2L44',
 ROOM='ST_SATA',
 SEC='1',
 CDS_LIB='dev_discrete',
 CDS_PART_NAME='CAP_A_0402V-0.01UF,25V,10%,X7RA',
 VOLTAGE='25V',
 PRIM_FILE='./archive_libs/discrete/cap_a/chips/chips.prt';

PART_NAME
 C2L45 'CAP_0805-22UF,6.3V,20%,X6S,C95A':
 ROOM='P1V8_PCH_STBY_VR';

SECTION_NUMBER 1
 '@BASEBOARD_FAB2_LIB.BASEBOARD_FAB2(SCH_1):PAGE237_I12@MSTR_DISCRETE.CAP(CHIPS)':
 C_PATH='@baseboard_fab2_lib.baseboard_fab2(sch_1):page237_i12@mstr_discrete.cap~
(chips)',
 P_PATH='@baseboard_fab2_lib.baseboard_fab2(sch_1):page237_i12@mstr_discrete.cap~
(chips)',
 PATH='I12',
 DRAWING='@BASEBOARD_FAB2_LIB.BASEBOARD_FAB2(SCH_1):PAGE237',
 TOLERANCE='20%',
 MATERIAL='X6S',
 BOM_COST='P1V8_PCH_STBY_VR',
 PHYS_PAGE='237',
 XY='(3375,2150)',
 ROT='0',
 VER='1',
 VALUE='22UF',
 PACK_TYPE='0805',
 PART_NUMBER='C95333-008',
 LOCATION='C2L45',
 ROOM='P1V8_PCH_STBY_VR',
 CDS_LIB='mstr_discrete',
 CDS_PART_NAME='CAP_0805-22UF,6.3V,20%,X6S,C95A',
 VOLTAGE='6.3V',
 PRIM_FILE='./archive_libs/mstr_discrete/cap/chips/chips.prt';

PART_NAME
 C2L46 'CAPP_SM-470UF,2V,20%,ALUM,6990A':
 ROOM='P1V05_PCH_STBY';

SECTION_NUMBER 1
 '@BASEBOARD_FAB2_LIB.BASEBOARD_FAB2(SCH_1):PAGE236_I77@MSTR_DISCRETE.CAPP(CHIPS)':
 C_PATH='@baseboard_fab2_lib.baseboard_fab2(sch_1):page236_i77@mstr_discrete.cap~
p(chips)',
 P_PATH='@baseboard_fab2_lib.baseboard_fab2(sch_1):page236_i77@mstr_discrete.cap~
p(chips)',
 PATH='I77',
 DRAWING='@BASEBOARD_FAB2_LIB.BASEBOARD_FAB2(SCH_1):PAGE236',
 TOLERANCE='20%',
 SEC_TYPE='SM',
 MATERIAL='ALUM',
 PHYS_PAGE='236',
 XY='(12175,2050)',
 ROT='0',
 VER='1',
 VALUE='470UF',
 PACK_TYPE='SM',
 PART_NUMBER='699013-031',
 LOCATION='C2L46',
 ROOM='P1V05_PCH_STBY',
 SEC='1',
 CDS_LIB='mstr_discrete',
 CDS_PART_NAME='CAPP_SM-470UF,2V,20%,ALUM,6990A',
 VOLTAGE='2V',
 PRIM_FILE='./archive_libs/mstr_discrete/capp/chips/chips.prt';

PART_NAME
 C2L47 'CAP_A_0402V-0.01UF,25V,10%,X7RA':
 ROOM='ST_SATA';

SECTION_NUMBER 1
 '@BASEBOARD_FAB2_LIB.BASEBOARD_FAB2(SCH_1):PAGE173_I239@DEV_DISCRETE.CAP_A(CHIPS)':
 C_PATH='@baseboard_fab2_lib.baseboard_fab2(sch_1):page173_i239@dev_discrete.cap~
_a(chips)',
 P_PATH='@baseboard_fab2_lib.baseboard_fab2(sch_1):page173_i239@dev_discrete.cap~
_a(chips)',
 PATH='I239',
 DRAWING='@BASEBOARD_FAB2_LIB.BASEBOARD_FAB2(SCH_1):PAGE173',
 TOLERANCE='10%',
 SEC_TYPE='0402V',
 MATERIAL='X7R',
 BOM_COST='ST_SATA',
 PHYS_PAGE='173',
 XY='(650,2925)',
 ROT='0',
 VER='2',
 VALUE='0.01UF',
 PACK_TYPE='0402V',
 PART_NUMBER='A36096-045',
 LOCATION='C2L47',
 ROOM='ST_SATA',
 SEC='1',
 CDS_LIB='dev_discrete',
 CDS_PART_NAME='CAP_A_0402V-0.01UF,25V,10%,X7RA',
 VOLTAGE='25V',
 PRIM_FILE='./archive_libs/discrete/cap_a/chips/chips.prt';

PART_NAME
 C2L48 'CAP_A_0402V-0.01UF,25V,10%,X7RA':
 ROOM='ST_SATA';

SECTION_NUMBER 1
 '@BASEBOARD_FAB2_LIB.BASEBOARD_FAB2(SCH_1):PAGE173_I257@DEV_DISCRETE.CAP_A(CHIPS)':
 C_PATH='@baseboard_fab2_lib.baseboard_fab2(sch_1):page173_i257@dev_discrete.cap~
_a(chips)',
 P_PATH='@baseboard_fab2_lib.baseboard_fab2(sch_1):page173_i257@dev_discrete.cap~
_a(chips)',
 PATH='I257',
 DRAWING='@BASEBOARD_FAB2_LIB.BASEBOARD_FAB2(SCH_1):PAGE173',
 TOLERANCE='10%',
 SEC_TYPE='0402V',
 MATERIAL='X7R',
 BOM_COST='ST_SATA',
 PHYS_PAGE='173',
 XY='(650,2050)',
 ROT='0',
 VER='2',
 VALUE='0.01UF',
 PACK_TYPE='0402V',
 PART_NUMBER='A36096-045',
 LOCATION='C2L48',
 ROOM='ST_SATA',
 SEC='1',
 CDS_LIB='dev_discrete',
 CDS_PART_NAME='CAP_A_0402V-0.01UF,25V,10%,X7RA',
 VOLTAGE='25V',
 PRIM_FILE='./archive_libs/discrete/cap_a/chips/chips.prt';

PART_NAME
 C2L49 'CAP_A_0402V-0.01UF,25V,10%,X7RA':
 ROOM='ST_SATA';

SECTION_NUMBER 1
 '@BASEBOARD_FAB2_LIB.BASEBOARD_FAB2(SCH_1):PAGE172_I5@DEV_DISCRETE.CAP_A(CHIPS)':
 C_PATH='@baseboard_fab2_lib.baseboard_fab2(sch_1):page172_i5@dev_discrete.cap_a~
(chips)',
 P_PATH='@baseboard_fab2_lib.baseboard_fab2(sch_1):page172_i5@dev_discrete.cap_a~
(chips)',
 PATH='I5',
 DRAWING='@BASEBOARD_FAB2_LIB.BASEBOARD_FAB2(SCH_1):PAGE172',
 TOLERANCE='10%',
 SEC_TYPE='0402V',
 MATERIAL='X7R',
 PHYS_PAGE='172',
 XY='(1225,2100)',
 ROT='0',
 VER='2',
 VALUE='0.01UF',
 PACK_TYPE='0402V',
 PART_NUMBER='A36096-045',
 LOCATION='C2L49',
 ROOM='ST_SATA',
 SEC='1',
 CDS_LIB='dev_discrete',
 CDS_PART_NAME='CAP_A_0402V-0.01UF,25V,10%,X7RA',
 VOLTAGE='25V',
 PRIM_FILE='./archive_libs/discrete/cap_a/chips/chips.prt';

PART_NAME
 C2L50 'CAP_A_0402V-0.01UF,25V,10%,X7RA':
 ROOM='ST_SATA';

SECTION_NUMBER 1
 '@BASEBOARD_FAB2_LIB.BASEBOARD_FAB2(SCH_1):PAGE172_I7@DEV_DISCRETE.CAP_A(CHIPS)':
 C_PATH='@baseboard_fab2_lib.baseboard_fab2(sch_1):page172_i7@dev_discrete.cap_a~
(chips)',
 P_PATH='@baseboard_fab2_lib.baseboard_fab2(sch_1):page172_i7@dev_discrete.cap_a~
(chips)',
 PATH='I7',
 DRAWING='@BASEBOARD_FAB2_LIB.BASEBOARD_FAB2(SCH_1):PAGE172',
 TOLERANCE='10%',
 SEC_TYPE='0402V',
 MATERIAL='X7R',
 PHYS_PAGE='172',
 XY='(350,2150)',
 ROT='0',
 VER='2',
 VALUE='0.01UF',
 PACK_TYPE='0402V',
 PART_NUMBER='A36096-045',
 LOCATION='C2L50',
 ROOM='ST_SATA',
 SEC='1',
 CDS_LIB='dev_discrete',
 CDS_PART_NAME='CAP_A_0402V-0.01UF,25V,10%,X7RA',
 VOLTAGE='25V',
 PRIM_FILE='./archive_libs/discrete/cap_a/chips/chips.prt';

PART_NAME
 C2L51 'CAP_A_0402V-0.01UF,25V,10%,X7RA':
 ROOM='ST_SATA';

SECTION_NUMBER 1
 '@BASEBOARD_FAB2_LIB.BASEBOARD_FAB2(SCH_1):PAGE172_I8@DEV_DISCRETE.CAP_A(CHIPS)':
 C_PATH='@baseboard_fab2_lib.baseboard_fab2(sch_1):page172_i8@dev_discrete.cap_a~
(chips)',
 P_PATH='@baseboard_fab2_lib.baseboard_fab2(sch_1):page172_i8@dev_discrete.cap_a~
(chips)',
 PATH='I8',
 DRAWING='@BASEBOARD_FAB2_LIB.BASEBOARD_FAB2(SCH_1):PAGE172',
 TOLERANCE='10%',
 SEC_TYPE='0402V',
 MATERIAL='X7R',
 PHYS_PAGE='172',
 XY='(750,2250)',
 ROT='0',
 VER='2',
 VALUE='0.01UF',
 PACK_TYPE='0402V',
 PART_NUMBER='A36096-045',
 LOCATION='C2L51',
 ROOM='ST_SATA',
 SEC='1',
 CDS_LIB='dev_discrete',
 CDS_PART_NAME='CAP_A_0402V-0.01UF,25V,10%,X7RA',
 VOLTAGE='25V',
 PRIM_FILE='./archive_libs/discrete/cap_a/chips/chips.prt';

PART_NAME
 C2L52 'CAP_A_0402V-0.01UF,25V,10%,X7RA':
 ROOM='ST_SATA';

SECTION_NUMBER 1
 '@BASEBOARD_FAB2_LIB.BASEBOARD_FAB2(SCH_1):PAGE172_I6@DEV_DISCRETE.CAP_A(CHIPS)':
 C_PATH='@baseboard_fab2_lib.baseboard_fab2(sch_1):page172_i6@dev_discrete.cap_a~
(chips)',
 P_PATH='@baseboard_fab2_lib.baseboard_fab2(sch_1):page172_i6@dev_discrete.cap_a~
(chips)',
 PATH='I6',
 DRAWING='@BASEBOARD_FAB2_LIB.BASEBOARD_FAB2(SCH_1):PAGE172',
 TOLERANCE='10%',
 SEC_TYPE='0402V',
 MATERIAL='X7R',
 PHYS_PAGE='172',
 XY='(0,2300)',
 ROT='0',
 VER='2',
 VALUE='0.01UF',
 PACK_TYPE='0402V',
 PART_NUMBER='A36096-045',
 LOCATION='C2L52',
 ROOM='ST_SATA',
 SEC='1',
 CDS_LIB='dev_discrete',
 CDS_PART_NAME='CAP_A_0402V-0.01UF,25V,10%,X7RA',
 VOLTAGE='25V',
 PRIM_FILE='./archive_libs/discrete/cap_a/chips/chips.prt';

PART_NAME
 C2M1 'CAP_A_0603V-22.0UF,4V,20%,X6S,A':
 ROOM='SB_DECOUPLING';

SECTION_NUMBER 1
 '@BASEBOARD_FAB2_LIB.BASEBOARD_FAB2(SCH_1):PAGE130_I43@DEV_DISCRETE.CAP_A(CHIPS)':
 C_PATH='@baseboard_fab2_lib.baseboard_fab2(sch_1):page130_i43@dev_discrete.cap_~
a(chips)',
 P_PATH='@baseboard_fab2_lib.baseboard_fab2(sch_1):page130_i43@dev_discrete.cap_~
a(chips)',
 PATH='I43',
 DRAWING='@BASEBOARD_FAB2_LIB.BASEBOARD_FAB2(SCH_1):PAGE130',
 TOLERANCE='20%',
 MATERIAL='X6S',
 BOM_COST='SB',
 PHYS_PAGE='130',
 XY='(-4725,2750)',
 ROT='0',
 VER='1',
 VALUE='22.0UF',
 PACK_TYPE='0603V',
 PART_NUMBER='E15431-004',
 LOCATION='C2M1',
 ROOM='SB_DECOUPLING',
 CDS_LIB='dev_discrete',
 CDS_PART_NAME='CAP_A_0603V-22.0UF,4V,20%,X6S,A',
 VOLTAGE='4V',
 PRIM_FILE='./archive_libs/discrete/cap_a/chips/chips.prt';

PART_NAME
 C2M2 'CAP_A_0603V-22.0UF,4V,20%,X6S,A':
 ROOM='SB_DECOUPLING';

SECTION_NUMBER 1
 '@BASEBOARD_FAB2_LIB.BASEBOARD_FAB2(SCH_1):PAGE130_I45@DEV_DISCRETE.CAP_A(CHIPS)':
 C_PATH='@baseboard_fab2_lib.baseboard_fab2(sch_1):page130_i45@dev_discrete.cap_~
a(chips)',
 P_PATH='@baseboard_fab2_lib.baseboard_fab2(sch_1):page130_i45@dev_discrete.cap_~
a(chips)',
 PATH='I45',
 DRAWING='@BASEBOARD_FAB2_LIB.BASEBOARD_FAB2(SCH_1):PAGE130',
 TOLERANCE='20%',
 MATERIAL='X6S',
 BOM_COST='SB',
 PHYS_PAGE='130',
 XY='(-5150,2750)',
 ROT='0',
 VER='1',
 VALUE='22.0UF',
 PACK_TYPE='0603V',
 PART_NUMBER='E15431-004',
 LOCATION='C2M2',
 ROOM='SB_DECOUPLING',
 CDS_LIB='dev_discrete',
 CDS_PART_NAME='CAP_A_0603V-22.0UF,4V,20%,X6S,A',
 VOLTAGE='4V',
 PRIM_FILE='./archive_libs/discrete/cap_a/chips/chips.prt';

PART_NAME
 C2M3 'CAP_A_0402V-0.1UF,16V,10%,X7R,A':
 GROUP='AST2500',
 ROOM='PROC_SIDEBAND';

SECTION_NUMBER 1
 '@BASEBOARD_FAB2_LIB.BASEBOARD_FAB2(SCH_1):PAGE116_I239@DEV_DISCRETE.CAP_A(CHIPS)':
 C_PATH='@baseboard_fab2_lib.baseboard_fab2(sch_1):page116_i239@dev_discrete.cap~
_a(chips)',
 P_PATH='@baseboard_fab2_lib.baseboard_fab2(sch_1):page116_i239@dev_discrete.cap~
_a(chips)',
 PATH='I239',
 DRAWING='@BASEBOARD_FAB2_LIB.BASEBOARD_FAB2(SCH_1):PAGE116',
 TOLERANCE='10%',
 SEC_TYPE='0402V',
 MATERIAL='X7R',
 BOM_COST='PROC_SIDEBAND',
 PHYS_PAGE='116',
 XY='(-1325,2600)',
 ROT='1',
 VER='1',
 VALUE='0.1UF',
 PACK_TYPE='0402V',
 PART_NUMBER='A36096-030',
 LOCATION='C2M3',
 ROOM='PROC_SIDEBAND',
 GROUP='AST2500',
 SEC='1',
 CDS_LIB='dev_discrete',
 CDS_PART_NAME='CAP_A_0402V-0.1UF,16V,10%,X7R,A',
 VOLTAGE='16V',
 PRIM_FILE='./archive_libs/discrete/cap_a/chips/chips.prt';

PART_NAME
 C2M4 'CAP_A_0402V-0.1UF,16V,10%,X7R,A':
 GROUP='AST2500',
 ROOM='PROC_SIDEBAND';

SECTION_NUMBER 1
 '@BASEBOARD_FAB2_LIB.BASEBOARD_FAB2(SCH_1):PAGE116_I238@DEV_DISCRETE.CAP_A(CHIPS)':
 C_PATH='@baseboard_fab2_lib.baseboard_fab2(sch_1):page116_i238@dev_discrete.cap~
_a(chips)',
 P_PATH='@baseboard_fab2_lib.baseboard_fab2(sch_1):page116_i238@dev_discrete.cap~
_a(chips)',
 PATH='I238',
 DRAWING='@BASEBOARD_FAB2_LIB.BASEBOARD_FAB2(SCH_1):PAGE116',
 TOLERANCE='10%',
 SEC_TYPE='0402V',
 MATERIAL='X7R',
 BOM_COST='PROC_SIDEBAND',
 PHYS_PAGE='116',
 XY='(-1725,2650)',
 ROT='1',
 VER='1',
 VALUE='0.1UF',
 PACK_TYPE='0402V',
 PART_NUMBER='A36096-030',
 LOCATION='C2M4',
 ROOM='PROC_SIDEBAND',
 GROUP='AST2500',
 SEC='1',
 CDS_LIB='dev_discrete',
 CDS_PART_NAME='CAP_A_0402V-0.1UF,16V,10%,X7R,A',
 VOLTAGE='16V',
 PRIM_FILE='./archive_libs/discrete/cap_a/chips/chips.prt';

PART_NAME
 C2M5 'CAP_0603LF-10UF,4V,20%,X6S,E15A':
 ROOM='SB_FILTER_VM20';

SECTION_NUMBER 1
 '@BASEBOARD_FAB2_LIB.BASEBOARD_FAB2(SCH_1):PAGE127_I43@MSTR_DISCRETE.CAP(CHIPS)':
 C_PATH='@baseboard_fab2_lib.baseboard_fab2(sch_1):page127_i43@mstr_discrete.cap~
(chips)',
 P_PATH='@baseboard_fab2_lib.baseboard_fab2(sch_1):page127_i43@mstr_discrete.cap~
(chips)',
 PATH='I43',
 DRAWING='@BASEBOARD_FAB2_LIB.BASEBOARD_FAB2(SCH_1):PAGE127',
 TOLERANCE='20%',
 SEC_TYPE='0603LF',
 MATERIAL='X6S',
 BOM_COST='SB',
 PHYS_PAGE='127',
 XY='(1850,-1375)',
 ROT='0',
 VER='1',
 VALUE='10UF',
 PACK_TYPE='0603LF',
 PART_NUMBER='E15431-001',
 LOCATION='C2M5',
 ROOM='SB_FILTER_VM20',
 SEC='1',
 CDS_LIB='mstr_discrete',
 CDS_PART_NAME='CAP_0603LF-10UF,4V,20%,X6S,E15A',
 VOLTAGE='4V',
 PRIM_FILE='./archive_libs/mstr_discrete/cap/chips/chips.prt';

PART_NAME
 C2M6 'CAP_A_0402V-1.0UF,6.3V,10%,X6SA':
 ROOM='SB_FILTER_VM20';

SECTION_NUMBER 1
 '@BASEBOARD_FAB2_LIB.BASEBOARD_FAB2(SCH_1):PAGE127_I76@DEV_DISCRETE.CAP_A(CHIPS)':
 C_PATH='@baseboard_fab2_lib.baseboard_fab2(sch_1):page127_i76@dev_discrete.cap_~
a(chips)',
 P_PATH='@baseboard_fab2_lib.baseboard_fab2(sch_1):page127_i76@dev_discrete.cap_~
a(chips)',
 PATH='I76',
 DRAWING='@BASEBOARD_FAB2_LIB.BASEBOARD_FAB2(SCH_1):PAGE127',
 TOLERANCE='10%',
 SEC_TYPE='0402V',
 MATERIAL='X6S',
 BOM_COST='SB',
 PHYS_PAGE='127',
 XY='(950,-1375)',
 ROT='2',
 VER='1',
 VALUE='1.0UF',
 PACK_TYPE='0402V',
 PART_NUMBER='D97712-004',
 LOCATION='C2M6',
 ROOM='SB_FILTER_VM20',
 SEC='1',
 CDS_LIB='dev_discrete',
 CDS_PART_NAME='CAP_A_0402V-1.0UF,6.3V,10%,X6SA',
 VOLTAGE='6.3V',
 PRIM_FILE='./archive_libs/discrete/cap_a/chips/chips.prt';

PART_NAME
 C2M7 'CAP_A_0402V-1.0UF,6.3V,10%,X6SA':
 ROOM='SB_FILTER_VM20';

SECTION_NUMBER 1
 '@BASEBOARD_FAB2_LIB.BASEBOARD_FAB2(SCH_1):PAGE127_I44@DEV_DISCRETE.CAP_A(CHIPS)':
 C_PATH='@baseboard_fab2_lib.baseboard_fab2(sch_1):page127_i44@dev_discrete.cap_~
a(chips)',
 P_PATH='@baseboard_fab2_lib.baseboard_fab2(sch_1):page127_i44@dev_discrete.cap_~
a(chips)',
 PATH='I44',
 DRAWING='@BASEBOARD_FAB2_LIB.BASEBOARD_FAB2(SCH_1):PAGE127',
 TOLERANCE='10%',
 SEC_TYPE='0402V',
 MATERIAL='X6S',
 BOM_COST='SB',
 PHYS_PAGE='127',
 XY='(1400,-1375)',
 ROT='0',
 VER='1',
 VALUE='1.0UF',
 PACK_TYPE='0402V',
 PART_NUMBER='D97712-004',
 LOCATION='C2M7',
 ROOM='SB_FILTER_VM20',
 SEC='1',
 CDS_LIB='dev_discrete',
 CDS_PART_NAME='CAP_A_0402V-1.0UF,6.3V,10%,X6SA',
 VOLTAGE='6.3V',
 PRIM_FILE='./archive_libs/discrete/cap_a/chips/chips.prt';

PART_NAME
 C2M8 'CAP_A_0402V-1.0UF,6.3V,10%,X6SA':
 ROOM='SB_FILTER_VM26';

SECTION_NUMBER 1
 '@BASEBOARD_FAB2_LIB.BASEBOARD_FAB2(SCH_1):PAGE127_I74@DEV_DISCRETE.CAP_A(CHIPS)':
 C_PATH='@baseboard_fab2_lib.baseboard_fab2(sch_1):page127_i74@dev_discrete.cap_~
a(chips)',
 P_PATH='@baseboard_fab2_lib.baseboard_fab2(sch_1):page127_i74@dev_discrete.cap_~
a(chips)',
 PATH='I74',
 DRAWING='@BASEBOARD_FAB2_LIB.BASEBOARD_FAB2(SCH_1):PAGE127',
 TOLERANCE='10%',
 SEC_TYPE='0402V',
 MATERIAL='X6S',
 BOM_COST='SB',
 PHYS_PAGE='127',
 XY='(-1450,-1400)',
 ROT='2',
 VER='1',
 VALUE='1.0UF',
 PACK_TYPE='0402V',
 PART_NUMBER='D97712-004',
 LOCATION='C2M8',
 ROOM='SB_FILTER_VM26',
 SEC='1',
 CDS_LIB='dev_discrete',
 CDS_PART_NAME='CAP_A_0402V-1.0UF,6.3V,10%,X6SA',
 VOLTAGE='6.3V',
 PRIM_FILE='./archive_libs/discrete/cap_a/chips/chips.prt';

PART_NAME
 C2M9 'CAP_A_0402V-1.0UF,6.3V,10%,X6SA':
 ROOM='SB_FILTER_VM26';

SECTION_NUMBER 1
 '@BASEBOARD_FAB2_LIB.BASEBOARD_FAB2(SCH_1):PAGE127_I50@DEV_DISCRETE.CAP_A(CHIPS)':
 C_PATH='@baseboard_fab2_lib.baseboard_fab2(sch_1):page127_i50@dev_discrete.cap_~
a(chips)',
 P_PATH='@baseboard_fab2_lib.baseboard_fab2(sch_1):page127_i50@dev_discrete.cap_~
a(chips)',
 PATH='I50',
 DRAWING='@BASEBOARD_FAB2_LIB.BASEBOARD_FAB2(SCH_1):PAGE127',
 TOLERANCE='10%',
 SEC_TYPE='0402V',
 MATERIAL='X6S',
 BOM_COST='SB',
 PHYS_PAGE='127',
 XY='(-1000,-1400)',
 ROT='0',
 VER='1',
 VALUE='1.0UF',
 PACK_TYPE='0402V',
 PART_NUMBER='D97712-004',
 LOCATION='C2M9',
 ROOM='SB_FILTER_VM26',
 SEC='1',
 CDS_LIB='dev_discrete',
 CDS_PART_NAME='CAP_A_0402V-1.0UF,6.3V,10%,X6SA',
 VOLTAGE='6.3V',
 PRIM_FILE='./archive_libs/discrete/cap_a/chips/chips.prt';

PART_NAME
 C2M10 'CAP_0603LF-10UF,4V,20%,X6S,E15A':
 ROOM='SB_FILTER_VM26';

SECTION_NUMBER 1
 '@BASEBOARD_FAB2_LIB.BASEBOARD_FAB2(SCH_1):PAGE127_I49@MSTR_DISCRETE.CAP(CHIPS)':
 C_PATH='@baseboard_fab2_lib.baseboard_fab2(sch_1):page127_i49@mstr_discrete.cap~
(chips)',
 P_PATH='@baseboard_fab2_lib.baseboard_fab2(sch_1):page127_i49@mstr_discrete.cap~
(chips)',
 PATH='I49',
 DRAWING='@BASEBOARD_FAB2_LIB.BASEBOARD_FAB2(SCH_1):PAGE127',
 TOLERANCE='20%',
 SEC_TYPE='0603LF',
 MATERIAL='X6S',
 BOM_COST='SB',
 PHYS_PAGE='127',
 XY='(-500,-1400)',
 ROT='0',
 VER='1',
 VALUE='10UF',
 PACK_TYPE='0603LF',
 PART_NUMBER='E15431-001',
 LOCATION='C2M10',
 ROOM='SB_FILTER_VM26',
 SEC='1',
 CDS_LIB='mstr_discrete',
 CDS_PART_NAME='CAP_0603LF-10UF,4V,20%,X6S,E15A',
 VOLTAGE='4V',
 PRIM_FILE='./archive_libs/mstr_discrete/cap/chips/chips.prt';

PART_NAME
 C2M11 'CAP_0805-47UF,4V,20%,X6S,C9533A':
 ROOM='SB_DECOUPLING';

SECTION_NUMBER 1
 '@BASEBOARD_FAB2_LIB.BASEBOARD_FAB2(SCH_1):PAGE131_I35@MSTR_DISCRETE.CAP(CHIPS)':
 C_PATH='@baseboard_fab2_lib.baseboard_fab2(sch_1):page131_i35@mstr_discrete.cap~
(chips)',
 P_PATH='@baseboard_fab2_lib.baseboard_fab2(sch_1):page131_i35@mstr_discrete.cap~
(chips)',
 PATH='I35',
 DRAWING='@BASEBOARD_FAB2_LIB.BASEBOARD_FAB2(SCH_1):PAGE131',
 TOLERANCE='20%',
 MATERIAL='X6S',
 BOM_COST='SB',
 PHYS_PAGE='131',
 XY='(-2800,2025)',
 ROT='0',
 VER='1',
 VALUE='47UF',
 PACK_TYPE='0805',
 PART_NUMBER='C95333-006',
 LOCATION='C2M11',
 ROOM='SB_DECOUPLING',
 CDS_LIB='mstr_discrete',
 CDS_PART_NAME='CAP_0805-47UF,4V,20%,X6S,C9533A',
 VOLTAGE='4V',
 PRIM_FILE='./archive_libs/mstr_discrete/cap/chips/chips.prt';

PART_NAME
 C2M12 'CAP_A_0603V-22.0UF,4V,20%,X6S,A':
 ROOM='SB_DECOUPLING';

SECTION_NUMBER 1
 '@BASEBOARD_FAB2_LIB.BASEBOARD_FAB2(SCH_1):PAGE131_I52@DEV_DISCRETE.CAP_A(CHIPS)':
 C_PATH='@baseboard_fab2_lib.baseboard_fab2(sch_1):page131_i52@dev_discrete.cap_~
a(chips)',
 P_PATH='@baseboard_fab2_lib.baseboard_fab2(sch_1):page131_i52@dev_discrete.cap_~
a(chips)',
 PATH='I52',
 DRAWING='@BASEBOARD_FAB2_LIB.BASEBOARD_FAB2(SCH_1):PAGE131',
 TOLERANCE='20%',
 MATERIAL='X6S',
 BOM_COST='SB',
 PHYS_PAGE='131',
 XY='(-5075,2100)',
 ROT='0',
 VER='1',
 VALUE='22.0UF',
 PACK_TYPE='0603V',
 PART_NUMBER='E15431-004',
 LOCATION='C2M12',
 ROOM='SB_DECOUPLING',
 CDS_LIB='dev_discrete',
 CDS_PART_NAME='CAP_A_0603V-22.0UF,4V,20%,X6S,A',
 VOLTAGE='4V',
 PRIM_FILE='./archive_libs/discrete/cap_a/chips/chips.prt';

PART_NAME
 C2M13 'CAP_A_0603V-22.0UF,4V,20%,X6S,A':
 ROOM='SB_DECOUPLING';

SECTION_NUMBER 1
 '@BASEBOARD_FAB2_LIB.BASEBOARD_FAB2(SCH_1):PAGE131_I48@DEV_DISCRETE.CAP_A(CHIPS)':
 C_PATH='@baseboard_fab2_lib.baseboard_fab2(sch_1):page131_i48@dev_discrete.cap_~
a(chips)',
 P_PATH='@baseboard_fab2_lib.baseboard_fab2(sch_1):page131_i48@dev_discrete.cap_~
a(chips)',
 PATH='I48',
 DRAWING='@BASEBOARD_FAB2_LIB.BASEBOARD_FAB2(SCH_1):PAGE131',
 TOLERANCE='20%',
 MATERIAL='X6S',
 BOM_COST='SB',
 PHYS_PAGE='131',
 XY='(-4250,2100)',
 ROT='0',
 VER='1',
 VALUE='22.0UF',
 PACK_TYPE='0603V',
 PART_NUMBER='E15431-004',
 LOCATION='C2M13',
 ROOM='SB_DECOUPLING',
 CDS_LIB='dev_discrete',
 CDS_PART_NAME='CAP_A_0603V-22.0UF,4V,20%,X6S,A',
 VOLTAGE='4V',
 PRIM_FILE='./archive_libs/discrete/cap_a/chips/chips.prt';

PART_NAME
 C2M14 'CAP_0402-0.22UF,16V,10%,X7R,A3A':
 ROOM='PCIE_STEERING';

SECTION_NUMBER 1
 '@BASEBOARD_FAB2_LIB.BASEBOARD_FAB2(SCH_1):PAGE106_I76@MSTR_DISCRETE.CAP(CHIPS)':
 C_PATH='@baseboard_fab2_lib.baseboard_fab2(sch_1):page106_i76@mstr_discrete.cap~
(chips)',
 P_PATH='@baseboard_fab2_lib.baseboard_fab2(sch_1):page106_i76@mstr_discrete.cap~
(chips)',
 PATH='I76',
 DRAWING='@BASEBOARD_FAB2_LIB.BASEBOARD_FAB2(SCH_1):PAGE106',
 TOLERANCE='10%',
 MATERIAL='X7R',
 BOM_COST='IO_SLOT',
 PHYS_PAGE='106',
 XY='(-5700,2650)',
 ROT='2',
 VER='1',
 VALUE='0.22UF',
 PACK_TYPE='0402',
 PART_NUMBER='A36096-155',
 LOCATION='C2M14',
 ROOM='PCIE_STEERING',
 CDS_LIB='mstr_discrete',
 CDS_PART_NAME='CAP_0402-0.22UF,16V,10%,X7R,A3A',
 VOLTAGE='16V',
 PRIM_FILE='./archive_libs/mstr_discrete/cap/chips/chips.prt';

PART_NAME
 C2M15 'CAP_0402-0.22UF,16V,10%,X7R,A3A':
 ROOM='PCIE_STEERING';

SECTION_NUMBER 1
 '@BASEBOARD_FAB2_LIB.BASEBOARD_FAB2(SCH_1):PAGE106_I86@MSTR_DISCRETE.CAP(CHIPS)':
 C_PATH='@baseboard_fab2_lib.baseboard_fab2(sch_1):page106_i86@mstr_discrete.cap~
(chips)',
 P_PATH='@baseboard_fab2_lib.baseboard_fab2(sch_1):page106_i86@mstr_discrete.cap~
(chips)',
 PATH='I86',
 DRAWING='@BASEBOARD_FAB2_LIB.BASEBOARD_FAB2(SCH_1):PAGE106',
 TOLERANCE='10%',
 MATERIAL='X7R',
 BOM_COST='IO_SLOT',
 PHYS_PAGE='106',
 XY='(-5650,1650)',
 ROT='2',
 VER='1',
 VALUE='0.22UF',
 PACK_TYPE='0402',
 PART_NUMBER='A36096-155',
 LOCATION='C2M15',
 ROOM='PCIE_STEERING',
 CDS_LIB='mstr_discrete',
 CDS_PART_NAME='CAP_0402-0.22UF,16V,10%,X7R,A3A',
 VOLTAGE='16V',
 PRIM_FILE='./archive_libs/mstr_discrete/cap/chips/chips.prt';

PART_NAME
 C2M16 'CAP_A_0402V-1.0UF,6.3V,10%,X6SA':
 ROOM='SB_DECOUPLING';

SECTION_NUMBER 1
 '@BASEBOARD_FAB2_LIB.BASEBOARD_FAB2(SCH_1):PAGE130_I37@DEV_DISCRETE.CAP_A(CHIPS)':
 C_PATH='@baseboard_fab2_lib.baseboard_fab2(sch_1):page130_i37@dev_discrete.cap_~
a(chips)',
 P_PATH='@baseboard_fab2_lib.baseboard_fab2(sch_1):page130_i37@dev_discrete.cap_~
a(chips)',
 PATH='I37',
 DRAWING='@BASEBOARD_FAB2_LIB.BASEBOARD_FAB2(SCH_1):PAGE130',
 TOLERANCE='10%',
 MATERIAL='X6S',
 BOM_COST='SB',
 PHYS_PAGE='130',
 XY='(-4200,3925)',
 ROT='0',
 VER='1',
 VALUE='1.0UF',
 PACK_TYPE='0402V',
 PART_NUMBER='D97712-004',
 LOCATION='C2M16',
 ROOM='SB_DECOUPLING',
 CDS_LIB='dev_discrete',
 CDS_PART_NAME='CAP_A_0402V-1.0UF,6.3V,10%,X6SA',
 VOLTAGE='6.3V',
 PRIM_FILE='./archive_libs/discrete/cap_a/chips/chips.prt';

PART_NAME
 C2M17 'CAP_0805-47UF,4V,20%,X6S,C9533A':
 ROOM='SB_DECOUPLING';

SECTION_NUMBER 1
 '@BASEBOARD_FAB2_LIB.BASEBOARD_FAB2(SCH_1):PAGE131_I34@MSTR_DISCRETE.CAP(CHIPS)':
 C_PATH='@baseboard_fab2_lib.baseboard_fab2(sch_1):page131_i34@mstr_discrete.cap~
(chips)',
 P_PATH='@baseboard_fab2_lib.baseboard_fab2(sch_1):page131_i34@mstr_discrete.cap~
(chips)',
 PATH='I34',
 DRAWING='@BASEBOARD_FAB2_LIB.BASEBOARD_FAB2(SCH_1):PAGE131',
 TOLERANCE='20%',
 MATERIAL='X6S',
 BOM_COST='SB',
 PHYS_PAGE='131',
 XY='(-2400,2025)',
 ROT='0',
 VER='1',
 VALUE='47UF',
 PACK_TYPE='0805',
 PART_NUMBER='C95333-006',
 LOCATION='C2M17',
 ROOM='SB_DECOUPLING',
 CDS_LIB='mstr_discrete',
 CDS_PART_NAME='CAP_0805-47UF,4V,20%,X6S,C9533A',
 VOLTAGE='4V',
 PRIM_FILE='./archive_libs/mstr_discrete/cap/chips/chips.prt';

PART_NAME
 C2M18 'CAP_A_0402V-1.0UF,6.3V,10%,X6SA':
 ROOM='SB_DECOUPLING';

SECTION_NUMBER 1
 '@BASEBOARD_FAB2_LIB.BASEBOARD_FAB2(SCH_1):PAGE131_I29@DEV_DISCRETE.CAP_A(CHIPS)':
 C_PATH='@baseboard_fab2_lib.baseboard_fab2(sch_1):page131_i29@dev_discrete.cap_~
a(chips)',
 P_PATH='@baseboard_fab2_lib.baseboard_fab2(sch_1):page131_i29@dev_discrete.cap_~
a(chips)',
 PATH='I29',
 DRAWING='@BASEBOARD_FAB2_LIB.BASEBOARD_FAB2(SCH_1):PAGE131',
 TOLERANCE='10%',
 MATERIAL='X6S',
 BOM_COST='SB',
 PHYS_PAGE='131',
 XY='(-3175,4725)',
 ROT='0',
 VER='1',
 VALUE='1.0UF',
 PACK_TYPE='0402V',
 PART_NUMBER='D97712-004',
 LOCATION='C2M18',
 ROOM='SB_DECOUPLING',
 CDS_LIB='dev_discrete',
 CDS_PART_NAME='CAP_A_0402V-1.0UF,6.3V,10%,X6SA',
 VOLTAGE='6.3V',
 PRIM_FILE='./archive_libs/discrete/cap_a/chips/chips.prt';

PART_NAME
 C2M19 'CAP_A_0402V-1.0UF,6.3V,10%,X6SA':
 ROOM='SB_DECOUPLING';

SECTION_NUMBER 1
 '@BASEBOARD_FAB2_LIB.BASEBOARD_FAB2(SCH_1):PAGE131_I31@DEV_DISCRETE.CAP_A(CHIPS)':
 C_PATH='@baseboard_fab2_lib.baseboard_fab2(sch_1):page131_i31@dev_discrete.cap_~
a(chips)',
 P_PATH='@baseboard_fab2_lib.baseboard_fab2(sch_1):page131_i31@dev_discrete.cap_~
a(chips)',
 PATH='I31',
 DRAWING='@BASEBOARD_FAB2_LIB.BASEBOARD_FAB2(SCH_1):PAGE131',
 TOLERANCE='10%',
 MATERIAL='X6S',
 BOM_COST='SB',
 PHYS_PAGE='131',
 XY='(-2850,3525)',
 ROT='0',
 VER='1',
 VALUE='1.0UF',
 PACK_TYPE='0402V',
 PART_NUMBER='D97712-004',
 LOCATION='C2M19',
 ROOM='SB_DECOUPLING',
 CDS_LIB='dev_discrete',
 CDS_PART_NAME='CAP_A_0402V-1.0UF,6.3V,10%,X6SA',
 VOLTAGE='6.3V',
 PRIM_FILE='./archive_libs/discrete/cap_a/chips/chips.prt';

PART_NAME
 C2M20 'CAP_A_0402V-1.0UF,6.3V,10%,X6SA':
 ROOM='SB_DECOUPLING';

SECTION_NUMBER 1
 '@BASEBOARD_FAB2_LIB.BASEBOARD_FAB2(SCH_1):PAGE131_I39@DEV_DISCRETE.CAP_A(CHIPS)':
 C_PATH='@baseboard_fab2_lib.baseboard_fab2(sch_1):page131_i39@dev_discrete.cap_~
a(chips)',
 P_PATH='@baseboard_fab2_lib.baseboard_fab2(sch_1):page131_i39@dev_discrete.cap_~
a(chips)',
 PATH='I39',
 DRAWING='@BASEBOARD_FAB2_LIB.BASEBOARD_FAB2(SCH_1):PAGE131',
 TOLERANCE='10%',
 MATERIAL='X6S',
 BOM_COST='SB',
 PHYS_PAGE='131',
 XY='(-3550,4725)',
 ROT='0',
 VER='1',
 VALUE='1.0UF',
 PACK_TYPE='0402V',
 PART_NUMBER='D97712-004',
 LOCATION='C2M20',
 ROOM='SB_DECOUPLING',
 CDS_LIB='dev_discrete',
 CDS_PART_NAME='CAP_A_0402V-1.0UF,6.3V,10%,X6SA',
 VOLTAGE='6.3V',
 PRIM_FILE='./archive_libs/discrete/cap_a/chips/chips.prt';

PART_NAME
 C2M21 'CAP_A_0402V-1.0UF,6.3V,10%,X6SA':
 ROOM='SB_DECOUPLING';

SECTION_NUMBER 1
 '@BASEBOARD_FAB2_LIB.BASEBOARD_FAB2(SCH_1):PAGE131_I28@DEV_DISCRETE.CAP_A(CHIPS)':
 C_PATH='@baseboard_fab2_lib.baseboard_fab2(sch_1):page131_i28@dev_discrete.cap_~
a(chips)',
 P_PATH='@baseboard_fab2_lib.baseboard_fab2(sch_1):page131_i28@dev_discrete.cap_~
a(chips)',
 PATH='I28',
 DRAWING='@BASEBOARD_FAB2_LIB.BASEBOARD_FAB2(SCH_1):PAGE131',
 TOLERANCE='10%',
 MATERIAL='X6S',
 BOM_COST='SB',
 PHYS_PAGE='131',
 XY='(-2800,4725)',
 ROT='0',
 VER='1',
 VALUE='1.0UF',
 PACK_TYPE='0402V',
 PART_NUMBER='D97712-004',
 LOCATION='C2M21',
 ROOM='SB_DECOUPLING',
 CDS_LIB='dev_discrete',
 CDS_PART_NAME='CAP_A_0402V-1.0UF,6.3V,10%,X6SA',
 VOLTAGE='6.3V',
 PRIM_FILE='./archive_libs/discrete/cap_a/chips/chips.prt';

PART_NAME
 C2M22 'CAP_A_0402V-1.0UF,6.3V,10%,X6SA':
 ROOM='SB_DECOUPLING';

SECTION_NUMBER 1
 '@BASEBOARD_FAB2_LIB.BASEBOARD_FAB2(SCH_1):PAGE131_I27@DEV_DISCRETE.CAP_A(CHIPS)':
 C_PATH='@baseboard_fab2_lib.baseboard_fab2(sch_1):page131_i27@dev_discrete.cap_~
a(chips)',
 P_PATH='@baseboard_fab2_lib.baseboard_fab2(sch_1):page131_i27@dev_discrete.cap_~
a(chips)',
 PATH='I27',
 DRAWING='@BASEBOARD_FAB2_LIB.BASEBOARD_FAB2(SCH_1):PAGE131',
 TOLERANCE='10%',
 MATERIAL='X6S',
 BOM_COST='SB',
 PHYS_PAGE='131',
 XY='(-2375,4725)',
 ROT='0',
 VER='1',
 VALUE='1.0UF',
 PACK_TYPE='0402V',
 PART_NUMBER='D97712-004',
 LOCATION='C2M22',
 ROOM='SB_DECOUPLING',
 CDS_LIB='dev_discrete',
 CDS_PART_NAME='CAP_A_0402V-1.0UF,6.3V,10%,X6SA',
 VOLTAGE='6.3V',
 PRIM_FILE='./archive_libs/discrete/cap_a/chips/chips.prt';

PART_NAME
 C2M23 'CAP_A_0402V-0.1UF,16V,10%,X7R,A':
 GROUP='NI_I210&RJ45',
 ROOM='NIC_SPRV';

SECTION_NUMBER 1
 '@BASEBOARD_FAB2_LIB.BASEBOARD_FAB2(SCH_1):PAGE139_I89@DEV_DISCRETE.CAP_A(CHIPS)':
 C_PATH='@baseboard_fab2_lib.baseboard_fab2(sch_1):page139_i89@dev_discrete.cap_~
a(chips)',
 P_PATH='@baseboard_fab2_lib.baseboard_fab2(sch_1):page139_i89@dev_discrete.cap_~
a(chips)',
 PATH='I89',
 DRAWING='@BASEBOARD_FAB2_LIB.BASEBOARD_FAB2(SCH_1):PAGE139',
 TOLERANCE='10%',
 SEC_TYPE='0402V',
 MATERIAL='X7R',
 BOM_COST='NT_GBE_BASE',
 PHYS_PAGE='139',
 XY='(-5925,2125)',
 ROT='0',
 VER='2',
 VALUE='0.1UF',
 PACK_TYPE='0402V',
 PART_NUMBER='A36096-030',
 LOCATION='C2M23',
 ROOM='NIC_SPRV',
 GROUP='NI_I210&RJ45',
 SEC='1',
 CDS_LIB='dev_discrete',
 CDS_PART_NAME='CAP_A_0402V-0.1UF,16V,10%,X7R,A',
 VOLTAGE='16V',
 PRIM_FILE='./archive_libs/discrete/cap_a/chips/chips.prt';

PART_NAME
 C2M24 'CAP_A_0402V-0.1UF,16V,10%,X7R,A':
 GROUP='NI_I210&RJ45',
 ROOM='NIC_SPRV';

SECTION_NUMBER 1
 '@BASEBOARD_FAB2_LIB.BASEBOARD_FAB2(SCH_1):PAGE139_I90@DEV_DISCRETE.CAP_A(CHIPS)':
 C_PATH='@baseboard_fab2_lib.baseboard_fab2(sch_1):page139_i90@dev_discrete.cap_~
a(chips)',
 P_PATH='@baseboard_fab2_lib.baseboard_fab2(sch_1):page139_i90@dev_discrete.cap_~
a(chips)',
 PATH='I90',
 DRAWING='@BASEBOARD_FAB2_LIB.BASEBOARD_FAB2(SCH_1):PAGE139',
 TOLERANCE='10%',
 SEC_TYPE='0402V',
 MATERIAL='X7R',
 BOM_COST='NT_GBE_BASE',
 PHYS_PAGE='139',
 XY='(-6150,2075)',
 ROT='0',
 VER='2',
 VALUE='0.1UF',
 PACK_TYPE='0402V',
 PART_NUMBER='A36096-030',
 LOCATION='C2M24',
 ROOM='NIC_SPRV',
 GROUP='NI_I210&RJ45',
 SEC='1',
 CDS_LIB='dev_discrete',
 CDS_PART_NAME='CAP_A_0402V-0.1UF,16V,10%,X7R,A',
 VOLTAGE='16V',
 PRIM_FILE='./archive_libs/discrete/cap_a/chips/chips.prt';

PART_NAME
 C2M25 'CAP_A_0402V-1.0UF,6.3V,10%,X6SA':
 ROOM='SB_FILTER_KR_PLL';

SECTION_NUMBER 1
 '@BASEBOARD_FAB2_LIB.BASEBOARD_FAB2(SCH_1):PAGE127_I78@DEV_DISCRETE.CAP_A(CHIPS)':
 C_PATH='@baseboard_fab2_lib.baseboard_fab2(sch_1):page127_i78@dev_discrete.cap_~
a(chips)',
 P_PATH='@baseboard_fab2_lib.baseboard_fab2(sch_1):page127_i78@dev_discrete.cap_~
a(chips)',
 PATH='I78',
 DRAWING='@BASEBOARD_FAB2_LIB.BASEBOARD_FAB2(SCH_1):PAGE127',
 TOLERANCE='10%',
 SEC_TYPE='0402V',
 MATERIAL='X6S',
 BOM_COST='SB',
 PHYS_PAGE='127',
 XY='(-1450,-3300)',
 ROT='2',
 VER='1',
 VALUE='1.0UF',
 PACK_TYPE='0402V',
 PART_NUMBER='D97712-004',
 LOCATION='C2M25',
 ROOM='SB_FILTER_KR_PLL',
 SEC='1',
 CDS_LIB='dev_discrete',
 CDS_PART_NAME='CAP_A_0402V-1.0UF,6.3V,10%,X6SA',
 VOLTAGE='6.3V',
 PRIM_FILE='./archive_libs/discrete/cap_a/chips/chips.prt';

PART_NAME
 C2N2 'CAP_A_0402V-1.0UF,6.3V,10%,X6SA':
 ROOM='SB_DECOUPLING';

SECTION_NUMBER 1
 '@BASEBOARD_FAB2_LIB.BASEBOARD_FAB2(SCH_1):PAGE131_I41@DEV_DISCRETE.CAP_A(CHIPS)':
 C_PATH='@baseboard_fab2_lib.baseboard_fab2(sch_1):page131_i41@dev_discrete.cap_~
a(chips)',
 P_PATH='@baseboard_fab2_lib.baseboard_fab2(sch_1):page131_i41@dev_discrete.cap_~
a(chips)',
 PATH='I41',
 DRAWING='@BASEBOARD_FAB2_LIB.BASEBOARD_FAB2(SCH_1):PAGE131',
 TOLERANCE='10%',
 MATERIAL='X6S',
 BOM_COST='SB',
 PHYS_PAGE='131',
 XY='(-4350,4725)',
 ROT='0',
 VER='1',
 VALUE='1.0UF',
 PACK_TYPE='0402V',
 PART_NUMBER='D97712-004',
 LOCATION='C2N2',
 ROOM='SB_DECOUPLING',
 CDS_LIB='dev_discrete',
 CDS_PART_NAME='CAP_A_0402V-1.0UF,6.3V,10%,X6SA',
 VOLTAGE='6.3V',
 PRIM_FILE='./archive_libs/discrete/cap_a/chips/chips.prt';

PART_NAME
 C2N3 'CAP_A_0402V-1.0UF,6.3V,10%,X6SA':
 ROOM='SB_DECOUPLING';

SECTION_NUMBER 1
 '@BASEBOARD_FAB2_LIB.BASEBOARD_FAB2(SCH_1):PAGE132_I27@DEV_DISCRETE.CAP_A(CHIPS)':
 C_PATH='@baseboard_fab2_lib.baseboard_fab2(sch_1):page132_i27@dev_discrete.cap_~
a(chips)',
 P_PATH='@baseboard_fab2_lib.baseboard_fab2(sch_1):page132_i27@dev_discrete.cap_~
a(chips)',
 PATH='I27',
 DRAWING='@BASEBOARD_FAB2_LIB.BASEBOARD_FAB2(SCH_1):PAGE132',
 TOLERANCE='10%',
 MATERIAL='X6S',
 BOM_COST='SB',
 PHYS_PAGE='132',
 XY='(-725,4050)',
 ROT='0',
 VER='1',
 VALUE='1.0UF',
 PACK_TYPE='0402V',
 PART_NUMBER='D97712-004',
 LOCATION='C2N3',
 ROOM='SB_DECOUPLING',
 CDS_LIB='dev_discrete',
 CDS_PART_NAME='CAP_A_0402V-1.0UF,6.3V,10%,X6SA',
 VOLTAGE='6.3V',
 PRIM_FILE='./archive_libs/discrete/cap_a/chips/chips.prt';

PART_NAME
 C2N4 'CAP_A_0402V-1.0UF,6.3V,10%,X6SA':
 ROOM='SB_DECOUPLING';

SECTION_NUMBER 1
 '@BASEBOARD_FAB2_LIB.BASEBOARD_FAB2(SCH_1):PAGE132_I28@DEV_DISCRETE.CAP_A(CHIPS)':
 C_PATH='@baseboard_fab2_lib.baseboard_fab2(sch_1):page132_i28@dev_discrete.cap_~
a(chips)',
 P_PATH='@baseboard_fab2_lib.baseboard_fab2(sch_1):page132_i28@dev_discrete.cap_~
a(chips)',
 PATH='I28',
 DRAWING='@BASEBOARD_FAB2_LIB.BASEBOARD_FAB2(SCH_1):PAGE132',
 TOLERANCE='10%',
 MATERIAL='X6S',
 PHYS_PAGE='132',
 XY='(-300,3025)',
 ROT='0',
 VER='1',
 VALUE='1.0UF',
 PACK_TYPE='0402V',
 PART_NUMBER='D97712-004',
 LOCATION='C2N4',
 ROOM='SB_DECOUPLING',
 CDS_LIB='dev_discrete',
 CDS_PART_NAME='CAP_A_0402V-1.0UF,6.3V,10%,X6SA',
 VOLTAGE='6.3V',
 PRIM_FILE='./archive_libs/discrete/cap_a/chips/chips.prt';

PART_NAME
 C2N5 'CAP_A_0402V-1.0UF,6.3V,10%,X6SA':
 ROOM='SB_FILTER_KR_PLL';

SECTION_NUMBER 1
 '@BASEBOARD_FAB2_LIB.BASEBOARD_FAB2(SCH_1):PAGE127_I65@DEV_DISCRETE.CAP_A(CHIPS)':
 C_PATH='@baseboard_fab2_lib.baseboard_fab2(sch_1):page127_i65@dev_discrete.cap_~
a(chips)',
 P_PATH='@baseboard_fab2_lib.baseboard_fab2(sch_1):page127_i65@dev_discrete.cap_~
a(chips)',
 PATH='I65',
 DRAWING='@BASEBOARD_FAB2_LIB.BASEBOARD_FAB2(SCH_1):PAGE127',
 TOLERANCE='10%',
 SEC_TYPE='0402V',
 MATERIAL='X6S',
 BOM_COST='SB',
 PHYS_PAGE='127',
 XY='(-1000,-3300)',
 ROT='0',
 VER='1',
 VALUE='1.0UF',
 PACK_TYPE='0402V',
 PART_NUMBER='D97712-004',
 LOCATION='C2N5',
 ROOM='SB_FILTER_KR_PLL',
 SEC='1',
 CDS_LIB='dev_discrete',
 CDS_PART_NAME='CAP_A_0402V-1.0UF,6.3V,10%,X6SA',
 VOLTAGE='6.3V',
 PRIM_FILE='./archive_libs/discrete/cap_a/chips/chips.prt';

PART_NAME
 C2N6 'CAP_0603LF-10UF,4V,20%,X6S,E15A':
 ROOM='SB_FILTER_KR_PLL';

SECTION_NUMBER 1
 '@BASEBOARD_FAB2_LIB.BASEBOARD_FAB2(SCH_1):PAGE127_I64@MSTR_DISCRETE.CAP(CHIPS)':
 C_PATH='@baseboard_fab2_lib.baseboard_fab2(sch_1):page127_i64@mstr_discrete.cap~
(chips)',
 P_PATH='@baseboard_fab2_lib.baseboard_fab2(sch_1):page127_i64@mstr_discrete.cap~
(chips)',
 PATH='I64',
 DRAWING='@BASEBOARD_FAB2_LIB.BASEBOARD_FAB2(SCH_1):PAGE127',
 TOLERANCE='20%',
 SEC_TYPE='0603LF',
 MATERIAL='X6S',
 BOM_COST='SB',
 PHYS_PAGE='127',
 XY='(-500,-3300)',
 ROT='0',
 VER='1',
 VALUE='10UF',
 PACK_TYPE='0603LF',
 PART_NUMBER='E15431-001',
 LOCATION='C2N6',
 ROOM='SB_FILTER_KR_PLL',
 SEC='1',
 CDS_LIB='mstr_discrete',
 CDS_PART_NAME='CAP_0603LF-10UF,4V,20%,X6S,E15A',
 VOLTAGE='4V',
 PRIM_FILE='./archive_libs/mstr_discrete/cap/chips/chips.prt';

PART_NAME
 C2N7 'CAP_A_0402V-1.0UF,6.3V,10%,X6SA':
 ROOM='SB_DECOUPLING';

SECTION_NUMBER 1
 '@BASEBOARD_FAB2_LIB.BASEBOARD_FAB2(SCH_1):PAGE131_I43@DEV_DISCRETE.CAP_A(CHIPS)':
 C_PATH='@baseboard_fab2_lib.baseboard_fab2(sch_1):page131_i43@dev_discrete.cap_~
a(chips)',
 P_PATH='@baseboard_fab2_lib.baseboard_fab2(sch_1):page131_i43@dev_discrete.cap_~
a(chips)',
 PATH='I43',
 DRAWING='@BASEBOARD_FAB2_LIB.BASEBOARD_FAB2(SCH_1):PAGE131',
 TOLERANCE='10%',
 MATERIAL='X6S',
 BOM_COST='SB',
 PHYS_PAGE='131',
 XY='(-4000,3525)',
 ROT='0',
 VER='1',
 VALUE='1.0UF',
 PACK_TYPE='0402V',
 PART_NUMBER='D97712-004',
 LOCATION='C2N7',
 ROOM='SB_DECOUPLING',
 CDS_LIB='dev_discrete',
 CDS_PART_NAME='CAP_A_0402V-1.0UF,6.3V,10%,X6SA',
 VOLTAGE='6.3V',
 PRIM_FILE='./archive_libs/discrete/cap_a/chips/chips.prt';

PART_NAME
 C2N8 'CAP_A_0402V-1.0UF,6.3V,10%,X6SA':
 ROOM='SB_DECOUPLING';

SECTION_NUMBER 1
 '@BASEBOARD_FAB2_LIB.BASEBOARD_FAB2(SCH_1):PAGE131_I47@DEV_DISCRETE.CAP_A(CHIPS)':
 C_PATH='@baseboard_fab2_lib.baseboard_fab2(sch_1):page131_i47@dev_discrete.cap_~
a(chips)',
 P_PATH='@baseboard_fab2_lib.baseboard_fab2(sch_1):page131_i47@dev_discrete.cap_~
a(chips)',
 PATH='I47',
 DRAWING='@BASEBOARD_FAB2_LIB.BASEBOARD_FAB2(SCH_1):PAGE131',
 TOLERANCE='10%',
 MATERIAL='X6S',
 BOM_COST='SB',
 PHYS_PAGE='131',
 XY='(-4775,3525)',
 ROT='0',
 VER='1',
 VALUE='1.0UF',
 PACK_TYPE='0402V',
 PART_NUMBER='D97712-004',
 LOCATION='C2N8',
 ROOM='SB_DECOUPLING',
 CDS_LIB='dev_discrete',
 CDS_PART_NAME='CAP_A_0402V-1.0UF,6.3V,10%,X6SA',
 VOLTAGE='6.3V',
 PRIM_FILE='./archive_libs/discrete/cap_a/chips/chips.prt';

PART_NAME
 C2N9 'CAP_A_0402V-1.0UF,6.3V,10%,X6SA':
 ROOM='SB_DECOUPLING';

SECTION_NUMBER 1
 '@BASEBOARD_FAB2_LIB.BASEBOARD_FAB2(SCH_1):PAGE132_I26@DEV_DISCRETE.CAP_A(CHIPS)':
 C_PATH='@baseboard_fab2_lib.baseboard_fab2(sch_1):page132_i26@dev_discrete.cap_~
a(chips)',
 P_PATH='@baseboard_fab2_lib.baseboard_fab2(sch_1):page132_i26@dev_discrete.cap_~
a(chips)',
 PATH='I26',
 DRAWING='@BASEBOARD_FAB2_LIB.BASEBOARD_FAB2(SCH_1):PAGE132',
 TOLERANCE='10%',
 MATERIAL='X6S',
 PHYS_PAGE='132',
 XY='(-325,4050)',
 ROT='0',
 VER='1',
 VALUE='1.0UF',
 PACK_TYPE='0402V',
 PART_NUMBER='D97712-004',
 LOCATION='C2N9',
 ROOM='SB_DECOUPLING',
 CDS_LIB='dev_discrete',
 CDS_PART_NAME='CAP_A_0402V-1.0UF,6.3V,10%,X6SA',
 VOLTAGE='6.3V',
 PRIM_FILE='./archive_libs/discrete/cap_a/chips/chips.prt';

PART_NAME
 C2N10 'CAP_A_0603V-22.0UF,4V,20%,X6S,A':
 ROOM='SB_DECOUPLING';

SECTION_NUMBER 1
 '@BASEBOARD_FAB2_LIB.BASEBOARD_FAB2(SCH_1):PAGE131_I50@DEV_DISCRETE.CAP_A(CHIPS)':
 C_PATH='@baseboard_fab2_lib.baseboard_fab2(sch_1):page131_i50@dev_discrete.cap_~
a(chips)',
 P_PATH='@baseboard_fab2_lib.baseboard_fab2(sch_1):page131_i50@dev_discrete.cap_~
a(chips)',
 PATH='I50',
 DRAWING='@BASEBOARD_FAB2_LIB.BASEBOARD_FAB2(SCH_1):PAGE131',
 TOLERANCE='20%',
 MATERIAL='X6S',
 BOM_COST='SB',
 PHYS_PAGE='131',
 XY='(-4650,2100)',
 ROT='0',
 VER='1',
 VALUE='22.0UF',
 PACK_TYPE='0603V',
 PART_NUMBER='E15431-004',
 LOCATION='C2N10',
 ROOM='SB_DECOUPLING',
 CDS_LIB='dev_discrete',
 CDS_PART_NAME='CAP_A_0603V-22.0UF,4V,20%,X6S,A',
 VOLTAGE='4V',
 PRIM_FILE='./archive_libs/discrete/cap_a/chips/chips.prt';

PART_NAME
 C2N11 'CAP_A_0402V-1.0UF,6.3V,10%,X6SA':
 ROOM='SB_DECOUPLING';

SECTION_NUMBER 1
 '@BASEBOARD_FAB2_LIB.BASEBOARD_FAB2(SCH_1):PAGE132_I30@DEV_DISCRETE.CAP_A(CHIPS)':
 C_PATH='@baseboard_fab2_lib.baseboard_fab2(sch_1):page132_i30@dev_discrete.cap_~
a(chips)',
 P_PATH='@baseboard_fab2_lib.baseboard_fab2(sch_1):page132_i30@dev_discrete.cap_~
a(chips)',
 PATH='I30',
 DRAWING='@BASEBOARD_FAB2_LIB.BASEBOARD_FAB2(SCH_1):PAGE132',
 TOLERANCE='10%',
 MATERIAL='X6S',
 BOM_COST='SB',
 PHYS_PAGE='132',
 XY='(-1100,4050)',
 ROT='0',
 VER='1',
 VALUE='1.0UF',
 PACK_TYPE='0402V',
 PART_NUMBER='D97712-004',
 LOCATION='C2N11',
 ROOM='SB_DECOUPLING',
 CDS_LIB='dev_discrete',
 CDS_PART_NAME='CAP_A_0402V-1.0UF,6.3V,10%,X6SA',
 VOLTAGE='6.3V',
 PRIM_FILE='./archive_libs/discrete/cap_a/chips/chips.prt';

PART_NAME
 C2N12 'CAP_A_0402V-1.0UF,6.3V,10%,X6SA':
 ROOM='SB_DECOUPLING';

SECTION_NUMBER 1
 '@BASEBOARD_FAB2_LIB.BASEBOARD_FAB2(SCH_1):PAGE132_I29@DEV_DISCRETE.CAP_A(CHIPS)':
 C_PATH='@baseboard_fab2_lib.baseboard_fab2(sch_1):page132_i29@dev_discrete.cap_~
a(chips)',
 P_PATH='@baseboard_fab2_lib.baseboard_fab2(sch_1):page132_i29@dev_discrete.cap_~
a(chips)',
 PATH='I29',
 DRAWING='@BASEBOARD_FAB2_LIB.BASEBOARD_FAB2(SCH_1):PAGE132',
 TOLERANCE='10%',
 MATERIAL='X6S',
 BOM_COST='SB',
 PHYS_PAGE='132',
 XY='(-700,3025)',
 ROT='0',
 VER='1',
 VALUE='1.0UF',
 PACK_TYPE='0402V',
 PART_NUMBER='D97712-004',
 LOCATION='C2N12',
 ROOM='SB_DECOUPLING',
 CDS_LIB='dev_discrete',
 CDS_PART_NAME='CAP_A_0402V-1.0UF,6.3V,10%,X6SA',
 VOLTAGE='6.3V',
 PRIM_FILE='./archive_libs/discrete/cap_a/chips/chips.prt';

PART_NAME
 C2N13 'CAP_A_0402V-1.0UF,6.3V,10%,X6SA':
 ROOM='SB_DECOUPLING';

SECTION_NUMBER 1
 '@BASEBOARD_FAB2_LIB.BASEBOARD_FAB2(SCH_1):PAGE131_I40@DEV_DISCRETE.CAP_A(CHIPS)':
 C_PATH='@baseboard_fab2_lib.baseboard_fab2(sch_1):page131_i40@dev_discrete.cap_~
a(chips)',
 P_PATH='@baseboard_fab2_lib.baseboard_fab2(sch_1):page131_i40@dev_discrete.cap_~
a(chips)',
 PATH='I40',
 DRAWING='@BASEBOARD_FAB2_LIB.BASEBOARD_FAB2(SCH_1):PAGE131',
 TOLERANCE='10%',
 MATERIAL='X6S',
 BOM_COST='SB',
 PHYS_PAGE='131',
 XY='(-3950,4725)',
 ROT='0',
 VER='1',
 VALUE='1.0UF',
 PACK_TYPE='0402V',
 PART_NUMBER='D97712-004',
 LOCATION='C2N13',
 ROOM='SB_DECOUPLING',
 CDS_LIB='dev_discrete',
 CDS_PART_NAME='CAP_A_0402V-1.0UF,6.3V,10%,X6SA',
 VOLTAGE='6.3V',
 PRIM_FILE='./archive_libs/discrete/cap_a/chips/chips.prt';

PART_NAME
 C2N14 'CAP_0603-10UF,6.3V,20%,X6S,E15A':
 ROOM='SB_DECOUPLING';

SECTION_NUMBER 1
 '@BASEBOARD_FAB2_LIB.BASEBOARD_FAB2(SCH_1):PAGE130_I25@MSTR_DISCRETE.CAP(CHIPS)':
 C_PATH='@baseboard_fab2_lib.baseboard_fab2(sch_1):page130_i25@mstr_discrete.cap~
(chips)',
 P_PATH='@baseboard_fab2_lib.baseboard_fab2(sch_1):page130_i25@mstr_discrete.cap~
(chips)',
 PATH='I25',
 DRAWING='@BASEBOARD_FAB2_LIB.BASEBOARD_FAB2(SCH_1):PAGE130',
 TOLERANCE='20%',
 MATERIAL='X6S',
 BOM_COST='SB',
 PHYS_PAGE='130',
 XY='(-4575,4925)',
 ROT='0',
 VER='1',
 VALUE='10UF',
 PACK_TYPE='0603',
 PART_NUMBER='E15431-002',
 LOCATION='C2N14',
 ROOM='SB_DECOUPLING',
 CDS_LIB='mstr_discrete',
 CDS_PART_NAME='CAP_0603-10UF,6.3V,20%,X6S,E15A',
 VOLTAGE='6.3V',
 PRIM_FILE='./archive_libs/mstr_discrete/cap/chips/chips.prt';

PART_NAME
 C2N15 'CAP_A_0402V-1.0UF,6.3V,10%,X6SA':
 ROOM='SB_DECOUPLING';

SECTION_NUMBER 1
 '@BASEBOARD_FAB2_LIB.BASEBOARD_FAB2(SCH_1):PAGE130_I47@DEV_DISCRETE.CAP_A(CHIPS)':
 C_PATH='@baseboard_fab2_lib.baseboard_fab2(sch_1):page130_i47@dev_discrete.cap_~
a(chips)',
 P_PATH='@baseboard_fab2_lib.baseboard_fab2(sch_1):page130_i47@dev_discrete.cap_~
a(chips)',
 PATH='I47',
 DRAWING='@BASEBOARD_FAB2_LIB.BASEBOARD_FAB2(SCH_1):PAGE130',
 TOLERANCE='10%',
 MATERIAL='X6S',
 BOM_COST='SB',
 PHYS_PAGE='130',
 XY='(-3600,1475)',
 ROT='0',
 VER='1',
 VALUE='1.0UF',
 PACK_TYPE='0402V',
 PART_NUMBER='D97712-004',
 LOCATION='C2N15',
 ROOM='SB_DECOUPLING',
 CDS_LIB='dev_discrete',
 CDS_PART_NAME='CAP_A_0402V-1.0UF,6.3V,10%,X6SA',
 VOLTAGE='6.3V',
 PRIM_FILE='./archive_libs/discrete/cap_a/chips/chips.prt';

PART_NAME
 C2N16 'CAP_A_0402V-1.0UF,6.3V,10%,X6SA':
 ROOM='SB_DECOUPLING';

SECTION_NUMBER 1
 '@BASEBOARD_FAB2_LIB.BASEBOARD_FAB2(SCH_1):PAGE130_I52@DEV_DISCRETE.CAP_A(CHIPS)':
 C_PATH='@baseboard_fab2_lib.baseboard_fab2(sch_1):page130_i52@dev_discrete.cap_~
a(chips)',
 P_PATH='@baseboard_fab2_lib.baseboard_fab2(sch_1):page130_i52@dev_discrete.cap_~
a(chips)',
 PATH='I52',
 DRAWING='@BASEBOARD_FAB2_LIB.BASEBOARD_FAB2(SCH_1):PAGE130',
 TOLERANCE='10%',
 MATERIAL='X6S',
 BOM_COST='SB',
 PHYS_PAGE='130',
 XY='(-4775,1475)',
 ROT='0',
 VER='1',
 VALUE='1.0UF',
 PACK_TYPE='0402V',
 PART_NUMBER='D97712-004',
 LOCATION='C2N16',
 ROOM='SB_DECOUPLING',
 CDS_LIB='dev_discrete',
 CDS_PART_NAME='CAP_A_0402V-1.0UF,6.3V,10%,X6SA',
 VOLTAGE='6.3V',
 PRIM_FILE='./archive_libs/discrete/cap_a/chips/chips.prt';

PART_NAME
 C2N17 'CAP_0603-10UF,6.3V,20%,X6S,E15A':
 ROOM='SB_DECOUPLING';

SECTION_NUMBER 1
 '@BASEBOARD_FAB2_LIB.BASEBOARD_FAB2(SCH_1):PAGE130_I28@MSTR_DISCRETE.CAP(CHIPS)':
 C_PATH='@baseboard_fab2_lib.baseboard_fab2(sch_1):page130_i28@mstr_discrete.cap~
(chips)',
 P_PATH='@baseboard_fab2_lib.baseboard_fab2(sch_1):page130_i28@mstr_discrete.cap~
(chips)',
 PATH='I28',
 DRAWING='@BASEBOARD_FAB2_LIB.BASEBOARD_FAB2(SCH_1):PAGE130',
 TOLERANCE='20%',
 MATERIAL='X6S',
 BOM_COST='SB',
 PHYS_PAGE='130',
 XY='(-1475,3925)',
 ROT='0',
 VER='1',
 VALUE='10UF',
 PACK_TYPE='0603',
 PART_NUMBER='E15431-002',
 LOCATION='C2N17',
 ROOM='SB_DECOUPLING',
 CDS_LIB='mstr_discrete',
 CDS_PART_NAME='CAP_0603-10UF,6.3V,20%,X6S,E15A',
 VOLTAGE='6.3V',
 PRIM_FILE='./archive_libs/mstr_discrete/cap/chips/chips.prt';

PART_NAME
 C2N18 'CAP_A_0402V-1.0UF,6.3V,10%,X6SA':
 ROOM='SB_DECOUPLING';

SECTION_NUMBER 1
 '@BASEBOARD_FAB2_LIB.BASEBOARD_FAB2(SCH_1):PAGE130_I29@DEV_DISCRETE.CAP_A(CHIPS)':
 C_PATH='@baseboard_fab2_lib.baseboard_fab2(sch_1):page130_i29@dev_discrete.cap_~
a(chips)',
 P_PATH='@baseboard_fab2_lib.baseboard_fab2(sch_1):page130_i29@dev_discrete.cap_~
a(chips)',
 PATH='I29',
 DRAWING='@BASEBOARD_FAB2_LIB.BASEBOARD_FAB2(SCH_1):PAGE130',
 TOLERANCE='10%',
 MATERIAL='X6S',
 BOM_COST='SB',
 PHYS_PAGE='130',
 XY='(-3450,3925)',
 ROT='0',
 VER='1',
 VALUE='1.0UF',
 PACK_TYPE='0402V',
 PART_NUMBER='D97712-004',
 LOCATION='C2N18',
 ROOM='SB_DECOUPLING',
 CDS_LIB='dev_discrete',
 CDS_PART_NAME='CAP_A_0402V-1.0UF,6.3V,10%,X6SA',
 VOLTAGE='6.3V',
 PRIM_FILE='./archive_libs/discrete/cap_a/chips/chips.prt';

PART_NAME
 C2N19 'CAP_A_0402V-1.0UF,6.3V,10%,X6SA':
 ROOM='SB_DECOUPLING';

SECTION_NUMBER 1
 '@BASEBOARD_FAB2_LIB.BASEBOARD_FAB2(SCH_1):PAGE130_I7@DEV_DISCRETE.CAP_A(CHIPS)':
 C_PATH='@baseboard_fab2_lib.baseboard_fab2(sch_1):page130_i7@dev_discrete.cap_a~
(chips)',
 P_PATH='@baseboard_fab2_lib.baseboard_fab2(sch_1):page130_i7@dev_discrete.cap_a~
(chips)',
 PATH='I7',
 DRAWING='@BASEBOARD_FAB2_LIB.BASEBOARD_FAB2(SCH_1):PAGE130',
 TOLERANCE='10%',
 MATERIAL='X6S',
 BOM_COST='SB',
 PHYS_PAGE='130',
 XY='(1175,3900)',
 ROT='0',
 VER='1',
 VALUE='1.0UF',
 PACK_TYPE='0402V',
 PART_NUMBER='D97712-004',
 LOCATION='C2N19',
 ROOM='SB_DECOUPLING',
 CDS_LIB='dev_discrete',
 CDS_PART_NAME='CAP_A_0402V-1.0UF,6.3V,10%,X6SA',
 VOLTAGE='6.3V',
 PRIM_FILE='./archive_libs/discrete/cap_a/chips/chips.prt';

PART_NAME
 C2N20 'CAP_A_0402V-1.0UF,6.3V,10%,X6SA':
 ROOM='SB_DECOUPLING';

SECTION_NUMBER 1
 '@BASEBOARD_FAB2_LIB.BASEBOARD_FAB2(SCH_1):PAGE130_I12@DEV_DISCRETE.CAP_A(CHIPS)':
 C_PATH='@baseboard_fab2_lib.baseboard_fab2(sch_1):page130_i12@dev_discrete.cap_~
a(chips)',
 P_PATH='@baseboard_fab2_lib.baseboard_fab2(sch_1):page130_i12@dev_discrete.cap_~
a(chips)',
 PATH='I12',
 DRAWING='@BASEBOARD_FAB2_LIB.BASEBOARD_FAB2(SCH_1):PAGE130',
 TOLERANCE='10%',
 MATERIAL='X6S',
 BOM_COST='SB',
 PHYS_PAGE='130',
 XY='(1925,1600)',
 ROT='0',
 VER='1',
 VALUE='1.0UF',
 PACK_TYPE='0402V',
 PART_NUMBER='D97712-004',
 LOCATION='C2N20',
 ROOM='SB_DECOUPLING',
 CDS_LIB='dev_discrete',
 CDS_PART_NAME='CAP_A_0402V-1.0UF,6.3V,10%,X6SA',
 VOLTAGE='6.3V',
 PRIM_FILE='./archive_libs/discrete/cap_a/chips/chips.prt';

PART_NAME
 C2N21 'CAP_0603-10UF,6.3V,20%,X6S,E15A':
 ROOM='SB_DECOUPLING';

SECTION_NUMBER 1
 '@BASEBOARD_FAB2_LIB.BASEBOARD_FAB2(SCH_1):PAGE130_I15@MSTR_DISCRETE.CAP(CHIPS)':
 C_PATH='@baseboard_fab2_lib.baseboard_fab2(sch_1):page130_i15@mstr_discrete.cap~
(chips)',
 P_PATH='@baseboard_fab2_lib.baseboard_fab2(sch_1):page130_i15@mstr_discrete.cap~
(chips)',
 PATH='I15',
 DRAWING='@BASEBOARD_FAB2_LIB.BASEBOARD_FAB2(SCH_1):PAGE130',
 TOLERANCE='20%',
 MATERIAL='X6S',
 BOM_COST='SB',
 PHYS_PAGE='130',
 XY='(425,2650)',
 ROT='0',
 VER='1',
 VALUE='10UF',
 PACK_TYPE='0603',
 PART_NUMBER='E15431-002',
 LOCATION='C2N21',
 ROOM='SB_DECOUPLING',
 CDS_LIB='mstr_discrete',
 CDS_PART_NAME='CAP_0603-10UF,6.3V,20%,X6S,E15A',
 VOLTAGE='6.3V',
 PRIM_FILE='./archive_libs/mstr_discrete/cap/chips/chips.prt';

PART_NAME
 C2N22 'CAP_0603-10UF,6.3V,20%,X6S,E15A':
 ROOM='SB_DECOUPLING';

SECTION_NUMBER 1
 '@BASEBOARD_FAB2_LIB.BASEBOARD_FAB2(SCH_1):PAGE130_I9@MSTR_DISCRETE.CAP(CHIPS)':
 C_PATH='@baseboard_fab2_lib.baseboard_fab2(sch_1):page130_i9@mstr_discrete.cap(~
chips)',
 P_PATH='@baseboard_fab2_lib.baseboard_fab2(sch_1):page130_i9@mstr_discrete.cap(~
chips)',
 PATH='I9',
 DRAWING='@BASEBOARD_FAB2_LIB.BASEBOARD_FAB2(SCH_1):PAGE130',
 TOLERANCE='20%',
 MATERIAL='X6S',
 BOM_COST='SB',
 PHYS_PAGE='130',
 XY='(875,2650)',
 ROT='0',
 VER='1',
 VALUE='10UF',
 PACK_TYPE='0603',
 PART_NUMBER='E15431-002',
 LOCATION='C2N22',
 ROOM='SB_DECOUPLING',
 CDS_LIB='mstr_discrete',
 CDS_PART_NAME='CAP_0603-10UF,6.3V,20%,X6S,E15A',
 VOLTAGE='6.3V',
 PRIM_FILE='./archive_libs/mstr_discrete/cap/chips/chips.prt';

PART_NAME
 C2N23 'CAP_0603-10UF,6.3V,20%,X6S,E15A':
 ROOM='SB_DECOUPLING';

SECTION_NUMBER 1
 '@BASEBOARD_FAB2_LIB.BASEBOARD_FAB2(SCH_1):PAGE130_I24@MSTR_DISCRETE.CAP(CHIPS)':
 C_PATH='@baseboard_fab2_lib.baseboard_fab2(sch_1):page130_i24@mstr_discrete.cap~
(chips)',
 P_PATH='@baseboard_fab2_lib.baseboard_fab2(sch_1):page130_i24@mstr_discrete.cap~
(chips)',
 PATH='I24',
 DRAWING='@BASEBOARD_FAB2_LIB.BASEBOARD_FAB2(SCH_1):PAGE130',
 TOLERANCE='20%',
 MATERIAL='X6S',
 BOM_COST='SB',
 PHYS_PAGE='130',
 XY='(-4175,4925)',
 ROT='0',
 VER='1',
 VALUE='10UF',
 PACK_TYPE='0603',
 PART_NUMBER='E15431-002',
 LOCATION='C2N23',
 ROOM='SB_DECOUPLING',
 CDS_LIB='mstr_discrete',
 CDS_PART_NAME='CAP_0603-10UF,6.3V,20%,X6S,E15A',
 VOLTAGE='6.3V',
 PRIM_FILE='./archive_libs/mstr_discrete/cap/chips/chips.prt';

PART_NAME
 C2N24 'CAP_0603-10UF,6.3V,20%,X6S,E15A':
 ROOM='SB_DECOUPLING';

SECTION_NUMBER 1
 '@BASEBOARD_FAB2_LIB.BASEBOARD_FAB2(SCH_1):PAGE130_I8@MSTR_DISCRETE.CAP(CHIPS)':
 C_PATH='@baseboard_fab2_lib.baseboard_fab2(sch_1):page130_i8@mstr_discrete.cap(~
chips)',
 P_PATH='@baseboard_fab2_lib.baseboard_fab2(sch_1):page130_i8@mstr_discrete.cap(~
chips)',
 PATH='I8',
 DRAWING='@BASEBOARD_FAB2_LIB.BASEBOARD_FAB2(SCH_1):PAGE130',
 TOLERANCE='20%',
 MATERIAL='X6S',
 BOM_COST='SB',
 PHYS_PAGE='130',
 XY='(1300,2650)',
 ROT='0',
 VER='1',
 VALUE='10UF',
 PACK_TYPE='0603',
 PART_NUMBER='E15431-002',
 LOCATION='C2N24',
 ROOM='SB_DECOUPLING',
 CDS_LIB='mstr_discrete',
 CDS_PART_NAME='CAP_0603-10UF,6.3V,20%,X6S,E15A',
 VOLTAGE='6.3V',
 PRIM_FILE='./archive_libs/mstr_discrete/cap/chips/chips.prt';

PART_NAME
 C2N25 'CAP_A_0402V-1.0UF,6.3V,10%,X6SA':
 ROOM='SB_DECOUPLING';

SECTION_NUMBER 1
 '@BASEBOARD_FAB2_LIB.BASEBOARD_FAB2(SCH_1):PAGE130_I34@DEV_DISCRETE.CAP_A(CHIPS)':
 C_PATH='@baseboard_fab2_lib.baseboard_fab2(sch_1):page130_i34@dev_discrete.cap_~
a(chips)',
 P_PATH='@baseboard_fab2_lib.baseboard_fab2(sch_1):page130_i34@dev_discrete.cap_~
a(chips)',
 PATH='I34',
 DRAWING='@BASEBOARD_FAB2_LIB.BASEBOARD_FAB2(SCH_1):PAGE130',
 TOLERANCE='10%',
 MATERIAL='X6S',
 BOM_COST='SB',
 PHYS_PAGE='130',
 XY='(-3825,3925)',
 ROT='0',
 VER='1',
 VALUE='1.0UF',
 PACK_TYPE='0402V',
 PART_NUMBER='D97712-004',
 LOCATION='C2N25',
 ROOM='SB_DECOUPLING',
 CDS_LIB='dev_discrete',
 CDS_PART_NAME='CAP_A_0402V-1.0UF,6.3V,10%,X6SA',
 VOLTAGE='6.3V',
 PRIM_FILE='./archive_libs/discrete/cap_a/chips/chips.prt';

PART_NAME
 C2N26 'CAP_A_0402V-1.0UF,6.3V,10%,X6SA':
 ROOM='SB_DECOUPLING';

SECTION_NUMBER 1
 '@BASEBOARD_FAB2_LIB.BASEBOARD_FAB2(SCH_1):PAGE130_I4@DEV_DISCRETE.CAP_A(CHIPS)':
 C_PATH='@baseboard_fab2_lib.baseboard_fab2(sch_1):page130_i4@dev_discrete.cap_a~
(chips)',
 P_PATH='@baseboard_fab2_lib.baseboard_fab2(sch_1):page130_i4@dev_discrete.cap_a~
(chips)',
 PATH='I4',
 DRAWING='@BASEBOARD_FAB2_LIB.BASEBOARD_FAB2(SCH_1):PAGE130',
 TOLERANCE='10%',
 MATERIAL='X6S',
 BOM_COST='SB',
 PHYS_PAGE='130',
 XY='(1725,2650)',
 ROT='0',
 VER='1',
 VALUE='1.0UF',
 PACK_TYPE='0402V',
 PART_NUMBER='D97712-004',
 LOCATION='C2N26',
 ROOM='SB_DECOUPLING',
 CDS_LIB='dev_discrete',
 CDS_PART_NAME='CAP_A_0402V-1.0UF,6.3V,10%,X6SA',
 VOLTAGE='6.3V',
 PRIM_FILE='./archive_libs/discrete/cap_a/chips/chips.prt';

PART_NAME
 C2P1 'CAP_A_0402V-0.1UF,16V,10%,X7R,A':
 ROOM='FAST_PROCHOT';

SECTION_NUMBER 1
 '@BASEBOARD_FAB2_LIB.BASEBOARD_FAB2(SCH_1):PAGE170_I8@DEV_DISCRETE.CAP_A(CHIPS)':
 C_PATH='@baseboard_fab2_lib.baseboard_fab2(sch_1):page170_i8@dev_discrete.cap_a~
(chips)',
 P_PATH='@baseboard_fab2_lib.baseboard_fab2(sch_1):page170_i8@dev_discrete.cap_a~
(chips)',
 PATH='I8',
 DRAWING='@BASEBOARD_FAB2_LIB.BASEBOARD_FAB2(SCH_1):PAGE170',
 TOLERANCE='10%',
 SEC_TYPE='0402V',
 MATERIAL='X7R',
 BOM_COST='FAST_PROCHOT',
 PHYS_PAGE='170',
 XY='(-5100,3350)',
 ROT='0',
 VER='1',
 VALUE='0.1UF',
 PACK_TYPE='0402V',
 PART_NUMBER='A36096-030',
 LOCATION='C2P1',
 ROOM='FAST_PROCHOT',
 SEC='1',
 CDS_LIB='dev_discrete',
 CDS_PART_NAME='CAP_A_0402V-0.1UF,16V,10%,X7R,A',
 VOLTAGE='16V',
 PRIM_FILE='./archive_libs/discrete/cap_a/chips/chips.prt';

PART_NAME
 C2P2 'CAP_A_0402V-0.1UF,16V,10%,X7R,A':
 ROOM='CPLD',
 SIGNAL_MODEL='DEFAULT_CAPACITOR_100000pF_2_1';

SECTION_NUMBER 1
 '@BASEBOARD_FAB2_LIB.BASEBOARD_FAB2(SCH_1):PAGE192_I9@DEV_DISCRETE.CAP_A(CHIPS)':
 C_PATH='@baseboard_fab2_lib.baseboard_fab2(sch_1):page192_i9@dev_discrete.cap_a~
(chips)',
 P_PATH='@baseboard_fab2_lib.baseboard_fab2(sch_1):page192_i9@dev_discrete.cap_a~
(chips)',
 PATH='I9',
 DRAWING='@BASEBOARD_FAB2_LIB.BASEBOARD_FAB2(SCH_1):PAGE192',
 TOLERANCE='10%',
 MATERIAL='X7R',
 BOM_COST='CPLD',
 PHYS_PAGE='192',
 XY='(-3600,1975)',
 ROT='0',
 VER='1',
 VALUE='0.1UF',
 PACK_TYPE='0402V',
 PART_NUMBER='A36096-030',
 LOCATION='C2P2',
 SIGNAL_MODEL='DEFAULT_CAPACITOR_100000pF_2_1',
 ROOM='CPLD',
 CDS_LIB='dev_discrete',
 CDS_PART_NAME='CAP_A_0402V-0.1UF,16V,10%,X7R,A',
 VOLTAGE='16V',
 PRIM_FILE='./archive_libs/discrete/cap_a/chips/chips.prt';

PART_NAME
 C2P3 'CAP_A_0402V-0.1UF,16V,10%,X7R,A':
 ROOM='CPLD',
 SIGNAL_MODEL='DEFAULT_CAPACITOR_100000pF_2_1';

SECTION_NUMBER 1
 '@BASEBOARD_FAB2_LIB.BASEBOARD_FAB2(SCH_1):PAGE192_I22@DEV_DISCRETE.CAP_A(CHIPS)':
 C_PATH='@baseboard_fab2_lib.baseboard_fab2(sch_1):page192_i22@dev_discrete.cap_~
a(chips)',
 P_PATH='@baseboard_fab2_lib.baseboard_fab2(sch_1):page192_i22@dev_discrete.cap_~
a(chips)',
 PATH='I22',
 DRAWING='@BASEBOARD_FAB2_LIB.BASEBOARD_FAB2(SCH_1):PAGE192',
 TOLERANCE='10%',
 MATERIAL='X7R',
 BOM_COST='CPLD',
 PHYS_PAGE='192',
 XY='(-6250,1300)',
 ROT='0',
 VER='1',
 VALUE='0.1UF',
 PACK_TYPE='0402V',
 PART_NUMBER='A36096-030',
 LOCATION='C2P3',
 SIGNAL_MODEL='DEFAULT_CAPACITOR_100000pF_2_1',
 ROOM='CPLD',
 CDS_LIB='dev_discrete',
 CDS_PART_NAME='CAP_A_0402V-0.1UF,16V,10%,X7R,A',
 VOLTAGE='16V',
 PRIM_FILE='./archive_libs/discrete/cap_a/chips/chips.prt';

PART_NAME
 C2P4 'CAP_A_0402V-0.1UF,16V,10%,X7R,A':
 ROOM='CPLD',
 SIGNAL_MODEL='DEFAULT_CAPACITOR_100000pF_2_1';

SECTION_NUMBER 1
 '@BASEBOARD_FAB2_LIB.BASEBOARD_FAB2(SCH_1):PAGE192_I16@DEV_DISCRETE.CAP_A(CHIPS)':
 C_PATH='@baseboard_fab2_lib.baseboard_fab2(sch_1):page192_i16@dev_discrete.cap_~
a(chips)',
 P_PATH='@baseboard_fab2_lib.baseboard_fab2(sch_1):page192_i16@dev_discrete.cap_~
a(chips)',
 PATH='I16',
 DRAWING='@BASEBOARD_FAB2_LIB.BASEBOARD_FAB2(SCH_1):PAGE192',
 TOLERANCE='10%',
 MATERIAL='X7R',
 BOM_COST='CPLD',
 PHYS_PAGE='192',
 XY='(-5025,1975)',
 ROT='0',
 VER='1',
 VALUE='0.1UF',
 PACK_TYPE='0402V',
 PART_NUMBER='A36096-030',
 LOCATION='C2P4',
 SIGNAL_MODEL='DEFAULT_CAPACITOR_100000pF_2_1',
 ROOM='CPLD',
 CDS_LIB='dev_discrete',
 CDS_PART_NAME='CAP_A_0402V-0.1UF,16V,10%,X7R,A',
 VOLTAGE='16V',
 PRIM_FILE='./archive_libs/discrete/cap_a/chips/chips.prt';

PART_NAME
 C2P5 'CAP_A_0402V-0.1UF,16V,10%,X7R,A':
 ROOM='CPLD',
 SIGNAL_MODEL='DEFAULT_CAPACITOR_100000pF_2_1';

SECTION_NUMBER 1
 '@BASEBOARD_FAB2_LIB.BASEBOARD_FAB2(SCH_1):PAGE192_I3@DEV_DISCRETE.CAP_A(CHIPS)':
 C_PATH='@baseboard_fab2_lib.baseboard_fab2(sch_1):page192_i3@dev_discrete.cap_a~
(chips)',
 P_PATH='@baseboard_fab2_lib.baseboard_fab2(sch_1):page192_i3@dev_discrete.cap_a~
(chips)',
 PATH='I3',
 DRAWING='@BASEBOARD_FAB2_LIB.BASEBOARD_FAB2(SCH_1):PAGE192',
 TOLERANCE='10%',
 MATERIAL='X7R',
 BOM_COST='CPLD',
 PHYS_PAGE='192',
 XY='(-1700,1975)',
 ROT='0',
 VER='1',
 VALUE='0.1UF',
 PACK_TYPE='0402V',
 PART_NUMBER='A36096-030',
 LOCATION='C2P5',
 SIGNAL_MODEL='DEFAULT_CAPACITOR_100000pF_2_1',
 ROOM='CPLD',
 CDS_LIB='dev_discrete',
 CDS_PART_NAME='CAP_A_0402V-0.1UF,16V,10%,X7R,A',
 VOLTAGE='16V',
 PRIM_FILE='./archive_libs/discrete/cap_a/chips/chips.prt';

PART_NAME
 C2P6 'CAP_A_0402V-0.1UF,16V,10%,X7R,A':
 ROOM='CPLD',
 SIGNAL_MODEL='DEFAULT_CAPACITOR_100000pF_2_1';

SECTION_NUMBER 1
 '@BASEBOARD_FAB2_LIB.BASEBOARD_FAB2(SCH_1):PAGE192_I18@DEV_DISCRETE.CAP_A(CHIPS)':
 C_PATH='@baseboard_fab2_lib.baseboard_fab2(sch_1):page192_i18@dev_discrete.cap_~
a(chips)',
 P_PATH='@baseboard_fab2_lib.baseboard_fab2(sch_1):page192_i18@dev_discrete.cap_~
a(chips)',
 PATH='I18',
 DRAWING='@BASEBOARD_FAB2_LIB.BASEBOARD_FAB2(SCH_1):PAGE192',
 TOLERANCE='10%',
 MATERIAL='X7R',
 BOM_COST='CPLD',
 PHYS_PAGE='192',
 XY='(-5225,1300)',
 ROT='0',
 VER='1',
 VALUE='0.1UF',
 PACK_TYPE='0402V',
 PART_NUMBER='A36096-030',
 LOCATION='C2P6',
 SIGNAL_MODEL='DEFAULT_CAPACITOR_100000pF_2_1',
 ROOM='CPLD',
 CDS_LIB='dev_discrete',
 CDS_PART_NAME='CAP_A_0402V-0.1UF,16V,10%,X7R,A',
 VOLTAGE='16V',
 PRIM_FILE='./archive_libs/discrete/cap_a/chips/chips.prt';

PART_NAME
 C2P7 'CAP_A_0402V-0.1UF,16V,10%,X7R,A':
 ROOM='CPLD',
 SIGNAL_MODEL='DEFAULT_CAPACITOR_100000pF_2_1';

SECTION_NUMBER 1
 '@BASEBOARD_FAB2_LIB.BASEBOARD_FAB2(SCH_1):PAGE192_I20@DEV_DISCRETE.CAP_A(CHIPS)':
 C_PATH='@baseboard_fab2_lib.baseboard_fab2(sch_1):page192_i20@dev_discrete.cap_~
a(chips)',
 P_PATH='@baseboard_fab2_lib.baseboard_fab2(sch_1):page192_i20@dev_discrete.cap_~
a(chips)',
 PATH='I20',
 DRAWING='@BASEBOARD_FAB2_LIB.BASEBOARD_FAB2(SCH_1):PAGE192',
 TOLERANCE='10%',
 MATERIAL='X7R',
 BOM_COST='CPLD',
 PHYS_PAGE='192',
 XY='(-5975,1975)',
 ROT='0',
 VER='1',
 VALUE='0.1UF',
 PACK_TYPE='0402V',
 PART_NUMBER='A36096-030',
 LOCATION='C2P7',
 SIGNAL_MODEL='DEFAULT_CAPACITOR_100000pF_2_1',
 ROOM='CPLD',
 CDS_LIB='dev_discrete',
 CDS_PART_NAME='CAP_A_0402V-0.1UF,16V,10%,X7R,A',
 VOLTAGE='16V',
 PRIM_FILE='./archive_libs/discrete/cap_a/chips/chips.prt';

PART_NAME
 C2P8 'CAP_A_0402V-0.01UF,25V,10%,X7RA':
 ROOM='CPLD',
 SIGNAL_MODEL='DEFAULT_CAPACITOR_10000pF_2_1';

SECTION_NUMBER 1
 '@BASEBOARD_FAB2_LIB.BASEBOARD_FAB2(SCH_1):PAGE192_I1@DEV_DISCRETE.CAP_A(CHIPS)':
 C_PATH='@baseboard_fab2_lib.baseboard_fab2(sch_1):page192_i1@dev_discrete.cap_a~
(chips)',
 P_PATH='@baseboard_fab2_lib.baseboard_fab2(sch_1):page192_i1@dev_discrete.cap_a~
(chips)',
 PATH='I1',
 DRAWING='@BASEBOARD_FAB2_LIB.BASEBOARD_FAB2(SCH_1):PAGE192',
 TOLERANCE='10%',
 MATERIAL='X7R',
 BOM_COST='CPLD',
 PHYS_PAGE='192',
 XY='(-1225,1975)',
 ROT='0',
 VER='1',
 VALUE='0.01UF',
 PACK_TYPE='0402V',
 PART_NUMBER='A36096-045',
 LOCATION='C2P8',
 SIGNAL_MODEL='DEFAULT_CAPACITOR_10000pF_2_1',
 ROOM='CPLD',
 CDS_LIB='dev_discrete',
 CDS_PART_NAME='CAP_A_0402V-0.01UF,25V,10%,X7RA',
 VOLTAGE='25V',
 PRIM_FILE='./archive_libs/discrete/cap_a/chips/chips.prt';

PART_NAME
 C2P9 'CAP_A_0402V-0.1UF,16V,10%,X7R,A':
 ROOM='M_2';

SECTION_NUMBER 1
 '@BASEBOARD_FAB2_LIB.BASEBOARD_FAB2(SCH_1):PAGE185_I117@DEV_DISCRETE.CAP_A(CHIPS)':
 C_PATH='@baseboard_fab2_lib.baseboard_fab2(sch_1):page185_i117@dev_discrete.cap~
_a(chips)',
 P_PATH='@baseboard_fab2_lib.baseboard_fab2(sch_1):page185_i117@dev_discrete.cap~
_a(chips)',
 PATH='I117',
 DRAWING='@BASEBOARD_FAB2_LIB.BASEBOARD_FAB2(SCH_1):PAGE185',
 TOLERANCE='10%',
 SEC_TYPE='0402V',
 MATERIAL='X7R',
 BOM_COST='SD_FLASH',
 PHYS_PAGE='185',
 XY='(-4500,1975)',
 ROT='0',
 VER='1',
 VALUE='0.1UF',
 PACK_TYPE='0402V',
 PART_NUMBER='A36096-030',
 LOCATION='C2P9',
 ROOM='M_2',
 SEC='1',
 CDS_LIB='dev_discrete',
 CDS_PART_NAME='CAP_A_0402V-0.1UF,16V,10%,X7R,A',
 VOLTAGE='16V',
 PRIM_FILE='./archive_libs/discrete/cap_a/chips/chips.prt';

PART_NAME
 C2P10 'CAP_1206LF-22UF,16V,10%,X6S,D3A':
 ROOM='IO_MODULE';

SECTION_NUMBER 1
 '@BASEBOARD_FAB2_LIB.BASEBOARD_FAB2(SCH_1):PAGE188_I41@MSTR_DISCRETE.CAP(CHIPS)':
 C_PATH='@baseboard_fab2_lib.baseboard_fab2(sch_1):page188_i41@mstr_discrete.cap~
(chips)',
 P_PATH='@baseboard_fab2_lib.baseboard_fab2(sch_1):page188_i41@mstr_discrete.cap~
(chips)',
 PATH='I41',
 DRAWING='@BASEBOARD_FAB2_LIB.BASEBOARD_FAB2(SCH_1):PAGE188',
 TOLERANCE='10%',
 SEC_TYPE='1206LF',
 MATERIAL='X6S',
 BOM_COST='IO_MODULE',
 PHYS_PAGE='188',
 XY='(-75,1300)',
 ROT='0',
 VER='1',
 VALUE='22UF',
 PACK_TYPE='1206LF',
 PART_NUMBER='D38464-005',
 LOCATION='C2P10',
 ROOM='IO_MODULE',
 SEC='1',
 CDS_LIB='mstr_discrete',
 CDS_PART_NAME='CAP_1206LF-22UF,16V,10%,X6S,D3A',
 VOLTAGE='16V',
 PRIM_FILE='./archive_libs/mstr_discrete/cap/chips/chips.prt';

PART_NAME
 C2P11 'CAP_A_0402V-0.1UF,16V,10%,X7R,A':
 ROOM='IO_MODULE';

SECTION_NUMBER 1
 '@BASEBOARD_FAB2_LIB.BASEBOARD_FAB2(SCH_1):PAGE188_I21@DEV_DISCRETE.CAP_A(CHIPS)':
 C_PATH='@baseboard_fab2_lib.baseboard_fab2(sch_1):page188_i21@dev_discrete.cap_~
a(chips)',
 P_PATH='@baseboard_fab2_lib.baseboard_fab2(sch_1):page188_i21@dev_discrete.cap_~
a(chips)',
 PATH='I21',
 DRAWING='@BASEBOARD_FAB2_LIB.BASEBOARD_FAB2(SCH_1):PAGE188',
 TOLERANCE='10%',
 SEC_TYPE='0402V',
 MATERIAL='X7R',
 BOM_COST='IO_MODULE',
 PHYS_PAGE='188',
 XY='(2400,1300)',
 ROT='0',
 VER='1',
 VALUE='0.1UF',
 PACK_TYPE='0402V',
 PART_NUMBER='A36096-030',
 LOCATION='C2P11',
 ROOM='IO_MODULE',
 SEC='1',
 CDS_LIB='dev_discrete',
 CDS_PART_NAME='CAP_A_0402V-0.1UF,16V,10%,X7R,A',
 VOLTAGE='16V',
 PRIM_FILE='./archive_libs/discrete/cap_a/chips/chips.prt';

PART_NAME
 C2P12 'CAP_A_0402V-0.1UF,16V,10%,X7R,A':
 ROOM='IO_MODULE';

SECTION_NUMBER 1
 '@BASEBOARD_FAB2_LIB.BASEBOARD_FAB2(SCH_1):PAGE188_I23@DEV_DISCRETE.CAP_A(CHIPS)':
 C_PATH='@baseboard_fab2_lib.baseboard_fab2(sch_1):page188_i23@dev_discrete.cap_~
a(chips)',
 P_PATH='@baseboard_fab2_lib.baseboard_fab2(sch_1):page188_i23@dev_discrete.cap_~
a(chips)',
 PATH='I23',
 DRAWING='@BASEBOARD_FAB2_LIB.BASEBOARD_FAB2(SCH_1):PAGE188',
 TOLERANCE='10%',
 SEC_TYPE='0402V',
 MATERIAL='X7R',
 BOM_COST='IO_MODULE',
 PHYS_PAGE='188',
 XY='(2050,1300)',
 ROT='0',
 VER='1',
 VALUE='0.1UF',
 PACK_TYPE='0402V',
 PART_NUMBER='A36096-030',
 LOCATION='C2P12',
 ROOM='IO_MODULE',
 SEC='1',
 CDS_LIB='dev_discrete',
 CDS_PART_NAME='CAP_A_0402V-0.1UF,16V,10%,X7R,A',
 VOLTAGE='16V',
 PRIM_FILE='./archive_libs/discrete/cap_a/chips/chips.prt';

PART_NAME
 C2P13 'CAP_A_0402V-0.1UF,16V,10%,X7R,A':
 ROOM='IO_MODULE';

SECTION_NUMBER 1
 '@BASEBOARD_FAB2_LIB.BASEBOARD_FAB2(SCH_1):PAGE188_I57@DEV_DISCRETE.CAP_A(CHIPS)':
 C_PATH='@baseboard_fab2_lib.baseboard_fab2(sch_1):page188_i57@dev_discrete.cap_~
a(chips)',
 P_PATH='@baseboard_fab2_lib.baseboard_fab2(sch_1):page188_i57@dev_discrete.cap_~
a(chips)',
 PATH='I57',
 DRAWING='@BASEBOARD_FAB2_LIB.BASEBOARD_FAB2(SCH_1):PAGE188',
 TOLERANCE='10%',
 MATERIAL='X7R',
 BOM_COST='IO_MODULE',
 PHYS_PAGE='188',
 XY='(-1825,1300)',
 ROT='0',
 VER='1',
 VALUE='0.1UF',
 PACK_TYPE='0402V',
 PART_NUMBER='A36096-030',
 LOCATION='C2P13',
 ROOM='IO_MODULE',
 CDS_LIB='dev_discrete',
 CDS_PART_NAME='CAP_A_0402V-0.1UF,16V,10%,X7R,A',
 VOLTAGE='16V',
 PRIM_FILE='./archive_libs/discrete/cap_a/chips/chips.prt';

PART_NAME
 C2P14 'CAP_A_0402V-0.1UF,16V,10%,X7R,A':
 ROOM='IO_MODULE';

SECTION_NUMBER 1
 '@BASEBOARD_FAB2_LIB.BASEBOARD_FAB2(SCH_1):PAGE188_I56@DEV_DISCRETE.CAP_A(CHIPS)':
 C_PATH='@baseboard_fab2_lib.baseboard_fab2(sch_1):page188_i56@dev_discrete.cap_~
a(chips)',
 P_PATH='@baseboard_fab2_lib.baseboard_fab2(sch_1):page188_i56@dev_discrete.cap_~
a(chips)',
 PATH='I56',
 DRAWING='@BASEBOARD_FAB2_LIB.BASEBOARD_FAB2(SCH_1):PAGE188',
 TOLERANCE='10%',
 MATERIAL='X7R',
 BOM_COST='IO_MODULE',
 PHYS_PAGE='188',
 XY='(-1400,1300)',
 ROT='0',
 VER='1',
 VALUE='0.1UF',
 PACK_TYPE='0402V',
 PART_NUMBER='A36096-030',
 LOCATION='C2P14',
 ROOM='IO_MODULE',
 CDS_LIB='dev_discrete',
 CDS_PART_NAME='CAP_A_0402V-0.1UF,16V,10%,X7R,A',
 VOLTAGE='16V',
 PRIM_FILE='./archive_libs/discrete/cap_a/chips/chips.prt';

PART_NAME
 C2P15 'CAP_A_0402V-0.1UF,16V,10%,X7R,A':
 ROOM='IO_MODULE';

SECTION_NUMBER 1
 '@BASEBOARD_FAB2_LIB.BASEBOARD_FAB2(SCH_1):PAGE188_I55@DEV_DISCRETE.CAP_A(CHIPS)':
 C_PATH='@baseboard_fab2_lib.baseboard_fab2(sch_1):page188_i55@dev_discrete.cap_~
a(chips)',
 P_PATH='@baseboard_fab2_lib.baseboard_fab2(sch_1):page188_i55@dev_discrete.cap_~
a(chips)',
 PATH='I55',
 DRAWING='@BASEBOARD_FAB2_LIB.BASEBOARD_FAB2(SCH_1):PAGE188',
 TOLERANCE='10%',
 MATERIAL='X7R',
 BOM_COST='IO_MODULE',
 PHYS_PAGE='188',
 XY='(-950,1300)',
 ROT='0',
 VER='1',
 VALUE='0.1UF',
 PACK_TYPE='0402V',
 PART_NUMBER='A36096-030',
 LOCATION='C2P15',
 ROOM='IO_MODULE',
 CDS_LIB='dev_discrete',
 CDS_PART_NAME='CAP_A_0402V-0.1UF,16V,10%,X7R,A',
 VOLTAGE='16V',
 PRIM_FILE='./archive_libs/discrete/cap_a/chips/chips.prt';

PART_NAME
 C2P16 'CAP_A_0402V-0.1UF,16V,10%,X7R,A':
 ROOM='IO_MODULE';

SECTION_NUMBER 1
 '@BASEBOARD_FAB2_LIB.BASEBOARD_FAB2(SCH_1):PAGE188_I53@DEV_DISCRETE.CAP_A(CHIPS)':
 C_PATH='@baseboard_fab2_lib.baseboard_fab2(sch_1):page188_i53@dev_discrete.cap_~
a(chips)',
 P_PATH='@baseboard_fab2_lib.baseboard_fab2(sch_1):page188_i53@dev_discrete.cap_~
a(chips)',
 PATH='I53',
 DRAWING='@BASEBOARD_FAB2_LIB.BASEBOARD_FAB2(SCH_1):PAGE188',
 TOLERANCE='10%',
 MATERIAL='X7R',
 BOM_COST='IO_MODULE',
 PHYS_PAGE='188',
 XY='(-525,1300)',
 ROT='0',
 VER='1',
 VALUE='0.1UF',
 PACK_TYPE='0402V',
 PART_NUMBER='A36096-030',
 LOCATION='C2P16',
 ROOM='IO_MODULE',
 CDS_LIB='dev_discrete',
 CDS_PART_NAME='CAP_A_0402V-0.1UF,16V,10%,X7R,A',
 VOLTAGE='16V',
 PRIM_FILE='./archive_libs/discrete/cap_a/chips/chips.prt';

PART_NAME
 C2R1 'CAP_A_0402V-0.1UF,16V,10%,X7R,A':
 ROOM='CPLD',
 SIGNAL_MODEL='DEFAULT_CAPACITOR_100000pF_2_1';

SECTION_NUMBER 1
 '@BASEBOARD_FAB2_LIB.BASEBOARD_FAB2(SCH_1):PAGE192_I8@DEV_DISCRETE.CAP_A(CHIPS)':
 C_PATH='@baseboard_fab2_lib.baseboard_fab2(sch_1):page192_i8@dev_discrete.cap_a~
(chips)',
 P_PATH='@baseboard_fab2_lib.baseboard_fab2(sch_1):page192_i8@dev_discrete.cap_a~
(chips)',
 PATH='I8',
 DRAWING='@BASEBOARD_FAB2_LIB.BASEBOARD_FAB2(SCH_1):PAGE192',
 TOLERANCE='10%',
 MATERIAL='X7R',
 BOM_COST='CPLD',
 PHYS_PAGE='192',
 XY='(-3150,1300)',
 ROT='0',
 VER='1',
 VALUE='0.1UF',
 PACK_TYPE='0402V',
 PART_NUMBER='A36096-030',
 LOCATION='C2R1',
 SIGNAL_MODEL='DEFAULT_CAPACITOR_100000pF_2_1',
 ROOM='CPLD',
 CDS_LIB='dev_discrete',
 CDS_PART_NAME='CAP_A_0402V-0.1UF,16V,10%,X7R,A',
 VOLTAGE='16V',
 PRIM_FILE='./archive_libs/discrete/cap_a/chips/chips.prt';

PART_NAME
 C2R2 'CAP_A_0402V-0.1UF,16V,10%,X7R,A':
 ROOM='CPLD',
 SIGNAL_MODEL='DEFAULT_CAPACITOR_100000pF_2_1';

SECTION_NUMBER 1
 '@BASEBOARD_FAB2_LIB.BASEBOARD_FAB2(SCH_1):PAGE192_I28@DEV_DISCRETE.CAP_A(CHIPS)':
 C_PATH='@baseboard_fab2_lib.baseboard_fab2(sch_1):page192_i28@dev_discrete.cap_~
a(chips)',
 P_PATH='@baseboard_fab2_lib.baseboard_fab2(sch_1):page192_i28@dev_discrete.cap_~
a(chips)',
 PATH='I28',
 DRAWING='@BASEBOARD_FAB2_LIB.BASEBOARD_FAB2(SCH_1):PAGE192',
 TOLERANCE='10%',
 MATERIAL='X7R',
 BOM_COST='CPLD',
 PHYS_PAGE='192',
 XY='(-6850,1300)',
 ROT='0',
 VER='1',
 VALUE='0.1UF',
 PACK_TYPE='0402V',
 PART_NUMBER='A36096-030',
 LOCATION='C2R2',
 SIGNAL_MODEL='DEFAULT_CAPACITOR_100000pF_2_1',
 ROOM='CPLD',
 CDS_LIB='dev_discrete',
 CDS_PART_NAME='CAP_A_0402V-0.1UF,16V,10%,X7R,A',
 VOLTAGE='16V',
 PRIM_FILE='./archive_libs/discrete/cap_a/chips/chips.prt';

PART_NAME
 C2R3 'CAP_A_0402V-0.1UF,16V,10%,X7R,A':
 ROOM='CPLD',
 SIGNAL_MODEL='DEFAULT_CAPACITOR_100000pF_2_1';

SECTION_NUMBER 1
 '@BASEBOARD_FAB2_LIB.BASEBOARD_FAB2(SCH_1):PAGE192_I19@DEV_DISCRETE.CAP_A(CHIPS)':
 C_PATH='@baseboard_fab2_lib.baseboard_fab2(sch_1):page192_i19@dev_discrete.cap_~
a(chips)',
 P_PATH='@baseboard_fab2_lib.baseboard_fab2(sch_1):page192_i19@dev_discrete.cap_~
a(chips)',
 PATH='I19',
 DRAWING='@BASEBOARD_FAB2_LIB.BASEBOARD_FAB2(SCH_1):PAGE192',
 TOLERANCE='10%',
 MATERIAL='X7R',
 BOM_COST='CPLD',
 PHYS_PAGE='192',
 XY='(-5500,1975)',
 ROT='0',
 VER='1',
 VALUE='0.1UF',
 PACK_TYPE='0402V',
 PART_NUMBER='A36096-030',
 LOCATION='C2R3',
 SIGNAL_MODEL='DEFAULT_CAPACITOR_100000pF_2_1',
 ROOM='CPLD',
 CDS_LIB='dev_discrete',
 CDS_PART_NAME='CAP_A_0402V-0.1UF,16V,10%,X7R,A',
 VOLTAGE='16V',
 PRIM_FILE='./archive_libs/discrete/cap_a/chips/chips.prt';

PART_NAME
 C2R4 'CAP_A_0402V-0.1UF,16V,10%,X7R,A':
 ROOM='CPLD',
 SIGNAL_MODEL='DEFAULT_CAPACITOR_100000pF_2_1';

SECTION_NUMBER 1
 '@BASEBOARD_FAB2_LIB.BASEBOARD_FAB2(SCH_1):PAGE192_I21@DEV_DISCRETE.CAP_A(CHIPS)':
 C_PATH='@baseboard_fab2_lib.baseboard_fab2(sch_1):page192_i21@dev_discrete.cap_~
a(chips)',
 P_PATH='@baseboard_fab2_lib.baseboard_fab2(sch_1):page192_i21@dev_discrete.cap_~
a(chips)',
 PATH='I21',
 DRAWING='@BASEBOARD_FAB2_LIB.BASEBOARD_FAB2(SCH_1):PAGE192',
 TOLERANCE='10%',
 MATERIAL='X7R',
 BOM_COST='CPLD',
 PHYS_PAGE='192',
 XY='(-5700,1300)',
 ROT='0',
 VER='1',
 VALUE='0.1UF',
 PACK_TYPE='0402V',
 PART_NUMBER='A36096-030',
 LOCATION='C2R4',
 SIGNAL_MODEL='DEFAULT_CAPACITOR_100000pF_2_1',
 ROOM='CPLD',
 CDS_LIB='dev_discrete',
 CDS_PART_NAME='CAP_A_0402V-0.1UF,16V,10%,X7R,A',
 VOLTAGE='16V',
 PRIM_FILE='./archive_libs/discrete/cap_a/chips/chips.prt';

PART_NAME
 C2R5 'CAP_A_0402V-0.1UF,16V,10%,X7R,A':
 ROOM='CPLD',
 SIGNAL_MODEL='DEFAULT_CAPACITOR_100000pF_2_1';

SECTION_NUMBER 1
 '@BASEBOARD_FAB2_LIB.BASEBOARD_FAB2(SCH_1):PAGE192_I15@DEV_DISCRETE.CAP_A(CHIPS)':
 C_PATH='@baseboard_fab2_lib.baseboard_fab2(sch_1):page192_i15@dev_discrete.cap_~
a(chips)',
 P_PATH='@baseboard_fab2_lib.baseboard_fab2(sch_1):page192_i15@dev_discrete.cap_~
a(chips)',
 PATH='I15',
 DRAWING='@BASEBOARD_FAB2_LIB.BASEBOARD_FAB2(SCH_1):PAGE192',
 TOLERANCE='10%',
 MATERIAL='X7R',
 BOM_COST='CPLD',
 PHYS_PAGE='192',
 XY='(-4550,1975)',
 ROT='0',
 VER='1',
 VALUE='0.1UF',
 PACK_TYPE='0402V',
 PART_NUMBER='A36096-030',
 LOCATION='C2R5',
 SIGNAL_MODEL='DEFAULT_CAPACITOR_100000pF_2_1',
 ROOM='CPLD',
 CDS_LIB='dev_discrete',
 CDS_PART_NAME='CAP_A_0402V-0.1UF,16V,10%,X7R,A',
 VOLTAGE='16V',
 PRIM_FILE='./archive_libs/discrete/cap_a/chips/chips.prt';

PART_NAME
 C2R6 'CAP_0402LF-470PF,50V,10%,EMPTYA':
 ROOM='IO_SLOT';

SECTION_NUMBER 1
 '@BASEBOARD_FAB2_LIB.BASEBOARD_FAB2(SCH_1):PAGE181_I40@MSTR_DISCRETE.CAP(CHIPS)':
 C_PATH='@baseboard_fab2_lib.baseboard_fab2(sch_1):page181_i40@mstr_discrete.cap~
(chips)',
 P_PATH='@baseboard_fab2_lib.baseboard_fab2(sch_1):page181_i40@mstr_discrete.cap~
(chips)',
 PATH='I40',
 DRAWING='@BASEBOARD_FAB2_LIB.BASEBOARD_FAB2(SCH_1):PAGE181',
 TOLERANCE='10%',
 SEC_TYPE='0402LF',
 MATERIAL='EMPTY',
 PHYS_PAGE='181',
 XY='(300,625)',
 ROT='0',
 VER='1',
 VALUE='470PF',
 PACK_TYPE='0402LF',
 PART_NUMBER='A36096-049',
 LOCATION='C2R6',
 ROOM='IO_SLOT',
 SEC='1',
 CDS_LIB='mstr_discrete',
 CDS_PART_NAME='CAP_0402LF-470PF,50V,10%,EMPTYA',
 VOLTAGE='50V',
 PRIM_FILE='./archive_libs/mstr_discrete/cap/chips/chips.prt';

PART_NAME
 C2R7 'CAP_0402-0.22UF,16V,10%,X7R,A3A':
 ROOM='PCIE_STEERING';

SECTION_NUMBER 1
 '@BASEBOARD_FAB2_LIB.BASEBOARD_FAB2(SCH_1):PAGE106_I123@MSTR_DISCRETE.CAP(CHIPS)':
 C_PATH='@baseboard_fab2_lib.baseboard_fab2(sch_1):page106_i123@mstr_discrete.ca~
p(chips)',
 P_PATH='@baseboard_fab2_lib.baseboard_fab2(sch_1):page106_i123@mstr_discrete.ca~
p(chips)',
 PATH='I123',
 DRAWING='@BASEBOARD_FAB2_LIB.BASEBOARD_FAB2(SCH_1):PAGE106',
 TOLERANCE='10%',
 MATERIAL='X7R',
 BOM_COST='IO_SLOT',
 PHYS_PAGE='106',
 XY='(-5275,1650)',
 ROT='2',
 VER='1',
 VALUE='0.22UF',
 PACK_TYPE='0402',
 PART_NUMBER='A36096-155',
 LOCATION='C2R7',
 ROOM='PCIE_STEERING',
 CDS_LIB='mstr_discrete',
 CDS_PART_NAME='CAP_0402-0.22UF,16V,10%,X7R,A3A',
 VOLTAGE='16V',
 PRIM_FILE='./archive_libs/mstr_discrete/cap/chips/chips.prt';

PART_NAME
 C2R8 'CAP_0402-0.22UF,16V,10%,X7R,A3A':
 ROOM='PCIE_STEERING';

SECTION_NUMBER 1
 '@BASEBOARD_FAB2_LIB.BASEBOARD_FAB2(SCH_1):PAGE106_I141@MSTR_DISCRETE.CAP(CHIPS)':
 C_PATH='@baseboard_fab2_lib.baseboard_fab2(sch_1):page106_i141@mstr_discrete.ca~
p(chips)',
 P_PATH='@baseboard_fab2_lib.baseboard_fab2(sch_1):page106_i141@mstr_discrete.ca~
p(chips)',
 PATH='I141',
 DRAWING='@BASEBOARD_FAB2_LIB.BASEBOARD_FAB2(SCH_1):PAGE106',
 TOLERANCE='10%',
 MATERIAL='X7R',
 BOM_COST='IO_SLOT',
 PHYS_PAGE='106',
 XY='(-5300,2650)',
 ROT='2',
 VER='1',
 VALUE='0.22UF',
 PACK_TYPE='0402',
 PART_NUMBER='A36096-155',
 LOCATION='C2R8',
 ROOM='PCIE_STEERING',
 CDS_LIB='mstr_discrete',
 CDS_PART_NAME='CAP_0402-0.22UF,16V,10%,X7R,A3A',
 VOLTAGE='16V',
 PRIM_FILE='./archive_libs/mstr_discrete/cap/chips/chips.prt';

PART_NAME
 C2R9 'CAP_0402-0.22UF,16V,10%,X7R,A3A':
 ROOM='PCIE_STEERING';

SECTION_NUMBER 1
 '@BASEBOARD_FAB2_LIB.BASEBOARD_FAB2(SCH_1):PAGE106_I147@MSTR_DISCRETE.CAP(CHIPS)':
 C_PATH='@baseboard_fab2_lib.baseboard_fab2(sch_1):page106_i147@mstr_discrete.ca~
p(chips)',
 P_PATH='@baseboard_fab2_lib.baseboard_fab2(sch_1):page106_i147@mstr_discrete.ca~
p(chips)',
 PATH='I147',
 DRAWING='@BASEBOARD_FAB2_LIB.BASEBOARD_FAB2(SCH_1):PAGE106',
 TOLERANCE='10%',
 MATERIAL='X7R',
 BOM_COST='IO_SLOT',
 PHYS_PAGE='106',
 XY='(-5475,1350)',
 ROT='2',
 VER='1',
 VALUE='0.22UF',
 PACK_TYPE='0402',
 PART_NUMBER='A36096-155',
 LOCATION='C2R9',
 ROOM='PCIE_STEERING',
 CDS_LIB='mstr_discrete',
 CDS_PART_NAME='CAP_0402-0.22UF,16V,10%,X7R,A3A',
 VOLTAGE='16V',
 PRIM_FILE='./archive_libs/mstr_discrete/cap/chips/chips.prt';

PART_NAME
 C2R10 'CAP_0402-0.22UF,16V,10%,X7R,A3A':
 ROOM='PCIE_STEERING';

SECTION_NUMBER 1
 '@BASEBOARD_FAB2_LIB.BASEBOARD_FAB2(SCH_1):PAGE106_I142@MSTR_DISCRETE.CAP(CHIPS)':
 C_PATH='@baseboard_fab2_lib.baseboard_fab2(sch_1):page106_i142@mstr_discrete.ca~
p(chips)',
 P_PATH='@baseboard_fab2_lib.baseboard_fab2(sch_1):page106_i142@mstr_discrete.ca~
p(chips)',
 PATH='I142',
 DRAWING='@BASEBOARD_FAB2_LIB.BASEBOARD_FAB2(SCH_1):PAGE106',
 TOLERANCE='10%',
 MATERIAL='X7R',
 BOM_COST='IO_SLOT',
 PHYS_PAGE='106',
 XY='(-5500,2350)',
 ROT='2',
 VER='1',
 VALUE='0.22UF',
 PACK_TYPE='0402',
 PART_NUMBER='A36096-155',
 LOCATION='C2R10',
 ROOM='PCIE_STEERING',
 CDS_LIB='mstr_discrete',
 CDS_PART_NAME='CAP_0402-0.22UF,16V,10%,X7R,A3A',
 VOLTAGE='16V',
 PRIM_FILE='./archive_libs/mstr_discrete/cap/chips/chips.prt';

PART_NAME
 C2R11 'SC4D7U16V3KX-GP_SMD-BCG5-SC4D7A':;

SECTION_NUMBER 1
 '@BASEBOARD_FAB2_LIB.BASEBOARD_FAB2(SCH_1):PAGE240_I191@W_HDL.SC4D7U16V3KX-GP(CHIPS)':
 C_PATH='@baseboard_fab2_lib.baseboard_fab2(sch_1):page240_i191@w_hdl.\sc4d7u16v~
3kx-gp\(chips)',
 P_PATH='@baseboard_fab2_lib.baseboard_fab2(sch_1):page240_i191@w_hdl.\sc4d7u16v~
3kx-gp\(chips)',
 PATH='I191',
 DRAWING='@BASEBOARD_FAB2_LIB.BASEBOARD_FAB2(SCH_1):PAGE240',
 PACK_SIZE='0603',
 RATED='16V',
 ATTRIBUTE='4.7UF',
 TOLERANCE='10%',
 SEC_TYPE='SMD-BCG5',
 PHYS_PAGE='240',
 XY='(5500,3275)',
 ROT='0',
 VER='1',
 VALUE='SC4D7U16V3KX-GP',
 PACK_TYPE='SMD-BCG5',
 PART_NUMBER='078.47521.08BD',
 LOCATION='C2R11',
 SEC='1',
 CDS_LIB='w_hdl',
 CDS_PART_NAME='SC4D7U16V3KX-GP_SMD-BCG5-SC4D7A',
 PRIM_FILE='C:/<user>/w_hdl/sc4d7u16v3kx#2dgp/chips/chips.prt';

PART_NAME
 C2R12 'CAP_A_0402V-1.0UF,6.3V,10%,X6SA':
 ROOM='MIO_CHASSIS';

SECTION_NUMBER 1
 '@BASEBOARD_FAB2_LIB.BASEBOARD_FAB2(SCH_1):PAGE157_I353@DEV_DISCRETE.CAP_A(CHIPS)':
 C_PATH='@baseboard_fab2_lib.baseboard_fab2(sch_1):page157_i353@dev_discrete.cap~
_a(chips)',
 P_PATH='@baseboard_fab2_lib.baseboard_fab2(sch_1):page157_i353@dev_discrete.cap~
_a(chips)',
 PATH='I353',
 DRAWING='@BASEBOARD_FAB2_LIB.BASEBOARD_FAB2(SCH_1):PAGE157',
 TOLERANCE='10%',
 SEC_TYPE='0402V',
 MATERIAL='X6S',
 BOM_COST='MIO_CHASSIS',
 PHYS_PAGE='157',
 XY='(-3225,2450)',
 ROT='0',
 VER='1',
 VALUE='1.0UF',
 PACK_TYPE='0402V',
 PART_NUMBER='D97712-004',
 LOCATION='C2R12',
 ROOM='MIO_CHASSIS',
 SEC='1',
 CDS_LIB='dev_discrete',
 CDS_PART_NAME='CAP_A_0402V-1.0UF,6.3V,10%,X6SA',
 VOLTAGE='6.3V',
 PRIM_FILE='./archive_libs/discrete/cap_a/chips/chips.prt';

PART_NAME
 C2R13 'CAP_0402-0.22UF,16V,10%,X7R,A3A':
 ROOM='PCIE_STEERING';

SECTION_NUMBER 1
 '@BASEBOARD_FAB2_LIB.BASEBOARD_FAB2(SCH_1):PAGE106_I137@MSTR_DISCRETE.CAP(CHIPS)':
 C_PATH='@baseboard_fab2_lib.baseboard_fab2(sch_1):page106_i137@mstr_discrete.ca~
p(chips)',
 P_PATH='@baseboard_fab2_lib.baseboard_fab2(sch_1):page106_i137@mstr_discrete.ca~
p(chips)',
 PATH='I137',
 DRAWING='@BASEBOARD_FAB2_LIB.BASEBOARD_FAB2(SCH_1):PAGE106',
 TOLERANCE='10%',
 MATERIAL='X7R',
 BOM_COST='IO_SLOT',
 PHYS_PAGE='106',
 XY='(-5075,1350)',
 ROT='2',
 VER='1',
 VALUE='0.22UF',
 PACK_TYPE='0402',
 PART_NUMBER='A36096-155',
 LOCATION='C2R13',
 ROOM='PCIE_STEERING',
 CDS_LIB='mstr_discrete',
 CDS_PART_NAME='CAP_0402-0.22UF,16V,10%,X7R,A3A',
 VOLTAGE='16V',
 PRIM_FILE='./archive_libs/mstr_discrete/cap/chips/chips.prt';

PART_NAME
 C2R14 'CAP_0402-0.22UF,16V,10%,X7R,A3A':
 ROOM='PCIE_STEERING';

SECTION_NUMBER 1
 '@BASEBOARD_FAB2_LIB.BASEBOARD_FAB2(SCH_1):PAGE106_I130@MSTR_DISCRETE.CAP(CHIPS)':
 C_PATH='@baseboard_fab2_lib.baseboard_fab2(sch_1):page106_i130@mstr_discrete.ca~
p(chips)',
 P_PATH='@baseboard_fab2_lib.baseboard_fab2(sch_1):page106_i130@mstr_discrete.ca~
p(chips)',
 PATH='I130',
 DRAWING='@BASEBOARD_FAB2_LIB.BASEBOARD_FAB2(SCH_1):PAGE106',
 TOLERANCE='10%',
 MATERIAL='X7R',
 BOM_COST='IO_SLOT',
 PHYS_PAGE='106',
 XY='(-5100,2350)',
 ROT='2',
 VER='1',
 VALUE='0.22UF',
 PACK_TYPE='0402',
 PART_NUMBER='A36096-155',
 LOCATION='C2R14',
 ROOM='PCIE_STEERING',
 CDS_LIB='mstr_discrete',
 CDS_PART_NAME='CAP_0402-0.22UF,16V,10%,X7R,A3A',
 VOLTAGE='16V',
 PRIM_FILE='./archive_libs/mstr_discrete/cap/chips/chips.prt';

PART_NAME
 C2R15 'CAP_A_0402V-0.1UF,16V,10%,X7R,A':
 ROOM='IO_MODULE';

SECTION_NUMBER 1
 '@BASEBOARD_FAB2_LIB.BASEBOARD_FAB2(SCH_1):PAGE188_I2@DEV_DISCRETE.CAP_A(CHIPS)':
 C_PATH='@baseboard_fab2_lib.baseboard_fab2(sch_1):page188_i2@dev_discrete.cap_a~
(chips)',
 P_PATH='@baseboard_fab2_lib.baseboard_fab2(sch_1):page188_i2@dev_discrete.cap_a~
(chips)',
 PATH='I2',
 DRAWING='@BASEBOARD_FAB2_LIB.BASEBOARD_FAB2(SCH_1):PAGE188',
 TOLERANCE='10%',
 SEC_TYPE='0402V',
 MATERIAL='X7R',
 BOM_COST='IO_MODULE',
 PHYS_PAGE='188',
 XY='(3300,1300)',
 ROT='0',
 VER='1',
 VALUE='0.1UF',
 PACK_TYPE='0402V',
 PART_NUMBER='A36096-030',
 LOCATION='C2R15',
 ROOM='IO_MODULE',
 SEC='1',
 CDS_LIB='dev_discrete',
 CDS_PART_NAME='CAP_A_0402V-0.1UF,16V,10%,X7R,A',
 VOLTAGE='16V',
 PRIM_FILE='./archive_libs/discrete/cap_a/chips/chips.prt';

PART_NAME
 C2R16 'CAP_A_0402V-0.1UF,16V,10%,X7R,A':
 ROOM='IO_MODULE';

SECTION_NUMBER 1
 '@BASEBOARD_FAB2_LIB.BASEBOARD_FAB2(SCH_1):PAGE188_I40@DEV_DISCRETE.CAP_A(CHIPS)':
 C_PATH='@baseboard_fab2_lib.baseboard_fab2(sch_1):page188_i40@dev_discrete.cap_~
a(chips)',
 P_PATH='@baseboard_fab2_lib.baseboard_fab2(sch_1):page188_i40@dev_discrete.cap_~
a(chips)',
 PATH='I40',
 DRAWING='@BASEBOARD_FAB2_LIB.BASEBOARD_FAB2(SCH_1):PAGE188',
 TOLERANCE='10%',
 MATERIAL='X7R',
 BOM_COST='IO_MODULE',
 PHYS_PAGE='188',
 XY='(475,1300)',
 ROT='0',
 VER='1',
 VALUE='0.1UF',
 PACK_TYPE='0402V',
 PART_NUMBER='A36096-030',
 LOCATION='C2R16',
 ROOM='IO_MODULE',
 CDS_LIB='dev_discrete',
 CDS_PART_NAME='CAP_A_0402V-0.1UF,16V,10%,X7R,A',
 VOLTAGE='16V',
 PRIM_FILE='./archive_libs/discrete/cap_a/chips/chips.prt';

PART_NAME
 C2R17 'CAP_A_0402V-0.1UF,16V,10%,X7R,A':
 ROOM='IO_MODULE';

SECTION_NUMBER 1
 '@BASEBOARD_FAB2_LIB.BASEBOARD_FAB2(SCH_1):PAGE188_I25@DEV_DISCRETE.CAP_A(CHIPS)':
 C_PATH='@baseboard_fab2_lib.baseboard_fab2(sch_1):page188_i25@dev_discrete.cap_~
a(chips)',
 P_PATH='@baseboard_fab2_lib.baseboard_fab2(sch_1):page188_i25@dev_discrete.cap_~
a(chips)',
 PATH='I25',
 DRAWING='@BASEBOARD_FAB2_LIB.BASEBOARD_FAB2(SCH_1):PAGE188',
 TOLERANCE='10%',
 MATERIAL='X7R',
 BOM_COST='IO_MODULE',
 PHYS_PAGE='188',
 XY='(1000,1300)',
 ROT='0',
 VER='1',
 VALUE='0.1UF',
 PACK_TYPE='0402V',
 PART_NUMBER='A36096-030',
 LOCATION='C2R17',
 ROOM='IO_MODULE',
 CDS_LIB='dev_discrete',
 CDS_PART_NAME='CAP_A_0402V-0.1UF,16V,10%,X7R,A',
 VOLTAGE='16V',
 PRIM_FILE='./archive_libs/discrete/cap_a/chips/chips.prt';

PART_NAME
 C2R18 'CAP_A_0402V-0.1UF,16V,10%,X7R,A':
 ROOM='IO_MODULE';

SECTION_NUMBER 1
 '@BASEBOARD_FAB2_LIB.BASEBOARD_FAB2(SCH_1):PAGE188_I3@DEV_DISCRETE.CAP_A(CHIPS)':
 C_PATH='@baseboard_fab2_lib.baseboard_fab2(sch_1):page188_i3@dev_discrete.cap_a~
(chips)',
 P_PATH='@baseboard_fab2_lib.baseboard_fab2(sch_1):page188_i3@dev_discrete.cap_a~
(chips)',
 PATH='I3',
 DRAWING='@BASEBOARD_FAB2_LIB.BASEBOARD_FAB2(SCH_1):PAGE188',
 TOLERANCE='10%',
 MATERIAL='X7R',
 BOM_COST='IO_MODULE',
 PHYS_PAGE='188',
 XY='(2925,1300)',
 ROT='0',
 VER='1',
 VALUE='0.1UF',
 PACK_TYPE='0402V',
 PART_NUMBER='A36096-030',
 LOCATION='C2R18',
 ROOM='IO_MODULE',
 CDS_LIB='dev_discrete',
 CDS_PART_NAME='CAP_A_0402V-0.1UF,16V,10%,X7R,A',
 VOLTAGE='16V',
 PRIM_FILE='./archive_libs/discrete/cap_a/chips/chips.prt';

PART_NAME
 C2T1 'CAP_A_0402V-0.1UF,16V,10%,X7R,A':
 ROOM='SB_BMC_SPI_MUX';

SECTION_NUMBER 1
 '@BASEBOARD_FAB2_LIB.BASEBOARD_FAB2(SCH_1):PAGE154_I94@DEV_DISCRETE.CAP_A(CHIPS)':
 C_PATH='@baseboard_fab2_lib.baseboard_fab2(sch_1):page154_i94@dev_discrete.cap_~
a(chips)',
 P_PATH='@baseboard_fab2_lib.baseboard_fab2(sch_1):page154_i94@dev_discrete.cap_~
a(chips)',
 PATH='I94',
 DRAWING='@BASEBOARD_FAB2_LIB.BASEBOARD_FAB2(SCH_1):PAGE154',
 TOLERANCE='10%',
 SEC_TYPE='0402V',
 MATERIAL='X7R',
 BOM_COST='MIO_BIOS_MEM',
 PHYS_PAGE='154',
 XY='(-1500,4525)',
 ROT='0',
 VER='1',
 VALUE='0.1UF',
 PACK_TYPE='0402V',
 PART_NUMBER='A36096-030',
 LOCATION='C2T1',
 ROOM='SB_BMC_SPI_MUX',
 SEC='1',
 CDS_LIB='dev_discrete',
 CDS_PART_NAME='CAP_A_0402V-0.1UF,16V,10%,X7R,A',
 VOLTAGE='16V',
 PRIM_FILE='./archive_libs/discrete/cap_a/chips/chips.prt';

PART_NAME
 C2T2 'CAP_A_0402V-0.1UF,16V,10%,X7R,A':
 ROOM='M_2';

SECTION_NUMBER 1
 '@BASEBOARD_FAB2_LIB.BASEBOARD_FAB2(SCH_1):PAGE185_I131@DEV_DISCRETE.CAP_A(CHIPS)':
 C_PATH='@baseboard_fab2_lib.baseboard_fab2(sch_1):page185_i131@dev_discrete.cap~
_a(chips)',
 P_PATH='@baseboard_fab2_lib.baseboard_fab2(sch_1):page185_i131@dev_discrete.cap~
_a(chips)',
 PATH='I131',
 DRAWING='@BASEBOARD_FAB2_LIB.BASEBOARD_FAB2(SCH_1):PAGE185',
 TOLERANCE='10%',
 SEC_TYPE='0402V',
 MATERIAL='X7R',
 BOM_COST='SD_FLASH',
 PHYS_PAGE='185',
 XY='(-950,4575)',
 ROT='0',
 VER='1',
 VALUE='0.1UF',
 PACK_TYPE='0402V',
 PART_NUMBER='A36096-030',
 LOCATION='C2T2',
 ROOM='M_2',
 SEC='1',
 CDS_LIB='dev_discrete',
 CDS_PART_NAME='CAP_A_0402V-0.1UF,16V,10%,X7R,A',
 VOLTAGE='16V',
 PRIM_FILE='./archive_libs/discrete/cap_a/chips/chips.prt';

PART_NAME
 C2T3 'CAP_A_0402V-0.1UF,16V,10%,X7R,A':
 ROOM='MIO_CHASSIS';

SECTION_NUMBER 1
 '@BASEBOARD_FAB2_LIB.BASEBOARD_FAB2(SCH_1):PAGE157_I370@DEV_DISCRETE.CAP_A(CHIPS)':
 C_PATH='@baseboard_fab2_lib.baseboard_fab2(sch_1):page157_i370@dev_discrete.cap~
_a(chips)',
 P_PATH='@baseboard_fab2_lib.baseboard_fab2(sch_1):page157_i370@dev_discrete.cap~
_a(chips)',
 PATH='I370',
 DRAWING='@BASEBOARD_FAB2_LIB.BASEBOARD_FAB2(SCH_1):PAGE157',
 TOLERANCE='10%',
 SEC_TYPE='0402V',
 MATERIAL='X7R',
 BOM_COST='MIO_CHASSIS',
 PHYS_PAGE='157',
 XY='(-1700,2575)',
 ROT='0',
 VER='1',
 VALUE='0.1UF',
 PACK_TYPE='0402V',
 PART_NUMBER='A36096-030',
 LOCATION='C2T3',
 ROOM='MIO_CHASSIS',
 SEC='1',
 CDS_LIB='dev_discrete',
 CDS_PART_NAME='CAP_A_0402V-0.1UF,16V,10%,X7R,A',
 VOLTAGE='16V',
 PRIM_FILE='./archive_libs/discrete/cap_a/chips/chips.prt';

PART_NAME
 C2T4 'CAP_A_0402V-0.1UF,16V,10%,X7R,A':
 ROOM='M_2';

SECTION_NUMBER 1
 '@BASEBOARD_FAB2_LIB.BASEBOARD_FAB2(SCH_1):PAGE185_I132@DEV_DISCRETE.CAP_A(CHIPS)':
 C_PATH='@baseboard_fab2_lib.baseboard_fab2(sch_1):page185_i132@dev_discrete.cap~
_a(chips)',
 P_PATH='@baseboard_fab2_lib.baseboard_fab2(sch_1):page185_i132@dev_discrete.cap~
_a(chips)',
 PATH='I132',
 DRAWING='@BASEBOARD_FAB2_LIB.BASEBOARD_FAB2(SCH_1):PAGE185',
 TOLERANCE='10%',
 SEC_TYPE='0402V',
 MATERIAL='X7R',
 BOM_COST='SD_FLASH',
 PHYS_PAGE='185',
 XY='(-1200,4575)',
 ROT='0',
 VER='1',
 VALUE='0.1UF',
 PACK_TYPE='0402V',
 PART_NUMBER='A36096-030',
 LOCATION='C2T4',
 ROOM='M_2',
 SEC='1',
 CDS_LIB='dev_discrete',
 CDS_PART_NAME='CAP_A_0402V-0.1UF,16V,10%,X7R,A',
 VOLTAGE='16V',
 PRIM_FILE='./archive_libs/discrete/cap_a/chips/chips.prt';

PART_NAME
 C2T5 'CAP_A_0402V-0.1UF,16V,10%,X7R,A':
 ROOM='M_2';

SECTION_NUMBER 1
 '@BASEBOARD_FAB2_LIB.BASEBOARD_FAB2(SCH_1):PAGE185_I135@DEV_DISCRETE.CAP_A(CHIPS)':
 C_PATH='@baseboard_fab2_lib.baseboard_fab2(sch_1):page185_i135@dev_discrete.cap~
_a(chips)',
 P_PATH='@baseboard_fab2_lib.baseboard_fab2(sch_1):page185_i135@dev_discrete.cap~
_a(chips)',
 PATH='I135',
 DRAWING='@BASEBOARD_FAB2_LIB.BASEBOARD_FAB2(SCH_1):PAGE185',
 TOLERANCE='10%',
 SEC_TYPE='0402V',
 MATERIAL='X7R',
 BOM_COST='SD_FLASH',
 PHYS_PAGE='185',
 XY='(-1450,4575)',
 ROT='0',
 VER='1',
 VALUE='0.1UF',
 PACK_TYPE='0402V',
 PART_NUMBER='A36096-030',
 LOCATION='C2T5',
 ROOM='M_2',
 SEC='1',
 CDS_LIB='dev_discrete',
 CDS_PART_NAME='CAP_A_0402V-0.1UF,16V,10%,X7R,A',
 VOLTAGE='16V',
 PRIM_FILE='./archive_libs/discrete/cap_a/chips/chips.prt';

PART_NAME
 C2T6 'CAP_0805-22UF,6.3V,20%,X6S,C95A':
 ROOM='P3V3_STBY_VR',
 REUSE_ID='33';

SECTION_NUMBER 1
 '@BASEBOARD_FAB2_LIB.BASEBOARD_FAB2(SCH_1):PAGE240_I160@MSTR_DISCRETE.CAP(CHIPS)':
 C_PATH='@baseboard_fab2_lib.baseboard_fab2(sch_1):page240_i160@mstr_discrete.ca~
p(chips)',
 P_PATH='@baseboard_fab2_lib.baseboard_fab2(sch_1):page240_i160@mstr_discrete.ca~
p(chips)',
 PATH='I160',
 DRAWING='@BASEBOARD_FAB2_LIB.BASEBOARD_FAB2(SCH_1):PAGE240',
 TOLERANCE='20%',
 MATERIAL='X6S',
 BOM_COST='P3V3_STBY_VR',
 PHYS_PAGE='240',
 REUSE_ID='33',
 XY='(12175,3875)',
 ROT='0',
 VER='1',
 VALUE='22UF',
 PACK_TYPE='0805',
 PART_NUMBER='C95333-008',
 LOCATION='C2T6',
 ROOM='P3V3_STBY_VR',
 CDS_LIB='mstr_discrete',
 CDS_PART_NAME='CAP_0805-22UF,6.3V,20%,X6S,C95A',
 VOLTAGE='6.3V',
 PRIM_FILE='./archive_libs/mstr_discrete/cap/chips/chips.prt';

PART_NAME
 C2T7 'CAP_0805-22UF,6.3V,20%,X6S,C95A':
 ROOM='P3V3_STBY_VR',
 REUSE_ID='33';

SECTION_NUMBER 1
 '@BASEBOARD_FAB2_LIB.BASEBOARD_FAB2(SCH_1):PAGE240_I158@MSTR_DISCRETE.CAP(CHIPS)':
 C_PATH='@baseboard_fab2_lib.baseboard_fab2(sch_1):page240_i158@mstr_discrete.ca~
p(chips)',
 P_PATH='@baseboard_fab2_lib.baseboard_fab2(sch_1):page240_i158@mstr_discrete.ca~
p(chips)',
 PATH='I158',
 DRAWING='@BASEBOARD_FAB2_LIB.BASEBOARD_FAB2(SCH_1):PAGE240',
 TOLERANCE='20%',
 MATERIAL='X6S',
 BOM_COST='P3V3_STBY_VR',
 PHYS_PAGE='240',
 REUSE_ID='33',
 XY='(11950,3875)',
 ROT='0',
 VER='1',
 VALUE='22UF',
 PACK_TYPE='0805',
 PART_NUMBER='C95333-008',
 LOCATION='C2T7',
 ROOM='P3V3_STBY_VR',
 CDS_LIB='mstr_discrete',
 CDS_PART_NAME='CAP_0805-22UF,6.3V,20%,X6S,C95A',
 VOLTAGE='6.3V',
 PRIM_FILE='./archive_libs/mstr_discrete/cap/chips/chips.prt';

PART_NAME
 C2T8 'CAP_A_0402V-0.1UF,16V,10%,X7R,A':
 ROOM='SB_BMC_SPI_MUX';

SECTION_NUMBER 1
 '@BASEBOARD_FAB2_LIB.BASEBOARD_FAB2(SCH_1):PAGE154_I135@DEV_DISCRETE.CAP_A(CHIPS)':
 C_PATH='@baseboard_fab2_lib.baseboard_fab2(sch_1):page154_i135@dev_discrete.cap~
_a(chips)',
 P_PATH='@baseboard_fab2_lib.baseboard_fab2(sch_1):page154_i135@dev_discrete.cap~
_a(chips)',
 PATH='I135',
 DRAWING='@BASEBOARD_FAB2_LIB.BASEBOARD_FAB2(SCH_1):PAGE154',
 TOLERANCE='10%',
 SEC_TYPE='0402V',
 MATERIAL='X7R',
 BOM_COST='MIO_BIOS_MEM',
 PHYS_PAGE='154',
 XY='(-375,1475)',
 ROT='0',
 VER='1',
 VALUE='0.1UF',
 PACK_TYPE='0402V',
 PART_NUMBER='A36096-030',
 LOCATION='C2T8',
 ROOM='SB_BMC_SPI_MUX',
 SEC='1',
 CDS_LIB='dev_discrete',
 CDS_PART_NAME='CAP_A_0402V-0.1UF,16V,10%,X7R,A',
 VOLTAGE='16V',
 PRIM_FILE='./archive_libs/discrete/cap_a/chips/chips.prt';

PART_NAME
 C2T9 'CAP_0805-22UF,6.3V,20%,X6S,C95A':
 ROOM='P3V3_STBY_VR',
 REUSE_ID='33';

SECTION_NUMBER 1
 '@BASEBOARD_FAB2_LIB.BASEBOARD_FAB2(SCH_1):PAGE240_I174@MSTR_DISCRETE.CAP(CHIPS)':
 C_PATH='@baseboard_fab2_lib.baseboard_fab2(sch_1):page240_i174@mstr_discrete.ca~
p(chips)',
 P_PATH='@baseboard_fab2_lib.baseboard_fab2(sch_1):page240_i174@mstr_discrete.ca~
p(chips)',
 PATH='I174',
 DRAWING='@BASEBOARD_FAB2_LIB.BASEBOARD_FAB2(SCH_1):PAGE240',
 TOLERANCE='20%',
 SEC_TYPE='0805',
 MATERIAL='X6S',
 BOM_COST='P3V3_STBY_VR',
 PHYS_PAGE='240',
 REUSE_ID='33',
 XY='(12425,3875)',
 ROT='0',
 VER='1',
 VALUE='22UF',
 PACK_TYPE='0805',
 PART_NUMBER='C95333-008',
 LOCATION='C2T9',
 ROOM='P3V3_STBY_VR',
 SEC='1',
 CDS_LIB='mstr_discrete',
 CDS_PART_NAME='CAP_0805-22UF,6.3V,20%,X6S,C95A',
 VOLTAGE='6.3V',
 PRIM_FILE='./archive_libs/mstr_discrete/cap/chips/chips.prt';

PART_NAME
 C2T10 'CAP_0402-0.22UF,16V,10%,X7R,A3A':
 ROOM='M_2';

SECTION_NUMBER 1
 '@BASEBOARD_FAB2_LIB.BASEBOARD_FAB2(SCH_1):PAGE185_I168@MSTR_DISCRETE.CAP(CHIPS)':
 C_PATH='@baseboard_fab2_lib.baseboard_fab2(sch_1):page185_i168@mstr_discrete.ca~
p(chips)',
 P_PATH='@baseboard_fab2_lib.baseboard_fab2(sch_1):page185_i168@mstr_discrete.ca~
p(chips)',
 PATH='I168',
 DRAWING='@BASEBOARD_FAB2_LIB.BASEBOARD_FAB2(SCH_1):PAGE185',
 TOLERANCE='10%',
 SEC_TYPE='0402',
 MATERIAL='X7R',
 BOM_COST='ST_FLASH',
 PHYS_PAGE='185',
 XY='(-4850,3600)',
 ROT='0',
 VER='2',
 VALUE='0.22UF',
 PACK_TYPE='0402',
 PART_NUMBER='A36096-155',
 LOCATION='C2T10',
 ROOM='M_2',
 SEC='1',
 CDS_LIB='mstr_discrete',
 CDS_PART_NAME='CAP_0402-0.22UF,16V,10%,X7R,A3A',
 VOLTAGE='16V',
 PRIM_FILE='./archive_libs/mstr_discrete/cap/chips/chips.prt';

PART_NAME
 C2T11 'CAP_0402-0.22UF,16V,10%,X7R,A3A':
 ROOM='M_2';

SECTION_NUMBER 1
 '@BASEBOARD_FAB2_LIB.BASEBOARD_FAB2(SCH_1):PAGE185_I167@MSTR_DISCRETE.CAP(CHIPS)':
 C_PATH='@baseboard_fab2_lib.baseboard_fab2(sch_1):page185_i167@mstr_discrete.ca~
p(chips)',
 P_PATH='@baseboard_fab2_lib.baseboard_fab2(sch_1):page185_i167@mstr_discrete.ca~
p(chips)',
 PATH='I167',
 DRAWING='@BASEBOARD_FAB2_LIB.BASEBOARD_FAB2(SCH_1):PAGE185',
 TOLERANCE='10%',
 SEC_TYPE='0402',
 MATERIAL='X7R',
 BOM_COST='ST_FLASH',
 PHYS_PAGE='185',
 XY='(-4850,3650)',
 ROT='0',
 VER='2',
 VALUE='0.22UF',
 PACK_TYPE='0402',
 PART_NUMBER='A36096-155',
 LOCATION='C2T11',
 ROOM='M_2',
 SEC='1',
 CDS_LIB='mstr_discrete',
 CDS_PART_NAME='CAP_0402-0.22UF,16V,10%,X7R,A3A',
 VOLTAGE='16V',
 PRIM_FILE='./archive_libs/mstr_discrete/cap/chips/chips.prt';

PART_NAME
 C2T12 'CAP_A_0402V-0.1UF,16V,10%,X7R,A':
 ROOM='SB_BMC_SPI_MUX';

SECTION_NUMBER 1
 '@BASEBOARD_FAB2_LIB.BASEBOARD_FAB2(SCH_1):PAGE154_I132@DEV_DISCRETE.CAP_A(CHIPS)':
 C_PATH='@baseboard_fab2_lib.baseboard_fab2(sch_1):page154_i132@dev_discrete.cap~
_a(chips)',
 P_PATH='@baseboard_fab2_lib.baseboard_fab2(sch_1):page154_i132@dev_discrete.cap~
_a(chips)',
 PATH='I132',
 DRAWING='@BASEBOARD_FAB2_LIB.BASEBOARD_FAB2(SCH_1):PAGE154',
 TOLERANCE='10%',
 SEC_TYPE='0402V',
 MATERIAL='X7R',
 BOM_COST='MIO_BIOS_MEM',
 PHYS_PAGE='154',
 XY='(-375,2225)',
 ROT='0',
 VER='1',
 VALUE='0.1UF',
 PACK_TYPE='0402V',
 PART_NUMBER='A36096-030',
 LOCATION='C2T12',
 ROOM='SB_BMC_SPI_MUX',
 SEC='1',
 CDS_LIB='dev_discrete',
 CDS_PART_NAME='CAP_A_0402V-0.1UF,16V,10%,X7R,A',
 VOLTAGE='16V',
 PRIM_FILE='./archive_libs/discrete/cap_a/chips/chips.prt';

PART_NAME
 C2T13 'CAP_0402-0.22UF,16V,10%,X7R,A3A':
 ROOM='M_2';

SECTION_NUMBER 1
 '@BASEBOARD_FAB2_LIB.BASEBOARD_FAB2(SCH_1):PAGE185_I172@MSTR_DISCRETE.CAP(CHIPS)':
 C_PATH='@baseboard_fab2_lib.baseboard_fab2(sch_1):page185_i172@mstr_discrete.ca~
p(chips)',
 P_PATH='@baseboard_fab2_lib.baseboard_fab2(sch_1):page185_i172@mstr_discrete.ca~
p(chips)',
 PATH='I172',
 DRAWING='@BASEBOARD_FAB2_LIB.BASEBOARD_FAB2(SCH_1):PAGE185',
 TOLERANCE='10%',
 SEC_TYPE='0402',
 MATERIAL='X7R',
 BOM_COST='ST_FLASH',
 PHYS_PAGE='185',
 XY='(-4850,3900)',
 ROT='0',
 VER='2',
 VALUE='0.22UF',
 PACK_TYPE='0402',
 PART_NUMBER='A36096-155',
 LOCATION='C2T13',
 ROOM='M_2',
 SEC='1',
 CDS_LIB='mstr_discrete',
 CDS_PART_NAME='CAP_0402-0.22UF,16V,10%,X7R,A3A',
 VOLTAGE='16V',
 PRIM_FILE='./archive_libs/mstr_discrete/cap/chips/chips.prt';

PART_NAME
 C2T14 'CAP_0402-0.22UF,16V,10%,X7R,A3A':
 ROOM='M_2';

SECTION_NUMBER 1
 '@BASEBOARD_FAB2_LIB.BASEBOARD_FAB2(SCH_1):PAGE185_I171@MSTR_DISCRETE.CAP(CHIPS)':
 C_PATH='@baseboard_fab2_lib.baseboard_fab2(sch_1):page185_i171@mstr_discrete.ca~
p(chips)',
 P_PATH='@baseboard_fab2_lib.baseboard_fab2(sch_1):page185_i171@mstr_discrete.ca~
p(chips)',
 PATH='I171',
 DRAWING='@BASEBOARD_FAB2_LIB.BASEBOARD_FAB2(SCH_1):PAGE185',
 TOLERANCE='10%',
 SEC_TYPE='0402',
 MATERIAL='X7R',
 BOM_COST='ST_FLASH',
 PHYS_PAGE='185',
 XY='(-4850,3950)',
 ROT='0',
 VER='2',
 VALUE='0.22UF',
 PACK_TYPE='0402',
 PART_NUMBER='A36096-155',
 LOCATION='C2T14',
 ROOM='M_2',
 SEC='1',
 CDS_LIB='mstr_discrete',
 CDS_PART_NAME='CAP_0402-0.22UF,16V,10%,X7R,A3A',
 VOLTAGE='16V',
 PRIM_FILE='./archive_libs/mstr_discrete/cap/chips/chips.prt';

PART_NAME
 C2T15 'CAP_A_0402V-0.1UF,16V,10%,X7R,A':
 ROOM='M_2';

SECTION_NUMBER 1
 '@BASEBOARD_FAB2_LIB.BASEBOARD_FAB2(SCH_1):PAGE185_I127@DEV_DISCRETE.CAP_A(CHIPS)':
 C_PATH='@baseboard_fab2_lib.baseboard_fab2(sch_1):page185_i127@dev_discrete.cap~
_a(chips)',
 P_PATH='@baseboard_fab2_lib.baseboard_fab2(sch_1):page185_i127@dev_discrete.cap~
_a(chips)',
 PATH='I127',
 DRAWING='@BASEBOARD_FAB2_LIB.BASEBOARD_FAB2(SCH_1):PAGE185',
 TOLERANCE='10%',
 SEC_TYPE='0402V',
 MATERIAL='X7R',
 BOM_COST='SD_FLASH',
 PHYS_PAGE='185',
 XY='(-2675,4575)',
 ROT='0',
 VER='1',
 VALUE='0.1UF',
 PACK_TYPE='0402V',
 PART_NUMBER='A36096-030',
 LOCATION='C2T15',
 ROOM='M_2',
 SEC='1',
 CDS_LIB='dev_discrete',
 CDS_PART_NAME='CAP_A_0402V-0.1UF,16V,10%,X7R,A',
 VOLTAGE='16V',
 PRIM_FILE='./archive_libs/discrete/cap_a/chips/chips.prt';

PART_NAME
 C2T16 'CAP_A_0402V-0.1UF,16V,10%,X7R,A':
 ROOM='M_2';

SECTION_NUMBER 1
 '@BASEBOARD_FAB2_LIB.BASEBOARD_FAB2(SCH_1):PAGE185_I126@DEV_DISCRETE.CAP_A(CHIPS)':
 C_PATH='@baseboard_fab2_lib.baseboard_fab2(sch_1):page185_i126@dev_discrete.cap~
_a(chips)',
 P_PATH='@baseboard_fab2_lib.baseboard_fab2(sch_1):page185_i126@dev_discrete.cap~
_a(chips)',
 PATH='I126',
 DRAWING='@BASEBOARD_FAB2_LIB.BASEBOARD_FAB2(SCH_1):PAGE185',
 TOLERANCE='10%',
 SEC_TYPE='0402V',
 MATERIAL='X7R',
 BOM_COST='SD_FLASH',
 PHYS_PAGE='185',
 XY='(-2425,4575)',
 ROT='0',
 VER='1',
 VALUE='0.1UF',
 PACK_TYPE='0402V',
 PART_NUMBER='A36096-030',
 LOCATION='C2T16',
 ROOM='M_2',
 SEC='1',
 CDS_LIB='dev_discrete',
 CDS_PART_NAME='CAP_A_0402V-0.1UF,16V,10%,X7R,A',
 VOLTAGE='16V',
 PRIM_FILE='./archive_libs/discrete/cap_a/chips/chips.prt';

PART_NAME
 C2T17 'CAP_A_0402V-0.1UF,16V,10%,X7R,A':
 ROOM='SYS_CLOCK';

SECTION_NUMBER 1
 '@BASEBOARD_FAB2_LIB.BASEBOARD_FAB2(SCH_1):PAGE101_I112@DEV_DISCRETE.CAP_A(CHIPS)':
 C_PATH='@baseboard_fab2_lib.baseboard_fab2(sch_1):page101_i112@dev_discrete.cap~
_a(chips)',
 P_PATH='@baseboard_fab2_lib.baseboard_fab2(sch_1):page101_i112@dev_discrete.cap~
_a(chips)',
 PATH='I112',
 DRAWING='@BASEBOARD_FAB2_LIB.BASEBOARD_FAB2(SCH_1):PAGE101',
 TOLERANCE='10%',
 MATERIAL='X7R',
 BOM_COST='SM_CONTROLLER',
 PHYS_PAGE='101',
 XY='(-7600,3975)',
 ROT='0',
 VER='1',
 VALUE='0.1UF',
 PACK_TYPE='0402V',
 PART_NUMBER='A36096-030',
 LOCATION='C2T17',
 ROOM='SYS_CLOCK',
 CDS_LIB='dev_discrete',
 CDS_PART_NAME='CAP_A_0402V-0.1UF,16V,10%,X7R,A',
 VOLTAGE='16V',
 PRIM_FILE='./archive_libs/discrete/cap_a/chips/chips.prt';

PART_NAME
 C2T18 'CAP_A_0402V-0.01UF,25V,10%,X7RA':
 ROOM='SYS_CLOCK';

SECTION_NUMBER 1
 '@BASEBOARD_FAB2_LIB.BASEBOARD_FAB2(SCH_1):PAGE101_I104@DEV_DISCRETE.CAP_A(CHIPS)':
 C_PATH='@baseboard_fab2_lib.baseboard_fab2(sch_1):page101_i104@dev_discrete.cap~
_a(chips)',
 P_PATH='@baseboard_fab2_lib.baseboard_fab2(sch_1):page101_i104@dev_discrete.cap~
_a(chips)',
 PATH='I104',
 DRAWING='@BASEBOARD_FAB2_LIB.BASEBOARD_FAB2(SCH_1):PAGE101',
 TOLERANCE='10%',
 MATERIAL='X7R',
 BOM_COST='SM_CONTROLLER',
 PHYS_PAGE='101',
 XY='(-5550,3975)',
 ROT='0',
 VER='1',
 VALUE='0.01UF',
 PACK_TYPE='0402V',
 PART_NUMBER='A36096-045',
 LOCATION='C2T18',
 ROOM='SYS_CLOCK',
 CDS_LIB='dev_discrete',
 CDS_PART_NAME='CAP_A_0402V-0.01UF,25V,10%,X7RA',
 VOLTAGE='25V',
 PRIM_FILE='./archive_libs/discrete/cap_a/chips/chips.prt';

PART_NAME
 C2T19 'CAP_A_0402V-1.0UF,6.3V,10%,X6SA':
 ROOM='SYS_CLOCK';

SECTION_NUMBER 1
 '@BASEBOARD_FAB2_LIB.BASEBOARD_FAB2(SCH_1):PAGE101_I106@DEV_DISCRETE.CAP_A(CHIPS)':
 C_PATH='@baseboard_fab2_lib.baseboard_fab2(sch_1):page101_i106@dev_discrete.cap~
_a(chips)',
 P_PATH='@baseboard_fab2_lib.baseboard_fab2(sch_1):page101_i106@dev_discrete.cap~
_a(chips)',
 PATH='I106',
 DRAWING='@BASEBOARD_FAB2_LIB.BASEBOARD_FAB2(SCH_1):PAGE101',
 TOLERANCE='10%',
 MATERIAL='X6S',
 BOM_COST='SM_CONTROLLER',
 PHYS_PAGE='101',
 XY='(-5150,3975)',
 ROT='0',
 VER='1',
 VALUE='1.0UF',
 PACK_TYPE='0402V',
 PART_NUMBER='D97712-004',
 LOCATION='C2T19',
 ROOM='SYS_CLOCK',
 CDS_LIB='dev_discrete',
 CDS_PART_NAME='CAP_A_0402V-1.0UF,6.3V,10%,X6SA',
 VOLTAGE='6.3V',
 PRIM_FILE='./archive_libs/discrete/cap_a/chips/chips.prt';

PART_NAME
 C2T20 'CAP_0402-0.22UF,16V,10%,X7R,A3A':
 ROOM='M_2';

SECTION_NUMBER 1
 '@BASEBOARD_FAB2_LIB.BASEBOARD_FAB2(SCH_1):PAGE185_I179@MSTR_DISCRETE.CAP(CHIPS)':
 C_PATH='@baseboard_fab2_lib.baseboard_fab2(sch_1):page185_i179@mstr_discrete.ca~
p(chips)',
 P_PATH='@baseboard_fab2_lib.baseboard_fab2(sch_1):page185_i179@mstr_discrete.ca~
p(chips)',
 PATH='I179',
 DRAWING='@BASEBOARD_FAB2_LIB.BASEBOARD_FAB2(SCH_1):PAGE185',
 TOLERANCE='10%',
 SEC_TYPE='0402',
 MATERIAL='X7R',
 BOM_COST='ST_FLASH',
 PHYS_PAGE='185',
 XY='(-4850,4200)',
 ROT='0',
 VER='2',
 VALUE='0.22UF',
 PACK_TYPE='0402',
 PART_NUMBER='A36096-155',
 LOCATION='C2T20',
 ROOM='M_2',
 SEC='1',
 CDS_LIB='mstr_discrete',
 CDS_PART_NAME='CAP_0402-0.22UF,16V,10%,X7R,A3A',
 VOLTAGE='16V',
 PRIM_FILE='./archive_libs/mstr_discrete/cap/chips/chips.prt';

PART_NAME
 C2T21 'CAP_A_0402V-0.1UF,16V,10%,X7R,A':
 ROOM='M_2';

SECTION_NUMBER 1
 '@BASEBOARD_FAB2_LIB.BASEBOARD_FAB2(SCH_1):PAGE185_I124@DEV_DISCRETE.CAP_A(CHIPS)':
 C_PATH='@baseboard_fab2_lib.baseboard_fab2(sch_1):page185_i124@dev_discrete.cap~
_a(chips)',
 P_PATH='@baseboard_fab2_lib.baseboard_fab2(sch_1):page185_i124@dev_discrete.cap~
_a(chips)',
 PATH='I124',
 DRAWING='@BASEBOARD_FAB2_LIB.BASEBOARD_FAB2(SCH_1):PAGE185',
 TOLERANCE='10%',
 SEC_TYPE='0402V',
 MATERIAL='X7R',
 BOM_COST='SD_FLASH',
 PHYS_PAGE='185',
 XY='(-3750,4575)',
 ROT='0',
 VER='1',
 VALUE='0.1UF',
 PACK_TYPE='0402V',
 PART_NUMBER='A36096-030',
 LOCATION='C2T21',
 ROOM='M_2',
 SEC='1',
 CDS_LIB='dev_discrete',
 CDS_PART_NAME='CAP_A_0402V-0.1UF,16V,10%,X7R,A',
 VOLTAGE='16V',
 PRIM_FILE='./archive_libs/discrete/cap_a/chips/chips.prt';

PART_NAME
 C2T22 'CAP_0805-10UF,16V,10%,X6S,C953A':
 ROOM='SYS_CLOCK';

SECTION_NUMBER 1
 '@BASEBOARD_FAB2_LIB.BASEBOARD_FAB2(SCH_1):PAGE101_I113@MSTR_DISCRETE.CAP(CHIPS)':
 C_PATH='@baseboard_fab2_lib.baseboard_fab2(sch_1):page101_i113@mstr_discrete.ca~
p(chips)',
 P_PATH='@baseboard_fab2_lib.baseboard_fab2(sch_1):page101_i113@mstr_discrete.ca~
p(chips)',
 PATH='I113',
 DRAWING='@BASEBOARD_FAB2_LIB.BASEBOARD_FAB2(SCH_1):PAGE101',
 TOLERANCE='10%',
 SEC_TYPE='0805',
 MATERIAL='X6S',
 BOM_COST='SM_CONTROLLER',
 PHYS_PAGE='101',
 XY='(-7900,3975)',
 ROT='0',
 VER='1',
 VALUE='10UF',
 PACK_TYPE='0805',
 PART_NUMBER='C95333-007',
 LOCATION='C2T22',
 ROOM='SYS_CLOCK',
 SEC='1',
 CDS_LIB='mstr_discrete',
 CDS_PART_NAME='CAP_0805-10UF,16V,10%,X6S,C953A',
 VOLTAGE='16V',
 PRIM_FILE='./archive_libs/mstr_discrete/cap/chips/chips.prt';

PART_NAME
 C2T23 'CAP_0402-0.22UF,16V,10%,X7R,A3A':
 ROOM='M_2';

SECTION_NUMBER 1
 '@BASEBOARD_FAB2_LIB.BASEBOARD_FAB2(SCH_1):PAGE185_I180@MSTR_DISCRETE.CAP(CHIPS)':
 C_PATH='@baseboard_fab2_lib.baseboard_fab2(sch_1):page185_i180@mstr_discrete.ca~
p(chips)',
 P_PATH='@baseboard_fab2_lib.baseboard_fab2(sch_1):page185_i180@mstr_discrete.ca~
p(chips)',
 PATH='I180',
 DRAWING='@BASEBOARD_FAB2_LIB.BASEBOARD_FAB2(SCH_1):PAGE185',
 TOLERANCE='10%',
 SEC_TYPE='0402',
 MATERIAL='X7R',
 BOM_COST='ST_FLASH',
 PHYS_PAGE='185',
 XY='(-4850,4250)',
 ROT='0',
 VER='2',
 VALUE='0.22UF',
 PACK_TYPE='0402',
 PART_NUMBER='A36096-155',
 LOCATION='C2T23',
 ROOM='M_2',
 SEC='1',
 CDS_LIB='mstr_discrete',
 CDS_PART_NAME='CAP_0402-0.22UF,16V,10%,X7R,A3A',
 VOLTAGE='16V',
 PRIM_FILE='./archive_libs/mstr_discrete/cap/chips/chips.prt';

PART_NAME
 C2T24 'CAP_A_0402V-0.1UF,16V,10%,X7R,A':
 ROOM='M_2';

SECTION_NUMBER 1
 '@BASEBOARD_FAB2_LIB.BASEBOARD_FAB2(SCH_1):PAGE185_I129@DEV_DISCRETE.CAP_A(CHIPS)':
 C_PATH='@baseboard_fab2_lib.baseboard_fab2(sch_1):page185_i129@dev_discrete.cap~
_a(chips)',
 P_PATH='@baseboard_fab2_lib.baseboard_fab2(sch_1):page185_i129@dev_discrete.cap~
_a(chips)',
 PATH='I129',
 DRAWING='@BASEBOARD_FAB2_LIB.BASEBOARD_FAB2(SCH_1):PAGE185',
 TOLERANCE='10%',
 SEC_TYPE='0402V',
 MATERIAL='X7R',
 BOM_COST='SD_FLASH',
 PHYS_PAGE='185',
 XY='(-2925,4575)',
 ROT='0',
 VER='1',
 VALUE='0.1UF',
 PACK_TYPE='0402V',
 PART_NUMBER='A36096-030',
 LOCATION='C2T24',
 ROOM='M_2',
 SEC='1',
 CDS_LIB='dev_discrete',
 CDS_PART_NAME='CAP_A_0402V-0.1UF,16V,10%,X7R,A',
 VOLTAGE='16V',
 PRIM_FILE='./archive_libs/discrete/cap_a/chips/chips.prt';

PART_NAME
 C2T25 'CAP_A_0402V-0.1UF,16V,10%,X7R,A':
 ROOM='SYS_CLOCK';

SECTION_NUMBER 1
 '@BASEBOARD_FAB2_LIB.BASEBOARD_FAB2(SCH_1):PAGE101_I111@DEV_DISCRETE.CAP_A(CHIPS)':
 C_PATH='@baseboard_fab2_lib.baseboard_fab2(sch_1):page101_i111@dev_discrete.cap~
_a(chips)',
 P_PATH='@baseboard_fab2_lib.baseboard_fab2(sch_1):page101_i111@dev_discrete.cap~
_a(chips)',
 PATH='I111',
 DRAWING='@BASEBOARD_FAB2_LIB.BASEBOARD_FAB2(SCH_1):PAGE101',
 TOLERANCE='10%',
 MATERIAL='X7R',
 BOM_COST='SM_CONTROLLER',
 PHYS_PAGE='101',
 XY='(-7300,3975)',
 ROT='0',
 VER='1',
 VALUE='0.1UF',
 PACK_TYPE='0402V',
 PART_NUMBER='A36096-030',
 LOCATION='C2T25',
 ROOM='SYS_CLOCK',
 CDS_LIB='dev_discrete',
 CDS_PART_NAME='CAP_A_0402V-0.1UF,16V,10%,X7R,A',
 VOLTAGE='16V',
 PRIM_FILE='./archive_libs/discrete/cap_a/chips/chips.prt';

PART_NAME
 C2T26 'CAP_A_0402V-0.1UF,16V,10%,X7R,A':
 ROOM='M_2';

SECTION_NUMBER 1
 '@BASEBOARD_FAB2_LIB.BASEBOARD_FAB2(SCH_1):PAGE185_I123@DEV_DISCRETE.CAP_A(CHIPS)':
 C_PATH='@baseboard_fab2_lib.baseboard_fab2(sch_1):page185_i123@dev_discrete.cap~
_a(chips)',
 P_PATH='@baseboard_fab2_lib.baseboard_fab2(sch_1):page185_i123@dev_discrete.cap~
_a(chips)',
 PATH='I123',
 DRAWING='@BASEBOARD_FAB2_LIB.BASEBOARD_FAB2(SCH_1):PAGE185',
 TOLERANCE='10%',
 SEC_TYPE='0402V',
 MATERIAL='X7R',
 BOM_COST='SD_FLASH',
 PHYS_PAGE='185',
 XY='(-4000,4575)',
 ROT='0',
 VER='1',
 VALUE='0.1UF',
 PACK_TYPE='0402V',
 PART_NUMBER='A36096-030',
 LOCATION='C2T26',
 ROOM='M_2',
 SEC='1',
 CDS_LIB='dev_discrete',
 CDS_PART_NAME='CAP_A_0402V-0.1UF,16V,10%,X7R,A',
 VOLTAGE='16V',
 PRIM_FILE='./archive_libs/discrete/cap_a/chips/chips.prt';

PART_NAME
 C2T27 'CAP_A_0402V-0.01UF,25V,10%,X7RA':
 ROOM='SYS_CLOCK';

SECTION_NUMBER 1
 '@BASEBOARD_FAB2_LIB.BASEBOARD_FAB2(SCH_1):PAGE101_I90@DEV_DISCRETE.CAP_A(CHIPS)':
 C_PATH='@baseboard_fab2_lib.baseboard_fab2(sch_1):page101_i90@dev_discrete.cap_~
a(chips)',
 P_PATH='@baseboard_fab2_lib.baseboard_fab2(sch_1):page101_i90@dev_discrete.cap_~
a(chips)',
 PATH='I90',
 DRAWING='@BASEBOARD_FAB2_LIB.BASEBOARD_FAB2(SCH_1):PAGE101',
 TOLERANCE='10%',
 MATERIAL='X7R',
 BOM_COST='SM_CONTROLLER',
 PHYS_PAGE='101',
 XY='(-4050,3925)',
 ROT='0',
 VER='1',
 VALUE='0.01UF',
 PACK_TYPE='0402V',
 PART_NUMBER='A36096-045',
 LOCATION='C2T27',
 ROOM='SYS_CLOCK',
 CDS_LIB='dev_discrete',
 CDS_PART_NAME='CAP_A_0402V-0.01UF,25V,10%,X7RA',
 VOLTAGE='25V',
 PRIM_FILE='./archive_libs/discrete/cap_a/chips/chips.prt';

PART_NAME
 C2T28 'CAP_A_0402V-1.0UF,6.3V,10%,X6SA':
 ROOM='SYS_CLOCK';

SECTION_NUMBER 1
 '@BASEBOARD_FAB2_LIB.BASEBOARD_FAB2(SCH_1):PAGE101_I116@DEV_DISCRETE.CAP_A(CHIPS)':
 C_PATH='@baseboard_fab2_lib.baseboard_fab2(sch_1):page101_i116@dev_discrete.cap~
_a(chips)',
 P_PATH='@baseboard_fab2_lib.baseboard_fab2(sch_1):page101_i116@dev_discrete.cap~
_a(chips)',
 PATH='I116',
 DRAWING='@BASEBOARD_FAB2_LIB.BASEBOARD_FAB2(SCH_1):PAGE101',
 TOLERANCE='10%',
 MATERIAL='X6S',
 BOM_COST='SM_CONTROLLER',
 PHYS_PAGE='101',
 XY='(-8475,3950)',
 ROT='0',
 VER='1',
 VALUE='1.0UF',
 PACK_TYPE='0402V',
 PART_NUMBER='D97712-004',
 LOCATION='C2T28',
 ROOM='SYS_CLOCK',
 CDS_LIB='dev_discrete',
 CDS_PART_NAME='CAP_A_0402V-1.0UF,6.3V,10%,X6SA',
 VOLTAGE='6.3V',
 PRIM_FILE='./archive_libs/discrete/cap_a/chips/chips.prt';

PART_NAME
 C2T29 'CAP_A_0402V-0.1UF,16V,10%,X7R,A':
 ROOM='M_2';

SECTION_NUMBER 1
 '@BASEBOARD_FAB2_LIB.BASEBOARD_FAB2(SCH_1):PAGE185_I120@DEV_DISCRETE.CAP_A(CHIPS)':
 C_PATH='@baseboard_fab2_lib.baseboard_fab2(sch_1):page185_i120@dev_discrete.cap~
_a(chips)',
 P_PATH='@baseboard_fab2_lib.baseboard_fab2(sch_1):page185_i120@dev_discrete.cap~
_a(chips)',
 PATH='I120',
 DRAWING='@BASEBOARD_FAB2_LIB.BASEBOARD_FAB2(SCH_1):PAGE185',
 TOLERANCE='10%',
 SEC_TYPE='0402V',
 MATERIAL='X7R',
 BOM_COST='SD_FLASH',
 PHYS_PAGE='185',
 XY='(-4250,4575)',
 ROT='0',
 VER='1',
 VALUE='0.1UF',
 PACK_TYPE='0402V',
 PART_NUMBER='A36096-030',
 LOCATION='C2T29',
 ROOM='M_2',
 SEC='1',
 CDS_LIB='dev_discrete',
 CDS_PART_NAME='CAP_A_0402V-0.1UF,16V,10%,X7R,A',
 VOLTAGE='16V',
 PRIM_FILE='./archive_libs/discrete/cap_a/chips/chips.prt';

PART_NAME
 C2T30 'CAP_A_0402V-0.1UF,16V,10%,X7R,A':
 ROOM='SYS_CLOCK';

SECTION_NUMBER 1
 '@BASEBOARD_FAB2_LIB.BASEBOARD_FAB2(SCH_1):PAGE101_I110@DEV_DISCRETE.CAP_A(CHIPS)':
 C_PATH='@baseboard_fab2_lib.baseboard_fab2(sch_1):page101_i110@dev_discrete.cap~
_a(chips)',
 P_PATH='@baseboard_fab2_lib.baseboard_fab2(sch_1):page101_i110@dev_discrete.cap~
_a(chips)',
 PATH='I110',
 DRAWING='@BASEBOARD_FAB2_LIB.BASEBOARD_FAB2(SCH_1):PAGE101',
 TOLERANCE='10%',
 MATERIAL='X7R',
 BOM_COST='SM_CONTROLLER',
 PHYS_PAGE='101',
 XY='(-6900,3975)',
 ROT='0',
 VER='1',
 VALUE='0.1UF',
 PACK_TYPE='0402V',
 PART_NUMBER='A36096-030',
 LOCATION='C2T30',
 ROOM='SYS_CLOCK',
 CDS_LIB='dev_discrete',
 CDS_PART_NAME='CAP_A_0402V-0.1UF,16V,10%,X7R,A',
 VOLTAGE='16V',
 PRIM_FILE='./archive_libs/discrete/cap_a/chips/chips.prt';

PART_NAME
 C2T31 'CAP_A_0402V-1.0UF,6.3V,10%,X6SA':
 ROOM='SYS_CLOCK';

SECTION_NUMBER 1
 '@BASEBOARD_FAB2_LIB.BASEBOARD_FAB2(SCH_1):PAGE101_I89@DEV_DISCRETE.CAP_A(CHIPS)':
 C_PATH='@baseboard_fab2_lib.baseboard_fab2(sch_1):page101_i89@dev_discrete.cap_~
a(chips)',
 P_PATH='@baseboard_fab2_lib.baseboard_fab2(sch_1):page101_i89@dev_discrete.cap_~
a(chips)',
 PATH='I89',
 DRAWING='@BASEBOARD_FAB2_LIB.BASEBOARD_FAB2(SCH_1):PAGE101',
 TOLERANCE='10%',
 MATERIAL='X6S',
 BOM_COST='SM_CONTROLLER',
 PHYS_PAGE='101',
 XY='(-3625,3925)',
 ROT='0',
 VER='1',
 VALUE='1.0UF',
 PACK_TYPE='0402V',
 PART_NUMBER='D97712-004',
 LOCATION='C2T31',
 ROOM='SYS_CLOCK',
 CDS_LIB='dev_discrete',
 CDS_PART_NAME='CAP_A_0402V-1.0UF,6.3V,10%,X6SA',
 VOLTAGE='6.3V',
 PRIM_FILE='./archive_libs/discrete/cap_a/chips/chips.prt';

PART_NAME
 C2T32 'CAP_A_0402V-0.1UF,16V,10%,X7R,A':
 ROOM='PROC_SIDEBAND';

SECTION_NUMBER 1
 '@BASEBOARD_FAB2_LIB.BASEBOARD_FAB2(SCH_1):PAGE93_I95@DEV_DISCRETE.CAP_A(CHIPS)':
 C_PATH='@baseboard_fab2_lib.baseboard_fab2(sch_1):page93_i95@dev_discrete.cap_a~
(chips)',
 P_PATH='@baseboard_fab2_lib.baseboard_fab2(sch_1):page93_i95@dev_discrete.cap_a~
(chips)',
 PATH='I95',
 DRAWING='@BASEBOARD_FAB2_LIB.BASEBOARD_FAB2(SCH_1):PAGE93',
 TOLERANCE='10%',
 SEC_TYPE='0402V',
 MATERIAL='X7R',
 BOM_COST='PROC',
 PHYS_PAGE='93',
 XY='(1950,600)',
 ROT='0',
 VER='1',
 VALUE='0.1UF',
 PACK_TYPE='0402V',
 PART_NUMBER='A36096-030',
 LOCATION='C2T32',
 ROOM='PROC_SIDEBAND',
 SEC='1',
 CDS_LIB='dev_discrete',
 CDS_PART_NAME='CAP_A_0402V-0.1UF,16V,10%,X7R,A',
 VOLTAGE='16V',
 PRIM_FILE='./archive_libs/discrete/cap_a/chips/chips.prt';

PART_NAME
 C2T33 'CAP_A_0402V-1.0UF,6.3V,10%,X6SA':
 ROOM='PROC_SIDEBAND';

SECTION_NUMBER 1
 '@BASEBOARD_FAB2_LIB.BASEBOARD_FAB2(SCH_1):PAGE93_I72@DEV_DISCRETE.CAP_A(CHIPS)':
 C_PATH='@baseboard_fab2_lib.baseboard_fab2(sch_1):page93_i72@dev_discrete.cap_a~
(chips)',
 P_PATH='@baseboard_fab2_lib.baseboard_fab2(sch_1):page93_i72@dev_discrete.cap_a~
(chips)',
 PATH='I72',
 DRAWING='@BASEBOARD_FAB2_LIB.BASEBOARD_FAB2(SCH_1):PAGE93',
 TOLERANCE='10%',
 SEC_TYPE='0402V',
 MATERIAL='X6S',
 BOM_COST='PROC',
 PHYS_PAGE='93',
 XY='(1150,3875)',
 ROT='0',
 VER='1',
 VALUE='1.0UF',
 PACK_TYPE='0402V',
 PART_NUMBER='D97712-004',
 LOCATION='C2T33',
 ROOM='PROC_SIDEBAND',
 SEC='1',
 CDS_LIB='dev_discrete',
 CDS_PART_NAME='CAP_A_0402V-1.0UF,6.3V,10%,X6SA',
 VOLTAGE='6.3V',
 PRIM_FILE='./archive_libs/discrete/cap_a/chips/chips.prt';

PART_NAME
 C2T34 'CAP_A_0402V-0.1UF,16V,10%,X7R,A':
 ROOM='SYS_CLOCK';

SECTION_NUMBER 1
 '@BASEBOARD_FAB2_LIB.BASEBOARD_FAB2(SCH_1):PAGE101_I109@DEV_DISCRETE.CAP_A(CHIPS)':
 C_PATH='@baseboard_fab2_lib.baseboard_fab2(sch_1):page101_i109@dev_discrete.cap~
_a(chips)',
 P_PATH='@baseboard_fab2_lib.baseboard_fab2(sch_1):page101_i109@dev_discrete.cap~
_a(chips)',
 PATH='I109',
 DRAWING='@BASEBOARD_FAB2_LIB.BASEBOARD_FAB2(SCH_1):PAGE101',
 TOLERANCE='10%',
 SEC_TYPE='0402V',
 MATERIAL='X7R',
 BOM_COST='SM_CONTROLLER',
 PHYS_PAGE='101',
 XY='(-6600,3975)',
 ROT='0',
 VER='1',
 VALUE='0.1UF',
 PACK_TYPE='0402V',
 PART_NUMBER='A36096-030',
 LOCATION='C2T34',
 ROOM='SYS_CLOCK',
 SEC='1',
 CDS_LIB='dev_discrete',
 CDS_PART_NAME='CAP_A_0402V-0.1UF,16V,10%,X7R,A',
 VOLTAGE='16V',
 PRIM_FILE='./archive_libs/discrete/cap_a/chips/chips.prt';

PART_NAME
 C2T35 'CAP_A_0402V-0.1UF,16V,10%,X7R,A':
 ROOM='BMC_MISC';

SECTION_NUMBER 1
 '@BASEBOARD_FAB2_LIB.BASEBOARD_FAB2(SCH_1):PAGE156_I273@DEV_DISCRETE.CAP_A(CHIPS)':
 C_PATH='@baseboard_fab2_lib.baseboard_fab2(sch_1):page156_i273@dev_discrete.cap~
_a(chips)',
 P_PATH='@baseboard_fab2_lib.baseboard_fab2(sch_1):page156_i273@dev_discrete.cap~
_a(chips)',
 PATH='I273',
 DRAWING='@BASEBOARD_FAB2_LIB.BASEBOARD_FAB2(SCH_1):PAGE156',
 TOLERANCE='10%',
 SEC_TYPE='0402V',
 MATERIAL='X7R',
 BOM_COST='SM_CONTROLLER',
 PHYS_PAGE='156',
 XY='(-3200,3450)',
 ROT='0',
 VER='1',
 VALUE='0.1UF',
 PACK_TYPE='0402V',
 PART_NUMBER='A36096-030',
 LOCATION='C2T35',
 ROOM='BMC_MISC',
 SEC='1',
 CDS_LIB='dev_discrete',
 CDS_PART_NAME='CAP_A_0402V-0.1UF,16V,10%,X7R,A',
 VOLTAGE='16V',
 PRIM_FILE='./archive_libs/discrete/cap_a/chips/chips.prt';

PART_NAME
 C2T36 'CAP_A_0402V-0.1UF,16V,10%,X7R,A':
 ROOM='P3V3_PWR_SWITCH';

SECTION_NUMBER 1
 '@BASEBOARD_FAB2_LIB.BASEBOARD_FAB2(SCH_1):PAGE198_I43@DEV_DISCRETE.CAP_A(CHIPS)':
 C_PATH='@baseboard_fab2_lib.baseboard_fab2(sch_1):page198_i43@dev_discrete.cap_~
a(chips)',
 P_PATH='@baseboard_fab2_lib.baseboard_fab2(sch_1):page198_i43@dev_discrete.cap_~
a(chips)',
 PATH='I43',
 DRAWING='@BASEBOARD_FAB2_LIB.BASEBOARD_FAB2(SCH_1):PAGE198',
 TOLERANCE='10%',
 SEC_TYPE='0402V',
 MATERIAL='X7R',
 BOM_COST='PWR_SWITCH',
 PHYS_PAGE='198',
 XY='(-5050,4275)',
 ROT='0',
 VER='1',
 VALUE='0.1UF',
 PACK_TYPE='0402V',
 PART_NUMBER='A36096-030',
 LOCATION='C2T36',
 ROOM='P3V3_PWR_SWITCH',
 SEC='1',
 CDS_LIB='dev_discrete',
 CDS_PART_NAME='CAP_A_0402V-0.1UF,16V,10%,X7R,A',
 VOLTAGE='16V',
 PRIM_FILE='./archive_libs/discrete/cap_a/chips/chips.prt';

PART_NAME
 C2T37 'CAP_A_0402V-0.01UF,25V,10%,X7RA':
 ROOM='SYS_CLOCK';

SECTION_NUMBER 1
 '@BASEBOARD_FAB2_LIB.BASEBOARD_FAB2(SCH_1):PAGE101_I99@DEV_DISCRETE.CAP_A(CHIPS)':
 C_PATH='@baseboard_fab2_lib.baseboard_fab2(sch_1):page101_i99@dev_discrete.cap_~
a(chips)',
 P_PATH='@baseboard_fab2_lib.baseboard_fab2(sch_1):page101_i99@dev_discrete.cap_~
a(chips)',
 PATH='I99',
 DRAWING='@BASEBOARD_FAB2_LIB.BASEBOARD_FAB2(SCH_1):PAGE101',
 TOLERANCE='10%',
 MATERIAL='X7R',
 BOM_COST='SM_CONTROLLER',
 PHYS_PAGE='101',
 XY='(-2625,4000)',
 ROT='0',
 VER='1',
 VALUE='0.01UF',
 PACK_TYPE='0402V',
 PART_NUMBER='A36096-045',
 LOCATION='C2T37',
 ROOM='SYS_CLOCK',
 CDS_LIB='dev_discrete',
 CDS_PART_NAME='CAP_A_0402V-0.01UF,25V,10%,X7RA',
 VOLTAGE='25V',
 PRIM_FILE='./archive_libs/discrete/cap_a/chips/chips.prt';

PART_NAME
 C2T38 'CAP_A_0402V-1.0UF,6.3V,10%,X6SA':
 ROOM='SYS_CLOCK';

SECTION_NUMBER 1
 '@BASEBOARD_FAB2_LIB.BASEBOARD_FAB2(SCH_1):PAGE101_I97@DEV_DISCRETE.CAP_A(CHIPS)':
 C_PATH='@baseboard_fab2_lib.baseboard_fab2(sch_1):page101_i97@dev_discrete.cap_~
a(chips)',
 P_PATH='@baseboard_fab2_lib.baseboard_fab2(sch_1):page101_i97@dev_discrete.cap_~
a(chips)',
 PATH='I97',
 DRAWING='@BASEBOARD_FAB2_LIB.BASEBOARD_FAB2(SCH_1):PAGE101',
 TOLERANCE='10%',
 MATERIAL='X6S',
 BOM_COST='SM_CONTROLLER',
 PHYS_PAGE='101',
 XY='(-2250,4000)',
 ROT='0',
 VER='1',
 VALUE='1.0UF',
 PACK_TYPE='0402V',
 PART_NUMBER='D97712-004',
 LOCATION='C2T38',
 ROOM='SYS_CLOCK',
 CDS_LIB='dev_discrete',
 CDS_PART_NAME='CAP_A_0402V-1.0UF,6.3V,10%,X6SA',
 VOLTAGE='6.3V',
 PRIM_FILE='./archive_libs/discrete/cap_a/chips/chips.prt';

PART_NAME
 C2U1 'CAP_0805-10UF,16V,10%,X6S,C953A':
 ROOM='P3V3_PWR_SWITCH';

SECTION_NUMBER 1
 '@BASEBOARD_FAB2_LIB.BASEBOARD_FAB2(SCH_1):PAGE198_I44@MSTR_DISCRETE.CAP(CHIPS)':
 C_PATH='@baseboard_fab2_lib.baseboard_fab2(sch_1):page198_i44@mstr_discrete.cap~
(chips)',
 P_PATH='@baseboard_fab2_lib.baseboard_fab2(sch_1):page198_i44@mstr_discrete.cap~
(chips)',
 PATH='I44',
 DRAWING='@BASEBOARD_FAB2_LIB.BASEBOARD_FAB2(SCH_1):PAGE198',
 TOLERANCE='10%',
 SEC_TYPE='0805',
 MATERIAL='X6S',
 PHYS_PAGE='198',
 XY='(-5375,4275)',
 ROT='0',
 VER='1',
 VALUE='10UF',
 PACK_TYPE='0805',
 PART_NUMBER='C95333-007',
 LOCATION='C2U1',
 ROOM='P3V3_PWR_SWITCH',
 SEC='1',
 CDS_LIB='mstr_discrete',
 CDS_PART_NAME='CAP_0805-10UF,16V,10%,X6S,C953A',
 VOLTAGE='16V',
 PRIM_FILE='./archive_libs/mstr_discrete/cap/chips/chips.prt';

PART_NAME
 C2U2 'CAP_0805-10UF,16V,10%,X6S,C953A':
 ROOM='P3V3_PWR_SWITCH';

SECTION_NUMBER 1
 '@BASEBOARD_FAB2_LIB.BASEBOARD_FAB2(SCH_1):PAGE198_I47@MSTR_DISCRETE.CAP(CHIPS)':
 C_PATH='@baseboard_fab2_lib.baseboard_fab2(sch_1):page198_i47@mstr_discrete.cap~
(chips)',
 P_PATH='@baseboard_fab2_lib.baseboard_fab2(sch_1):page198_i47@mstr_discrete.cap~
(chips)',
 PATH='I47',
 DRAWING='@BASEBOARD_FAB2_LIB.BASEBOARD_FAB2(SCH_1):PAGE198',
 TOLERANCE='10%',
 SEC_TYPE='0805',
 MATERIAL='X6S',
 PHYS_PAGE='198',
 XY='(-5000,3200)',
 ROT='0',
 VER='1',
 VALUE='10UF',
 PACK_TYPE='0805',
 PART_NUMBER='C95333-007',
 LOCATION='C2U2',
 ROOM='P3V3_PWR_SWITCH',
 SEC='1',
 CDS_LIB='mstr_discrete',
 CDS_PART_NAME='CAP_0805-10UF,16V,10%,X6S,C953A',
 VOLTAGE='16V',
 PRIM_FILE='./archive_libs/mstr_discrete/cap/chips/chips.prt';

PART_NAME
 C2U3 'CAP_0402-0.22UF,16V,10%,X7R,A3A':
 GROUP='PCIE_UPLINK';

SECTION_NUMBER 1
 '@BASEBOARD_FAB2_LIB.BASEBOARD_FAB2(SCH_1):PAGE107_I272@MSTR_DISCRETE.CAP(CHIPS)':
 C_PATH='@baseboard_fab2_lib.baseboard_fab2(sch_1):page107_i272@mstr_discrete.ca~
p(chips)',
 P_PATH='@baseboard_fab2_lib.baseboard_fab2(sch_1):page107_i272@mstr_discrete.ca~
p(chips)',
 PATH='I272',
 DRAWING='@BASEBOARD_FAB2_LIB.BASEBOARD_FAB2(SCH_1):PAGE107',
 TOLERANCE='10%',
 SEC_TYPE='0402',
 MATERIAL='X7R',
 PHYS_PAGE='107',
 XY='(-1900,875)',
 ROT='2',
 VER='1',
 VALUE='0.22UF',
 PACK_TYPE='0402',
 PART_NUMBER='A36096-155',
 LOCATION='C2U3',
 GROUP='PCIE_UPLINK',
 SEC='1',
 CDS_LIB='mstr_discrete',
 CDS_PART_NAME='CAP_0402-0.22UF,16V,10%,X7R,A3A',
 VOLTAGE='16V',
 PRIM_FILE='./archive_libs/mstr_discrete/cap/chips/chips.prt';

PART_NAME
 C2U4 'CAP_0402-0.22UF,16V,10%,X7R,A3A':
 GROUP='PCIE_UPLINK';

SECTION_NUMBER 1
 '@BASEBOARD_FAB2_LIB.BASEBOARD_FAB2(SCH_1):PAGE107_I257@MSTR_DISCRETE.CAP(CHIPS)':
 C_PATH='@baseboard_fab2_lib.baseboard_fab2(sch_1):page107_i257@mstr_discrete.ca~
p(chips)',
 P_PATH='@baseboard_fab2_lib.baseboard_fab2(sch_1):page107_i257@mstr_discrete.ca~
p(chips)',
 PATH='I257',
 DRAWING='@BASEBOARD_FAB2_LIB.BASEBOARD_FAB2(SCH_1):PAGE107',
 TOLERANCE='10%',
 SEC_TYPE='0402',
 MATERIAL='X7R',
 PHYS_PAGE='107',
 XY='(-1950,1875)',
 ROT='2',
 VER='1',
 VALUE='0.22UF',
 PACK_TYPE='0402',
 PART_NUMBER='A36096-155',
 LOCATION='C2U4',
 GROUP='PCIE_UPLINK',
 SEC='1',
 CDS_LIB='mstr_discrete',
 CDS_PART_NAME='CAP_0402-0.22UF,16V,10%,X7R,A3A',
 VOLTAGE='16V',
 PRIM_FILE='./archive_libs/mstr_discrete/cap/chips/chips.prt';

PART_NAME
 C2U5 'CAP_0402-0.22UF,16V,10%,X7R,A3A':
 GROUP='PCIE_UPLINK';

SECTION_NUMBER 1
 '@BASEBOARD_FAB2_LIB.BASEBOARD_FAB2(SCH_1):PAGE107_I274@MSTR_DISCRETE.CAP(CHIPS)':
 C_PATH='@baseboard_fab2_lib.baseboard_fab2(sch_1):page107_i274@mstr_discrete.ca~
p(chips)',
 P_PATH='@baseboard_fab2_lib.baseboard_fab2(sch_1):page107_i274@mstr_discrete.ca~
p(chips)',
 PATH='I274',
 DRAWING='@BASEBOARD_FAB2_LIB.BASEBOARD_FAB2(SCH_1):PAGE107',
 TOLERANCE='10%',
 SEC_TYPE='0402',
 MATERIAL='X7R',
 PHYS_PAGE='107',
 XY='(-2100,525)',
 ROT='2',
 VER='1',
 VALUE='0.22UF',
 PACK_TYPE='0402',
 PART_NUMBER='A36096-155',
 LOCATION='C2U5',
 GROUP='PCIE_UPLINK',
 SEC='1',
 CDS_LIB='mstr_discrete',
 CDS_PART_NAME='CAP_0402-0.22UF,16V,10%,X7R,A3A',
 VOLTAGE='16V',
 PRIM_FILE='./archive_libs/mstr_discrete/cap/chips/chips.prt';

PART_NAME
 C2U6 'CAP_0402-0.22UF,16V,10%,X7R,A3A':
 GROUP='PCIE_UPLINK';

SECTION_NUMBER 1
 '@BASEBOARD_FAB2_LIB.BASEBOARD_FAB2(SCH_1):PAGE107_I260@MSTR_DISCRETE.CAP(CHIPS)':
 C_PATH='@baseboard_fab2_lib.baseboard_fab2(sch_1):page107_i260@mstr_discrete.ca~
p(chips)',
 P_PATH='@baseboard_fab2_lib.baseboard_fab2(sch_1):page107_i260@mstr_discrete.ca~
p(chips)',
 PATH='I260',
 DRAWING='@BASEBOARD_FAB2_LIB.BASEBOARD_FAB2(SCH_1):PAGE107',
 TOLERANCE='10%',
 SEC_TYPE='0402',
 MATERIAL='X7R',
 PHYS_PAGE='107',
 XY='(-2150,1525)',
 ROT='2',
 VER='1',
 VALUE='0.22UF',
 PACK_TYPE='0402',
 PART_NUMBER='A36096-155',
 LOCATION='C2U6',
 GROUP='PCIE_UPLINK',
 SEC='1',
 CDS_LIB='mstr_discrete',
 CDS_PART_NAME='CAP_0402-0.22UF,16V,10%,X7R,A3A',
 VOLTAGE='16V',
 PRIM_FILE='./archive_libs/mstr_discrete/cap/chips/chips.prt';

PART_NAME
 C2U7 'CAP_0402-0.22UF,16V,10%,X7R,A3A':
 GROUP='PCIE_UPLINK';

SECTION_NUMBER 1
 '@BASEBOARD_FAB2_LIB.BASEBOARD_FAB2(SCH_1):PAGE107_I277@MSTR_DISCRETE.CAP(CHIPS)':
 C_PATH='@baseboard_fab2_lib.baseboard_fab2(sch_1):page107_i277@mstr_discrete.ca~
p(chips)',
 P_PATH='@baseboard_fab2_lib.baseboard_fab2(sch_1):page107_i277@mstr_discrete.ca~
p(chips)',
 PATH='I277',
 DRAWING='@BASEBOARD_FAB2_LIB.BASEBOARD_FAB2(SCH_1):PAGE107',
 TOLERANCE='10%',
 SEC_TYPE='0402',
 MATERIAL='X7R',
 PHYS_PAGE='107',
 XY='(-2300,875)',
 ROT='2',
 VER='1',
 VALUE='0.22UF',
 PACK_TYPE='0402',
 PART_NUMBER='A36096-155',
 LOCATION='C2U7',
 GROUP='PCIE_UPLINK',
 SEC='1',
 CDS_LIB='mstr_discrete',
 CDS_PART_NAME='CAP_0402-0.22UF,16V,10%,X7R,A3A',
 VOLTAGE='16V',
 PRIM_FILE='./archive_libs/mstr_discrete/cap/chips/chips.prt';

PART_NAME
 C2U8 'CAP_0402-0.22UF,16V,10%,X7R,A3A':
 GROUP='PCIE_UPLINK';

SECTION_NUMBER 1
 '@BASEBOARD_FAB2_LIB.BASEBOARD_FAB2(SCH_1):PAGE107_I264@MSTR_DISCRETE.CAP(CHIPS)':
 C_PATH='@baseboard_fab2_lib.baseboard_fab2(sch_1):page107_i264@mstr_discrete.ca~
p(chips)',
 P_PATH='@baseboard_fab2_lib.baseboard_fab2(sch_1):page107_i264@mstr_discrete.ca~
p(chips)',
 PATH='I264',
 DRAWING='@BASEBOARD_FAB2_LIB.BASEBOARD_FAB2(SCH_1):PAGE107',
 TOLERANCE='10%',
 SEC_TYPE='0402',
 MATERIAL='X7R',
 PHYS_PAGE='107',
 XY='(-2350,1875)',
 ROT='2',
 VER='1',
 VALUE='0.22UF',
 PACK_TYPE='0402',
 PART_NUMBER='A36096-155',
 LOCATION='C2U8',
 GROUP='PCIE_UPLINK',
 SEC='1',
 CDS_LIB='mstr_discrete',
 CDS_PART_NAME='CAP_0402-0.22UF,16V,10%,X7R,A3A',
 VOLTAGE='16V',
 PRIM_FILE='./archive_libs/mstr_discrete/cap/chips/chips.prt';

PART_NAME
 C2U9 'CAP_0402-0.22UF,16V,10%,X7R,A3A':
 GROUP='PCIE_UPLINK';

SECTION_NUMBER 1
 '@BASEBOARD_FAB2_LIB.BASEBOARD_FAB2(SCH_1):PAGE107_I279@MSTR_DISCRETE.CAP(CHIPS)':
 C_PATH='@baseboard_fab2_lib.baseboard_fab2(sch_1):page107_i279@mstr_discrete.ca~
p(chips)',
 P_PATH='@baseboard_fab2_lib.baseboard_fab2(sch_1):page107_i279@mstr_discrete.ca~
p(chips)',
 PATH='I279',
 DRAWING='@BASEBOARD_FAB2_LIB.BASEBOARD_FAB2(SCH_1):PAGE107',
 TOLERANCE='10%',
 SEC_TYPE='0402',
 MATERIAL='X7R',
 PHYS_PAGE='107',
 XY='(-2500,525)',
 ROT='2',
 VER='1',
 VALUE='0.22UF',
 PACK_TYPE='0402',
 PART_NUMBER='A36096-155',
 LOCATION='C2U9',
 GROUP='PCIE_UPLINK',
 SEC='1',
 CDS_LIB='mstr_discrete',
 CDS_PART_NAME='CAP_0402-0.22UF,16V,10%,X7R,A3A',
 VOLTAGE='16V',
 PRIM_FILE='./archive_libs/mstr_discrete/cap/chips/chips.prt';

PART_NAME
 C2U10 'CAP_0402-0.22UF,16V,10%,X7R,A3A':
 GROUP='PCIE_UPLINK';

SECTION_NUMBER 1
 '@BASEBOARD_FAB2_LIB.BASEBOARD_FAB2(SCH_1):PAGE107_I267@MSTR_DISCRETE.CAP(CHIPS)':
 C_PATH='@baseboard_fab2_lib.baseboard_fab2(sch_1):page107_i267@mstr_discrete.ca~
p(chips)',
 P_PATH='@baseboard_fab2_lib.baseboard_fab2(sch_1):page107_i267@mstr_discrete.ca~
p(chips)',
 PATH='I267',
 DRAWING='@BASEBOARD_FAB2_LIB.BASEBOARD_FAB2(SCH_1):PAGE107',
 TOLERANCE='10%',
 SEC_TYPE='0402',
 MATERIAL='X7R',
 PHYS_PAGE='107',
 XY='(-2550,1525)',
 ROT='2',
 VER='1',
 VALUE='0.22UF',
 PACK_TYPE='0402',
 PART_NUMBER='A36096-155',
 LOCATION='C2U10',
 GROUP='PCIE_UPLINK',
 SEC='1',
 CDS_LIB='mstr_discrete',
 CDS_PART_NAME='CAP_0402-0.22UF,16V,10%,X7R,A3A',
 VOLTAGE='16V',
 PRIM_FILE='./archive_libs/mstr_discrete/cap/chips/chips.prt';

PART_NAME
 C2U11 'CAP_0402-0.22UF,16V,10%,X7R,A3A':
 GROUP='PCIE_UPLINK';

SECTION_NUMBER 1
 '@BASEBOARD_FAB2_LIB.BASEBOARD_FAB2(SCH_1):PAGE107_I278@MSTR_DISCRETE.CAP(CHIPS)':
 C_PATH='@baseboard_fab2_lib.baseboard_fab2(sch_1):page107_i278@mstr_discrete.ca~
p(chips)',
 P_PATH='@baseboard_fab2_lib.baseboard_fab2(sch_1):page107_i278@mstr_discrete.ca~
p(chips)',
 PATH='I278',
 DRAWING='@BASEBOARD_FAB2_LIB.BASEBOARD_FAB2(SCH_1):PAGE107',
 TOLERANCE='10%',
 SEC_TYPE='0402',
 MATERIAL='X7R',
 PHYS_PAGE='107',
 XY='(-2700,875)',
 ROT='2',
 VER='1',
 VALUE='0.22UF',
 PACK_TYPE='0402',
 PART_NUMBER='A36096-155',
 LOCATION='C2U11',
 GROUP='PCIE_UPLINK',
 SEC='1',
 CDS_LIB='mstr_discrete',
 CDS_PART_NAME='CAP_0402-0.22UF,16V,10%,X7R,A3A',
 VOLTAGE='16V',
 PRIM_FILE='./archive_libs/mstr_discrete/cap/chips/chips.prt';

PART_NAME
 C2U12 'CAP_0402-0.22UF,16V,10%,X7R,A3A':
 GROUP='PCIE_UPLINK';

SECTION_NUMBER 1
 '@BASEBOARD_FAB2_LIB.BASEBOARD_FAB2(SCH_1):PAGE107_I265@MSTR_DISCRETE.CAP(CHIPS)':
 C_PATH='@baseboard_fab2_lib.baseboard_fab2(sch_1):page107_i265@mstr_discrete.ca~
p(chips)',
 P_PATH='@baseboard_fab2_lib.baseboard_fab2(sch_1):page107_i265@mstr_discrete.ca~
p(chips)',
 PATH='I265',
 DRAWING='@BASEBOARD_FAB2_LIB.BASEBOARD_FAB2(SCH_1):PAGE107',
 TOLERANCE='10%',
 SEC_TYPE='0402',
 MATERIAL='X7R',
 PHYS_PAGE='107',
 XY='(-2750,1875)',
 ROT='2',
 VER='1',
 VALUE='0.22UF',
 PACK_TYPE='0402',
 PART_NUMBER='A36096-155',
 LOCATION='C2U12',
 GROUP='PCIE_UPLINK',
 SEC='1',
 CDS_LIB='mstr_discrete',
 CDS_PART_NAME='CAP_0402-0.22UF,16V,10%,X7R,A3A',
 VOLTAGE='16V',
 PRIM_FILE='./archive_libs/mstr_discrete/cap/chips/chips.prt';

PART_NAME
 C2U13 'CAP_0402-0.22UF,16V,10%,X7R,A3A':
 GROUP='PCIE_UPLINK';

SECTION_NUMBER 1
 '@BASEBOARD_FAB2_LIB.BASEBOARD_FAB2(SCH_1):PAGE107_I297@MSTR_DISCRETE.CAP(CHIPS)':
 C_PATH='@baseboard_fab2_lib.baseboard_fab2(sch_1):page107_i297@mstr_discrete.ca~
p(chips)',
 P_PATH='@baseboard_fab2_lib.baseboard_fab2(sch_1):page107_i297@mstr_discrete.ca~
p(chips)',
 PATH='I297',
 DRAWING='@BASEBOARD_FAB2_LIB.BASEBOARD_FAB2(SCH_1):PAGE107',
 TOLERANCE='10%',
 SEC_TYPE='0402',
 MATERIAL='X7R',
 PHYS_PAGE='107',
 XY='(-2900,525)',
 ROT='2',
 VER='1',
 VALUE='0.22UF',
 PACK_TYPE='0402',
 PART_NUMBER='A36096-155',
 LOCATION='C2U13',
 GROUP='PCIE_UPLINK',
 SEC='1',
 CDS_LIB='mstr_discrete',
 CDS_PART_NAME='CAP_0402-0.22UF,16V,10%,X7R,A3A',
 VOLTAGE='16V',
 PRIM_FILE='./archive_libs/mstr_discrete/cap/chips/chips.prt';

PART_NAME
 C2U14 'CAP_0402-0.22UF,16V,10%,X7R,A3A':
 GROUP='PCIE_UPLINK';

SECTION_NUMBER 1
 '@BASEBOARD_FAB2_LIB.BASEBOARD_FAB2(SCH_1):PAGE107_I287@MSTR_DISCRETE.CAP(CHIPS)':
 C_PATH='@baseboard_fab2_lib.baseboard_fab2(sch_1):page107_i287@mstr_discrete.ca~
p(chips)',
 P_PATH='@baseboard_fab2_lib.baseboard_fab2(sch_1):page107_i287@mstr_discrete.ca~
p(chips)',
 PATH='I287',
 DRAWING='@BASEBOARD_FAB2_LIB.BASEBOARD_FAB2(SCH_1):PAGE107',
 TOLERANCE='10%',
 SEC_TYPE='0402',
 MATERIAL='X7R',
 PHYS_PAGE='107',
 XY='(-2950,1525)',
 ROT='2',
 VER='1',
 VALUE='0.22UF',
 PACK_TYPE='0402',
 PART_NUMBER='A36096-155',
 LOCATION='C2U14',
 GROUP='PCIE_UPLINK',
 SEC='1',
 CDS_LIB='mstr_discrete',
 CDS_PART_NAME='CAP_0402-0.22UF,16V,10%,X7R,A3A',
 VOLTAGE='16V',
 PRIM_FILE='./archive_libs/mstr_discrete/cap/chips/chips.prt';

PART_NAME
 C2U15 'CAP_0402-0.22UF,16V,10%,X7R,A3A':
 GROUP='PCIE_UPLINK';

SECTION_NUMBER 1
 '@BASEBOARD_FAB2_LIB.BASEBOARD_FAB2(SCH_1):PAGE107_I296@MSTR_DISCRETE.CAP(CHIPS)':
 C_PATH='@baseboard_fab2_lib.baseboard_fab2(sch_1):page107_i296@mstr_discrete.ca~
p(chips)',
 P_PATH='@baseboard_fab2_lib.baseboard_fab2(sch_1):page107_i296@mstr_discrete.ca~
p(chips)',
 PATH='I296',
 DRAWING='@BASEBOARD_FAB2_LIB.BASEBOARD_FAB2(SCH_1):PAGE107',
 TOLERANCE='10%',
 SEC_TYPE='0402',
 MATERIAL='X7R',
 PHYS_PAGE='107',
 XY='(-3100,875)',
 ROT='2',
 VER='1',
 VALUE='0.22UF',
 PACK_TYPE='0402',
 PART_NUMBER='A36096-155',
 LOCATION='C2U15',
 GROUP='PCIE_UPLINK',
 SEC='1',
 CDS_LIB='mstr_discrete',
 CDS_PART_NAME='CAP_0402-0.22UF,16V,10%,X7R,A3A',
 VOLTAGE='16V',
 PRIM_FILE='./archive_libs/mstr_discrete/cap/chips/chips.prt';

PART_NAME
 C2U16 'CAP_0402-0.22UF,16V,10%,X7R,A3A':
 GROUP='PCIE_UPLINK';

SECTION_NUMBER 1
 '@BASEBOARD_FAB2_LIB.BASEBOARD_FAB2(SCH_1):PAGE107_I286@MSTR_DISCRETE.CAP(CHIPS)':
 C_PATH='@baseboard_fab2_lib.baseboard_fab2(sch_1):page107_i286@mstr_discrete.ca~
p(chips)',
 P_PATH='@baseboard_fab2_lib.baseboard_fab2(sch_1):page107_i286@mstr_discrete.ca~
p(chips)',
 PATH='I286',
 DRAWING='@BASEBOARD_FAB2_LIB.BASEBOARD_FAB2(SCH_1):PAGE107',
 TOLERANCE='10%',
 SEC_TYPE='0402',
 MATERIAL='X7R',
 PHYS_PAGE='107',
 XY='(-3150,1875)',
 ROT='2',
 VER='1',
 VALUE='0.22UF',
 PACK_TYPE='0402',
 PART_NUMBER='A36096-155',
 LOCATION='C2U16',
 GROUP='PCIE_UPLINK',
 SEC='1',
 CDS_LIB='mstr_discrete',
 CDS_PART_NAME='CAP_0402-0.22UF,16V,10%,X7R,A3A',
 VOLTAGE='16V',
 PRIM_FILE='./archive_libs/mstr_discrete/cap/chips/chips.prt';

PART_NAME
 C2U17 'CAP_0402-0.22UF,16V,10%,X7R,A3A':
 GROUP='PCIE_UPLINK';

SECTION_NUMBER 1
 '@BASEBOARD_FAB2_LIB.BASEBOARD_FAB2(SCH_1):PAGE107_I300@MSTR_DISCRETE.CAP(CHIPS)':
 C_PATH='@baseboard_fab2_lib.baseboard_fab2(sch_1):page107_i300@mstr_discrete.ca~
p(chips)',
 P_PATH='@baseboard_fab2_lib.baseboard_fab2(sch_1):page107_i300@mstr_discrete.ca~
p(chips)',
 PATH='I300',
 DRAWING='@BASEBOARD_FAB2_LIB.BASEBOARD_FAB2(SCH_1):PAGE107',
 TOLERANCE='10%',
 SEC_TYPE='0402',
 MATERIAL='X7R',
 PHYS_PAGE='107',
 XY='(-3300,525)',
 ROT='2',
 VER='1',
 VALUE='0.22UF',
 PACK_TYPE='0402',
 PART_NUMBER='A36096-155',
 LOCATION='C2U17',
 GROUP='PCIE_UPLINK',
 SEC='1',
 CDS_LIB='mstr_discrete',
 CDS_PART_NAME='CAP_0402-0.22UF,16V,10%,X7R,A3A',
 VOLTAGE='16V',
 PRIM_FILE='./archive_libs/mstr_discrete/cap/chips/chips.prt';

PART_NAME
 C2U18 'CAP_0402-0.22UF,16V,10%,X7R,A3A':
 GROUP='PCIE_UPLINK';

SECTION_NUMBER 1
 '@BASEBOARD_FAB2_LIB.BASEBOARD_FAB2(SCH_1):PAGE107_I294@MSTR_DISCRETE.CAP(CHIPS)':
 C_PATH='@baseboard_fab2_lib.baseboard_fab2(sch_1):page107_i294@mstr_discrete.ca~
p(chips)',
 P_PATH='@baseboard_fab2_lib.baseboard_fab2(sch_1):page107_i294@mstr_discrete.ca~
p(chips)',
 PATH='I294',
 DRAWING='@BASEBOARD_FAB2_LIB.BASEBOARD_FAB2(SCH_1):PAGE107',
 TOLERANCE='10%',
 SEC_TYPE='0402',
 MATERIAL='X7R',
 PHYS_PAGE='107',
 XY='(-3350,1525)',
 ROT='2',
 VER='1',
 VALUE='0.22UF',
 PACK_TYPE='0402',
 PART_NUMBER='A36096-155',
 LOCATION='C2U18',
 GROUP='PCIE_UPLINK',
 SEC='1',
 CDS_LIB='mstr_discrete',
 CDS_PART_NAME='CAP_0402-0.22UF,16V,10%,X7R,A3A',
 VOLTAGE='16V',
 PRIM_FILE='./archive_libs/mstr_discrete/cap/chips/chips.prt';

PART_NAME
 C2U19 'CAP_A_0402V-0.1UF,16V,10%,X7R,A':
 ROOM='P3V3_PWR_SWITCH';

SECTION_NUMBER 1
 '@BASEBOARD_FAB2_LIB.BASEBOARD_FAB2(SCH_1):PAGE198_I46@DEV_DISCRETE.CAP_A(CHIPS)':
 C_PATH='@baseboard_fab2_lib.baseboard_fab2(sch_1):page198_i46@dev_discrete.cap_~
a(chips)',
 P_PATH='@baseboard_fab2_lib.baseboard_fab2(sch_1):page198_i46@dev_discrete.cap_~
a(chips)',
 PATH='I46',
 DRAWING='@BASEBOARD_FAB2_LIB.BASEBOARD_FAB2(SCH_1):PAGE198',
 TOLERANCE='10%',
 SEC_TYPE='0402V',
 MATERIAL='X7R',
 BOM_COST='PWR_SWITCH',
 PHYS_PAGE='198',
 XY='(-4675,3200)',
 ROT='0',
 VER='1',
 VALUE='0.1UF',
 PACK_TYPE='0402V',
 PART_NUMBER='A36096-030',
 LOCATION='C2U19',
 ROOM='P3V3_PWR_SWITCH',
 SEC='1',
 CDS_LIB='dev_discrete',
 CDS_PART_NAME='CAP_A_0402V-0.1UF,16V,10%,X7R,A',
 VOLTAGE='16V',
 PRIM_FILE='./archive_libs/discrete/cap_a/chips/chips.prt';

PART_NAME
 C2U20 'CAP_A_0402V-0.1UF,16V,10%,X7R,A':
 ROOM='IO_SLOT';

SECTION_NUMBER 1
 '@BASEBOARD_FAB2_LIB.BASEBOARD_FAB2(SCH_1):PAGE108_I1@DEV_DISCRETE.CAP_A(CHIPS)':
 C_PATH='@baseboard_fab2_lib.baseboard_fab2(sch_1):page108_i1@dev_discrete.cap_a~
(chips)',
 P_PATH='@baseboard_fab2_lib.baseboard_fab2(sch_1):page108_i1@dev_discrete.cap_a~
(chips)',
 PATH='I1',
 DRAWING='@BASEBOARD_FAB2_LIB.BASEBOARD_FAB2(SCH_1):PAGE108',
 TOLERANCE='10%',
 SEC_TYPE='0402V',
 MATERIAL='X7R',
 PHYS_PAGE='108',
 XY='(-3275,675)',
 ROT='0',
 VER='1',
 VALUE='0.1UF',
 PACK_TYPE='0402V',
 PART_NUMBER='A36096-030',
 LOCATION='C2U20',
 ROOM='IO_SLOT',
 SEC='1',
 CDS_LIB='dev_discrete',
 CDS_PART_NAME='CAP_A_0402V-0.1UF,16V,10%,X7R,A',
 VOLTAGE='16V',
 PRIM_FILE='./archive_libs/discrete/cap_a/chips/chips.prt';

PART_NAME
 C2U21 'CAP_A_0402V-0.1UF,16V,10%,X7R,A':
 ROOM='IO_SLOT';

SECTION_NUMBER 1
 '@BASEBOARD_FAB2_LIB.BASEBOARD_FAB2(SCH_1):PAGE108_I5@DEV_DISCRETE.CAP_A(CHIPS)':
 C_PATH='@baseboard_fab2_lib.baseboard_fab2(sch_1):page108_i5@dev_discrete.cap_a~
(chips)',
 P_PATH='@baseboard_fab2_lib.baseboard_fab2(sch_1):page108_i5@dev_discrete.cap_a~
(chips)',
 PATH='I5',
 DRAWING='@BASEBOARD_FAB2_LIB.BASEBOARD_FAB2(SCH_1):PAGE108',
 TOLERANCE='10%',
 SEC_TYPE='0402V',
 MATERIAL='X7R',
 PHYS_PAGE='108',
 XY='(-3275,1400)',
 ROT='0',
 VER='1',
 VALUE='0.1UF',
 PACK_TYPE='0402V',
 PART_NUMBER='A36096-030',
 LOCATION='C2U21',
 ROOM='IO_SLOT',
 SEC='1',
 CDS_LIB='dev_discrete',
 CDS_PART_NAME='CAP_A_0402V-0.1UF,16V,10%,X7R,A',
 VOLTAGE='16V',
 PRIM_FILE='./archive_libs/discrete/cap_a/chips/chips.prt';

PART_NAME
 C2U22 'CAP_A_0402V-0.1UF,16V,10%,X7R,A':
 ROOM='IO_SLOT';

SECTION_NUMBER 1
 '@BASEBOARD_FAB2_LIB.BASEBOARD_FAB2(SCH_1):PAGE108_I318@DEV_DISCRETE.CAP_A(CHIPS)':
 C_PATH='@baseboard_fab2_lib.baseboard_fab2(sch_1):page108_i318@dev_discrete.cap~
_a(chips)',
 P_PATH='@baseboard_fab2_lib.baseboard_fab2(sch_1):page108_i318@dev_discrete.cap~
_a(chips)',
 PATH='I318',
 DRAWING='@BASEBOARD_FAB2_LIB.BASEBOARD_FAB2(SCH_1):PAGE108',
 TOLERANCE='10%',
 SEC_TYPE='0402V',
 MATERIAL='X7R',
 PHYS_PAGE='108',
 XY='(-2350,1375)',
 ROT='0',
 VER='1',
 VALUE='0.1UF',
 PACK_TYPE='0402V',
 PART_NUMBER='A36096-030',
 LOCATION='C2U22',
 ROOM='IO_SLOT',
 SEC='1',
 CDS_LIB='dev_discrete',
 CDS_PART_NAME='CAP_A_0402V-0.1UF,16V,10%,X7R,A',
 VOLTAGE='16V',
 PRIM_FILE='./archive_libs/discrete/cap_a/chips/chips.prt';

PART_NAME
 C2U23 'CAP_A_0402V-0.1UF,16V,10%,X7R,A':
 ROOM='IO_SLOT';

SECTION_NUMBER 1
 '@BASEBOARD_FAB2_LIB.BASEBOARD_FAB2(SCH_1):PAGE108_I315@DEV_DISCRETE.CAP_A(CHIPS)':
 C_PATH='@baseboard_fab2_lib.baseboard_fab2(sch_1):page108_i315@dev_discrete.cap~
_a(chips)',
 P_PATH='@baseboard_fab2_lib.baseboard_fab2(sch_1):page108_i315@dev_discrete.cap~
_a(chips)',
 PATH='I315',
 DRAWING='@BASEBOARD_FAB2_LIB.BASEBOARD_FAB2(SCH_1):PAGE108',
 TOLERANCE='10%',
 SEC_TYPE='0402V',
 MATERIAL='X7R',
 PHYS_PAGE='108',
 XY='(-1950,1350)',
 ROT='0',
 VER='1',
 VALUE='0.1UF',
 PACK_TYPE='0402V',
 PART_NUMBER='A36096-030',
 LOCATION='C2U23',
 ROOM='IO_SLOT',
 SEC='1',
 CDS_LIB='dev_discrete',
 CDS_PART_NAME='CAP_A_0402V-0.1UF,16V,10%,X7R,A',
 VOLTAGE='16V',
 PRIM_FILE='./archive_libs/discrete/cap_a/chips/chips.prt';

PART_NAME
 C2U24 'CAP_A_0402V-0.1UF,16V,10%,X7R,A':
 ROOM='IO_SLOT';

SECTION_NUMBER 1
 '@BASEBOARD_FAB2_LIB.BASEBOARD_FAB2(SCH_1):PAGE108_I2@DEV_DISCRETE.CAP_A(CHIPS)':
 C_PATH='@baseboard_fab2_lib.baseboard_fab2(sch_1):page108_i2@dev_discrete.cap_a~
(chips)',
 P_PATH='@baseboard_fab2_lib.baseboard_fab2(sch_1):page108_i2@dev_discrete.cap_a~
(chips)',
 PATH='I2',
 DRAWING='@BASEBOARD_FAB2_LIB.BASEBOARD_FAB2(SCH_1):PAGE108',
 TOLERANCE='10%',
 SEC_TYPE='0402V',
 MATERIAL='X7R',
 PHYS_PAGE='108',
 XY='(-2875,650)',
 ROT='0',
 VER='1',
 VALUE='0.1UF',
 PACK_TYPE='0402V',
 PART_NUMBER='A36096-030',
 LOCATION='C2U24',
 ROOM='IO_SLOT',
 SEC='1',
 CDS_LIB='dev_discrete',
 CDS_PART_NAME='CAP_A_0402V-0.1UF,16V,10%,X7R,A',
 VOLTAGE='16V',
 PRIM_FILE='./archive_libs/discrete/cap_a/chips/chips.prt';

PART_NAME
 C2U25 'CAP_A_0402V-0.1UF,16V,10%,X7R,A':
 ROOM='IO_SLOT';

SECTION_NUMBER 1
 '@BASEBOARD_FAB2_LIB.BASEBOARD_FAB2(SCH_1):PAGE108_I7@DEV_DISCRETE.CAP_A(CHIPS)':
 C_PATH='@baseboard_fab2_lib.baseboard_fab2(sch_1):page108_i7@dev_discrete.cap_a~
(chips)',
 P_PATH='@baseboard_fab2_lib.baseboard_fab2(sch_1):page108_i7@dev_discrete.cap_a~
(chips)',
 PATH='I7',
 DRAWING='@BASEBOARD_FAB2_LIB.BASEBOARD_FAB2(SCH_1):PAGE108',
 TOLERANCE='10%',
 SEC_TYPE='0402V',
 MATERIAL='X7R',
 PHYS_PAGE='108',
 XY='(-2875,1375)',
 ROT='0',
 VER='1',
 VALUE='0.1UF',
 PACK_TYPE='0402V',
 PART_NUMBER='A36096-030',
 LOCATION='C2U25',
 ROOM='IO_SLOT',
 SEC='1',
 CDS_LIB='dev_discrete',
 CDS_PART_NAME='CAP_A_0402V-0.1UF,16V,10%,X7R,A',
 VOLTAGE='16V',
 PRIM_FILE='./archive_libs/discrete/cap_a/chips/chips.prt';

PART_NAME
 C2U26 'CAP_A_0402V-1.0UF,6.3V,10%,X6SA':
 ROOM='SB_VRD',
 NO_XNET_CONNECTION='1';

SECTION_NUMBER 1
 '@BASEBOARD_FAB2_LIB.BASEBOARD_FAB2(SCH_1):PAGE196_I102@DEV_DISCRETE.CAP_A(CHIPS)':
 C_PATH='@baseboard_fab2_lib.baseboard_fab2(sch_1):page196_i102@dev_discrete.cap~
_a(chips)',
 P_PATH='@baseboard_fab2_lib.baseboard_fab2(sch_1):page196_i102@dev_discrete.cap~
_a(chips)',
 PATH='I102',
 DRAWING='@BASEBOARD_FAB2_LIB.BASEBOARD_FAB2(SCH_1):PAGE196',
 TOLERANCE='10%',
 SEC_TYPE='0402V',
 MATERIAL='X6S',
 BOM_COST='SB',
 NO_XNET_CONNECTION='1',
 PHYS_PAGE='196',
 XY='(-2200,4500)',
 ROT='0',
 VER='1',
 VALUE='1.0UF',
 PACK_TYPE='0402V',
 PART_NUMBER='D97712-004',
 LOCATION='C2U26',
 ROOM='SB_VRD',
 SEC='1',
 CDS_LIB='dev_discrete',
 CDS_PART_NAME='CAP_A_0402V-1.0UF,6.3V,10%,X6SA',
 VOLTAGE='6.3V',
 PRIM_FILE='./archive_libs/discrete/cap_a/chips/chips.prt';

PART_NAME
 C2U27 'CAP_A_0402V-0.1UF,16V,10%,X7R,A':
 ROOM='CPU_FANS';

SECTION_NUMBER 1
 '@BASEBOARD_FAB2_LIB.BASEBOARD_FAB2(SCH_1):PAGE161_I90@DEV_DISCRETE.CAP_A(CHIPS)':
 C_PATH='@baseboard_fab2_lib.baseboard_fab2(sch_1):page161_i90@dev_discrete.cap_~
a(chips)',
 P_PATH='@baseboard_fab2_lib.baseboard_fab2(sch_1):page161_i90@dev_discrete.cap_~
a(chips)',
 PATH='I90',
 DRAWING='@BASEBOARD_FAB2_LIB.BASEBOARD_FAB2(SCH_1):PAGE161',
 TOLERANCE='10%',
 SEC_TYPE='0402V',
 MATERIAL='X7R',
 BOM_COST='SM_THERM',
 PHYS_PAGE='161',
 XY='(-6300,4450)',
 ROT='0',
 VER='1',
 VALUE='0.1UF',
 PACK_TYPE='0402V',
 PART_NUMBER='A36096-030',
 LOCATION='C2U27',
 ROOM='CPU_FANS',
 SEC='1',
 CDS_LIB='dev_discrete',
 CDS_PART_NAME='CAP_A_0402V-0.1UF,16V,10%,X7R,A',
 VOLTAGE='16V',
 PRIM_FILE='./archive_libs/discrete/cap_a/chips/chips.prt';

PART_NAME
 C2U28 'CAP_A_0402V-0.1UF,16V,10%,X7R,A':
 ROOM='CPU_FANS';

SECTION_NUMBER 1
 '@BASEBOARD_FAB2_LIB.BASEBOARD_FAB2(SCH_1):PAGE161_I93@DEV_DISCRETE.CAP_A(CHIPS)':
 C_PATH='@baseboard_fab2_lib.baseboard_fab2(sch_1):page161_i93@dev_discrete.cap_~
a(chips)',
 P_PATH='@baseboard_fab2_lib.baseboard_fab2(sch_1):page161_i93@dev_discrete.cap_~
a(chips)',
 PATH='I93',
 DRAWING='@BASEBOARD_FAB2_LIB.BASEBOARD_FAB2(SCH_1):PAGE161',
 TOLERANCE='10%',
 SEC_TYPE='0402V',
 MATERIAL='X7R',
 BOM_COST='SM_THERM',
 PHYS_PAGE='161',
 XY='(-6200,675)',
 ROT='0',
 VER='1',
 VALUE='0.1UF',
 PACK_TYPE='0402V',
 PART_NUMBER='A36096-030',
 LOCATION='C2U28',
 ROOM='CPU_FANS',
 SEC='1',
 CDS_LIB='dev_discrete',
 CDS_PART_NAME='CAP_A_0402V-0.1UF,16V,10%,X7R,A',
 VOLTAGE='16V',
 PRIM_FILE='./archive_libs/discrete/cap_a/chips/chips.prt';

PART_NAME
 C3A1 'CAP_A_0603V-47UF,4V,20%,X5R,60A':
 GROUP='PWR_MLCC_CAP';

SECTION_NUMBER 1
 '@BASEBOARD_FAB2_LIB.BASEBOARD_FAB2(SCH_1):PAGE228_I275@DEV_DISCRETE.CAP_A(CHIPS)':
 C_PATH='@baseboard_fab2_lib.baseboard_fab2(sch_1):page228_i275@dev_discrete.cap~
_a(chips)',
 P_PATH='@baseboard_fab2_lib.baseboard_fab2(sch_1):page228_i275@dev_discrete.cap~
_a(chips)',
 PATH='I275',
 DRAWING='@BASEBOARD_FAB2_LIB.BASEBOARD_FAB2(SCH_1):PAGE228',
 BOM_SS='E15431-004',
 TOLERANCE='20%',
 SEC_TYPE='0603V',
 MATERIAL='X5R',
 PHYS_PAGE='228',
 XY='(-225,-75)',
 ROT='0',
 VER='1',
 VALUE='47UF',
 PACK_TYPE='0603V',
 PART_NUMBER='602433-106',
 LOCATION='C3A1',
 GROUP='PWR_MLCC_CAP',
 SEC='1',
 CDS_LIB='dev_discrete',
 CDS_PART_NAME='CAP_A_0603V-47UF,4V,20%,X5R,60A',
 VOLTAGE='4V',
 PRIM_FILE='./archive_libs/discrete/cap_a/chips/chips.prt';

PART_NAME
 C3A2 'CAP_A_0603V-47UF,4V,20%,X5R,60A':
 GROUP='PWR_MLCC_CAP';

SECTION_NUMBER 1
 '@BASEBOARD_FAB2_LIB.BASEBOARD_FAB2(SCH_1):PAGE228_I276@DEV_DISCRETE.CAP_A(CHIPS)':
 C_PATH='@baseboard_fab2_lib.baseboard_fab2(sch_1):page228_i276@dev_discrete.cap~
_a(chips)',
 P_PATH='@baseboard_fab2_lib.baseboard_fab2(sch_1):page228_i276@dev_discrete.cap~
_a(chips)',
 PATH='I276',
 DRAWING='@BASEBOARD_FAB2_LIB.BASEBOARD_FAB2(SCH_1):PAGE228',
 BOM_SS='E15431-004',
 TOLERANCE='20%',
 SEC_TYPE='0603V',
 MATERIAL='X5R',
 PHYS_PAGE='228',
 XY='(100,-75)',
 ROT='0',
 VER='1',
 VALUE='47UF',
 PACK_TYPE='0603V',
 PART_NUMBER='602433-106',
 LOCATION='C3A2',
 GROUP='PWR_MLCC_CAP',
 SEC='1',
 CDS_LIB='dev_discrete',
 CDS_PART_NAME='CAP_A_0603V-47UF,4V,20%,X5R,60A',
 VOLTAGE='4V',
 PRIM_FILE='./archive_libs/discrete/cap_a/chips/chips.prt';

PART_NAME
 C3A3 'CAP_0603LF-10UF,4V,20%,X6S,E15A':
 GROUP='PWR_MLCC_CAP',
 ROOM='PVPP_KLM_VR';

SECTION_NUMBER 1
 '@BASEBOARD_FAB2_LIB.BASEBOARD_FAB2(SCH_1):PAGE234_I97@MSTR_DISCRETE.CAP(CHIPS)':
 C_PATH='@baseboard_fab2_lib.baseboard_fab2(sch_1):page234_i97@mstr_discrete.cap~
(chips)',
 P_PATH='@baseboard_fab2_lib.baseboard_fab2(sch_1):page234_i97@mstr_discrete.cap~
(chips)',
 PATH='I97',
 DRAWING='@BASEBOARD_FAB2_LIB.BASEBOARD_FAB2(SCH_1):PAGE234',
 TOLERANCE='20%',
 MATERIAL='X6S',
 BOM_COST='MEM_VRD_PVPP_AB',
 PHYS_PAGE='234',
 XY='(-8225,725)',
 ROT='0',
 VER='1',
 VALUE='10UF',
 PACK_TYPE='0603LF',
 PART_NUMBER='E15431-001',
 LOCATION='C3A3',
 ROOM='PVPP_KLM_VR',
 GROUP='PWR_MLCC_CAP',
 CDS_LIB='mstr_discrete',
 CDS_PART_NAME='CAP_0603LF-10UF,4V,20%,X6S,E15A',
 VOLTAGE='4V',
 PRIM_FILE='./archive_libs/mstr_discrete/cap/chips/chips.prt';

PART_NAME
 C3A4 'CAP_0603LF-10UF,4V,20%,X6S,E15A':
 GROUP='PWR_MLCC_CAP',
 ROOM='PVPP_KLM_VR';

SECTION_NUMBER 1
 '@BASEBOARD_FAB2_LIB.BASEBOARD_FAB2(SCH_1):PAGE234_I93@MSTR_DISCRETE.CAP(CHIPS)':
 C_PATH='@baseboard_fab2_lib.baseboard_fab2(sch_1):page234_i93@mstr_discrete.cap~
(chips)',
 P_PATH='@baseboard_fab2_lib.baseboard_fab2(sch_1):page234_i93@mstr_discrete.cap~
(chips)',
 PATH='I93',
 DRAWING='@BASEBOARD_FAB2_LIB.BASEBOARD_FAB2(SCH_1):PAGE234',
 TOLERANCE='20%',
 MATERIAL='X6S',
 BOM_COST='MEM_VRD_PVPP_AB',
 PHYS_PAGE='234',
 XY='(-7400,700)',
 ROT='0',
 VER='1',
 VALUE='10UF',
 PACK_TYPE='0603LF',
 PART_NUMBER='E15431-001',
 LOCATION='C3A4',
 ROOM='PVPP_KLM_VR',
 GROUP='PWR_MLCC_CAP',
 CDS_LIB='mstr_discrete',
 CDS_PART_NAME='CAP_0603LF-10UF,4V,20%,X6S,E15A',
 VOLTAGE='4V',
 PRIM_FILE='./archive_libs/mstr_discrete/cap/chips/chips.prt';

PART_NAME
 C3A5 'CAP_A_0603V-47UF,4V,20%,X5R,60A':
 GROUP='PWR_MLCC_CAP';

SECTION_NUMBER 1
 '@BASEBOARD_FAB2_LIB.BASEBOARD_FAB2(SCH_1):PAGE228_I270@DEV_DISCRETE.CAP_A(CHIPS)':
 C_PATH='@baseboard_fab2_lib.baseboard_fab2(sch_1):page228_i270@dev_discrete.cap~
_a(chips)',
 P_PATH='@baseboard_fab2_lib.baseboard_fab2(sch_1):page228_i270@dev_discrete.cap~
_a(chips)',
 PATH='I270',
 DRAWING='@BASEBOARD_FAB2_LIB.BASEBOARD_FAB2(SCH_1):PAGE228',
 BOM_SS='E15431-004',
 TOLERANCE='20%',
 SEC_TYPE='0603V',
 MATERIAL='X5R',
 PHYS_PAGE='228',
 XY='(-1650,-75)',
 ROT='0',
 VER='1',
 VALUE='47UF',
 PACK_TYPE='0603V',
 PART_NUMBER='602433-106',
 LOCATION='C3A5',
 GROUP='PWR_MLCC_CAP',
 SEC='1',
 CDS_LIB='dev_discrete',
 CDS_PART_NAME='CAP_A_0603V-47UF,4V,20%,X5R,60A',
 VOLTAGE='4V',
 PRIM_FILE='./archive_libs/discrete/cap_a/chips/chips.prt';

PART_NAME
 C3A6 'CAP_A_0603V-47UF,4V,20%,X5R,60A':
 GROUP='PWR_MLCC_CAP';

SECTION_NUMBER 1
 '@BASEBOARD_FAB2_LIB.BASEBOARD_FAB2(SCH_1):PAGE228_I269@DEV_DISCRETE.CAP_A(CHIPS)':
 C_PATH='@baseboard_fab2_lib.baseboard_fab2(sch_1):page228_i269@dev_discrete.cap~
_a(chips)',
 P_PATH='@baseboard_fab2_lib.baseboard_fab2(sch_1):page228_i269@dev_discrete.cap~
_a(chips)',
 PATH='I269',
 DRAWING='@BASEBOARD_FAB2_LIB.BASEBOARD_FAB2(SCH_1):PAGE228',
 BOM_SS='E15431-004',
 TOLERANCE='20%',
 SEC_TYPE='0603V',
 MATERIAL='X5R',
 PHYS_PAGE='228',
 XY='(-1950,-75)',
 ROT='0',
 VER='1',
 VALUE='47UF',
 PACK_TYPE='0603V',
 PART_NUMBER='602433-106',
 LOCATION='C3A6',
 GROUP='PWR_MLCC_CAP',
 SEC='1',
 CDS_LIB='dev_discrete',
 CDS_PART_NAME='CAP_A_0603V-47UF,4V,20%,X5R,60A',
 VOLTAGE='4V',
 PRIM_FILE='./archive_libs/discrete/cap_a/chips/chips.prt';

PART_NAME
 C3A7 'CAP_0603LF-10UF,4V,20%,X6S,E15A':
 GROUP='PWR_MLCC_CAP',
 ROOM='PVPP_KLM_VR';

SECTION_NUMBER 1
 '@BASEBOARD_FAB2_LIB.BASEBOARD_FAB2(SCH_1):PAGE234_I95@MSTR_DISCRETE.CAP(CHIPS)':
 C_PATH='@baseboard_fab2_lib.baseboard_fab2(sch_1):page234_i95@mstr_discrete.cap~
(chips)',
 P_PATH='@baseboard_fab2_lib.baseboard_fab2(sch_1):page234_i95@mstr_discrete.cap~
(chips)',
 PATH='I95',
 DRAWING='@BASEBOARD_FAB2_LIB.BASEBOARD_FAB2(SCH_1):PAGE234',
 TOLERANCE='20%',
 MATERIAL='X6S',
 BOM_COST='MEM_VRD_PVPP_AB',
 PHYS_PAGE='234',
 XY='(-7950,725)',
 ROT='0',
 VER='1',
 VALUE='10UF',
 PACK_TYPE='0603LF',
 PART_NUMBER='E15431-001',
 LOCATION='C3A7',
 ROOM='PVPP_KLM_VR',
 GROUP='PWR_MLCC_CAP',
 CDS_LIB='mstr_discrete',
 CDS_PART_NAME='CAP_0603LF-10UF,4V,20%,X6S,E15A',
 VOLTAGE='4V',
 PRIM_FILE='./archive_libs/mstr_discrete/cap/chips/chips.prt';

PART_NAME
 C3A8 'CAP_0603LF-10UF,4V,20%,X6S,E15A':
 GROUP='PWR_MLCC_CAP',
 ROOM='PVPP_KLM_VR';

SECTION_NUMBER 1
 '@BASEBOARD_FAB2_LIB.BASEBOARD_FAB2(SCH_1):PAGE234_I86@MSTR_DISCRETE.CAP(CHIPS)':
 C_PATH='@baseboard_fab2_lib.baseboard_fab2(sch_1):page234_i86@mstr_discrete.cap~
(chips)',
 P_PATH='@baseboard_fab2_lib.baseboard_fab2(sch_1):page234_i86@mstr_discrete.cap~
(chips)',
 PATH='I86',
 DRAWING='@BASEBOARD_FAB2_LIB.BASEBOARD_FAB2(SCH_1):PAGE234',
 TOLERANCE='20%',
 MATERIAL='X6S',
 BOM_COST='MEM_VRD_PVPP_AB',
 PHYS_PAGE='234',
 XY='(-5400,700)',
 ROT='0',
 VER='1',
 VALUE='10UF',
 PACK_TYPE='0603LF',
 PART_NUMBER='E15431-001',
 LOCATION='C3A8',
 ROOM='PVPP_KLM_VR',
 GROUP='PWR_MLCC_CAP',
 CDS_LIB='mstr_discrete',
 CDS_PART_NAME='CAP_0603LF-10UF,4V,20%,X6S,E15A',
 VOLTAGE='4V',
 PRIM_FILE='./archive_libs/mstr_discrete/cap/chips/chips.prt';

PART_NAME
 C3B1 'CAP_0603LF-10UF,4V,20%,X6S,E15A':
 GROUP='PWR_MLCC_CAP',
 ROOM='PVPP_KLM_VR';

SECTION_NUMBER 1
 '@BASEBOARD_FAB2_LIB.BASEBOARD_FAB2(SCH_1):PAGE234_I94@MSTR_DISCRETE.CAP(CHIPS)':
 C_PATH='@baseboard_fab2_lib.baseboard_fab2(sch_1):page234_i94@mstr_discrete.cap~
(chips)',
 P_PATH='@baseboard_fab2_lib.baseboard_fab2(sch_1):page234_i94@mstr_discrete.cap~
(chips)',
 PATH='I94',
 DRAWING='@BASEBOARD_FAB2_LIB.BASEBOARD_FAB2(SCH_1):PAGE234',
 TOLERANCE='20%',
 MATERIAL='X6S',
 BOM_COST='MEM_VRD_PVPP_AB',
 PHYS_PAGE='234',
 XY='(-7675,725)',
 ROT='0',
 VER='1',
 VALUE='10UF',
 PACK_TYPE='0603LF',
 PART_NUMBER='E15431-001',
 LOCATION='C3B1',
 ROOM='PVPP_KLM_VR',
 GROUP='PWR_MLCC_CAP',
 CDS_LIB='mstr_discrete',
 CDS_PART_NAME='CAP_0603LF-10UF,4V,20%,X6S,E15A',
 VOLTAGE='4V',
 PRIM_FILE='./archive_libs/mstr_discrete/cap/chips/chips.prt';

PART_NAME
 C3B2 'CAP_0603LF-10UF,4V,20%,X6S,E15A':
 GROUP='PWR_MLCC_CAP',
 ROOM='PVPP_KLM_VR';

SECTION_NUMBER 1
 '@BASEBOARD_FAB2_LIB.BASEBOARD_FAB2(SCH_1):PAGE234_I84@MSTR_DISCRETE.CAP(CHIPS)':
 C_PATH='@baseboard_fab2_lib.baseboard_fab2(sch_1):page234_i84@mstr_discrete.cap~
(chips)',
 P_PATH='@baseboard_fab2_lib.baseboard_fab2(sch_1):page234_i84@mstr_discrete.cap~
(chips)',
 PATH='I84',
 DRAWING='@BASEBOARD_FAB2_LIB.BASEBOARD_FAB2(SCH_1):PAGE234',
 TOLERANCE='20%',
 SEC_TYPE='0603LF',
 MATERIAL='X6S',
 BOM_COST='MEM_VRD_PVPP_AB',
 PHYS_PAGE='234',
 XY='(-5125,725)',
 ROT='0',
 VER='1',
 VALUE='10UF',
 PACK_TYPE='0603LF',
 PART_NUMBER='E15431-001',
 LOCATION='C3B2',
 ROOM='PVPP_KLM_VR',
 GROUP='PWR_MLCC_CAP',
 SEC='1',
 CDS_LIB='mstr_discrete',
 CDS_PART_NAME='CAP_0603LF-10UF,4V,20%,X6S,E15A',
 VOLTAGE='4V',
 PRIM_FILE='./archive_libs/mstr_discrete/cap/chips/chips.prt';

PART_NAME
 C3B3 'CAPP_7343LF-330UF,6.3V,20%,POSA':
 GROUP='PWR_BULK_CAP',
 ROOM='PVPP_KLM_VR',
 REUSE_ID='28';

SECTION_NUMBER 1
 '@BASEBOARD_FAB2_LIB.BASEBOARD_FAB2(SCH_1):PAGE234_I167@MSTR_DISCRETE.CAPP(CHIPS)':
 C_PATH='@baseboard_fab2_lib.baseboard_fab2(sch_1):page234_i167@mstr_discrete.ca~
pp(chips)',
 P_PATH='@baseboard_fab2_lib.baseboard_fab2(sch_1):page234_i167@mstr_discrete.ca~
pp(chips)',
 PATH='I167',
 DRAWING='@BASEBOARD_FAB2_LIB.BASEBOARD_FAB2(SCH_1):PAGE234',
 TOLERANCE='20%',
 MATERIAL='POSCAP',
 BOM_COST='PVPP_KLM_VR',
 PHYS_PAGE='234',
 REUSE_ID='28',
 XY='(-1750,3650)',
 ROT='0',
 VER='1',
 VALUE='330UF',
 PACK_TYPE='7343LF',
 PART_NUMBER='724613-042',
 LOCATION='C3B3',
 ROOM='PVPP_KLM_VR',
 GROUP='PWR_BULK_CAP',
 CDS_LIB='mstr_discrete',
 CDS_PART_NAME='CAPP_7343LF-330UF,6.3V,20%,POSA',
 VOLTAGE='6.3V',
 PRIM_FILE='./archive_libs/mstr_discrete/capp/chips/chips.prt';

PART_NAME
 C3B4 'CAP_A_0402V-0.1UF,16V,10%,X7R,A':
 ROOM='MEM',
 SIGNAL_MODEL='DEFAULT_CAPACITOR_100000pF_2_1';

SECTION_NUMBER 1
 '@BASEBOARD_FAB2_LIB.BASEBOARD_FAB2(SCH_1):PAGE99_I47@DEV_DISCRETE.CAP_A(CHIPS)':
 C_PATH='@baseboard_fab2_lib.baseboard_fab2(sch_1):page99_i47@dev_discrete.cap_a~
(chips)',
 P_PATH='@baseboard_fab2_lib.baseboard_fab2(sch_1):page99_i47@dev_discrete.cap_a~
(chips)',
 PATH='I47',
 DRAWING='@BASEBOARD_FAB2_LIB.BASEBOARD_FAB2(SCH_1):PAGE99',
 CD_SEC='1',
 TOLERANCE='10%',
 MATERIAL='X7R',
 BOM_COST='SM_CONTROLLER',
 PHYS_PAGE='99',
 XY='(2250,1525)',
 ROT='0',
 VER='1',
 VALUE='0.1UF',
 PACK_TYPE='0402V',
 PART_NUMBER='A36096-030',
 LOCATION='C3B4',
 SIGNAL_MODEL='DEFAULT_CAPACITOR_100000pF_2_1',
 ROOM='MEM',
 CDS_LIB='dev_discrete',
 CDS_PART_NAME='CAP_A_0402V-0.1UF,16V,10%,X7R,A',
 VOLTAGE='16V',
 PRIM_FILE='./archive_libs/discrete/cap_a/chips/chips.prt';

PART_NAME
 C3B5 'CAP_A_0402V-0.1UF,16V,10%,X7R,A':
 ROOM='MEM',
 SIGNAL_MODEL='DEFAULT_CAPACITOR_100000pF_2_1';

SECTION_NUMBER 1
 '@BASEBOARD_FAB2_LIB.BASEBOARD_FAB2(SCH_1):PAGE99_I53@DEV_DISCRETE.CAP_A(CHIPS)':
 C_PATH='@baseboard_fab2_lib.baseboard_fab2(sch_1):page99_i53@dev_discrete.cap_a~
(chips)',
 P_PATH='@baseboard_fab2_lib.baseboard_fab2(sch_1):page99_i53@dev_discrete.cap_a~
(chips)',
 PATH='I53',
 DRAWING='@BASEBOARD_FAB2_LIB.BASEBOARD_FAB2(SCH_1):PAGE99',
 CD_SEC='1',
 TOLERANCE='10%',
 MATERIAL='X7R',
 BOM_COST='SM_CONTROLLER',
 PHYS_PAGE='99',
 XY='(1675,1500)',
 ROT='0',
 VER='1',
 VALUE='0.1UF',
 PACK_TYPE='0402V',
 PART_NUMBER='A36096-030',
 LOCATION='C3B5',
 SIGNAL_MODEL='DEFAULT_CAPACITOR_100000pF_2_1',
 ROOM='MEM',
 CDS_LIB='dev_discrete',
 CDS_PART_NAME='CAP_A_0402V-0.1UF,16V,10%,X7R,A',
 VOLTAGE='16V',
 PRIM_FILE='./archive_libs/discrete/cap_a/chips/chips.prt';

PART_NAME
 C3B6 'CAPP_3018-68UF,16V,20%,TANT,72A':;

SECTION_NUMBER 1
 '@BASEBOARD_FAB2_LIB.BASEBOARD_FAB2(SCH_1):PAGE195_I100@MSTR_DISCRETE.CAPP(CHIPS)':
 C_PATH='@baseboard_fab2_lib.baseboard_fab2(sch_1):page195_i100@mstr_discrete.ca~
pp(chips)',
 P_PATH='@baseboard_fab2_lib.baseboard_fab2(sch_1):page195_i100@mstr_discrete.ca~
pp(chips)',
 PATH='I100',
 DRAWING='@BASEBOARD_FAB2_LIB.BASEBOARD_FAB2(SCH_1):PAGE195',
 TOLERANCE='20%',
 SEC_TYPE='3018',
 MATERIAL='TANT',
 PHYS_PAGE='195',
 XY='(-7700,775)',
 ROT='0',
 VER='1',
 VALUE='68UF',
 PACK_TYPE='3018',
 PART_NUMBER='724613-112',
 LOCATION='C3B6',
 SEC='1',
 CDS_LIB='mstr_discrete',
 CDS_PART_NAME='CAPP_3018-68UF,16V,20%,TANT,72A',
 VOLTAGE='16V',
 PRIM_FILE='./archive_libs/mstr_discrete/capp/chips/chips.prt';

PART_NAME
 C3C1 'CAP_A_0402V-1.0UF,6.3V,10%,X6SA':
 GROUP='PWR_MCP_CAP',
 ROOM='P0V95_FPGA_CPU1';

SECTION_NUMBER 1
 '@BASEBOARD_FAB2_LIB.BASEBOARD_FAB2(SCH_1):PAGE193_I38@DEV_DISCRETE.CAP_A(CHIPS)':
 C_PATH='@baseboard_fab2_lib.baseboard_fab2(sch_1):page193_i38@dev_discrete.cap_~
a(chips)',
 P_PATH='@baseboard_fab2_lib.baseboard_fab2(sch_1):page193_i38@dev_discrete.cap_~
a(chips)',
 PATH='I38',
 DRAWING='@BASEBOARD_FAB2_LIB.BASEBOARD_FAB2(SCH_1):PAGE193',
 TOLERANCE='10%',
 SEC_TYPE='0402V',
 MATERIAL='X6S',
 PHYS_PAGE='193',
 XY='(-1600,3950)',
 ROT='0',
 VER='1',
 VALUE='1.0UF',
 PACK_TYPE='0402V',
 PART_NUMBER='D97712-004',
 LOCATION='C3C1',
 ROOM='P0V95_FPGA_CPU1',
 GROUP='PWR_MCP_CAP',
 SEC='1',
 CDS_LIB='dev_discrete',
 CDS_PART_NAME='CAP_A_0402V-1.0UF,6.3V,10%,X6SA',
 VOLTAGE='6.3V',
 PRIM_FILE='./archive_libs/discrete/cap_a/chips/chips.prt';

PART_NAME
 C3C2 'CAP_A_0402V-1.0UF,6.3V,10%,X6SA':
 GROUP='PWR_MCP_CAP',
 ROOM='P0V95_FPGA_CPU1';

SECTION_NUMBER 1
 '@BASEBOARD_FAB2_LIB.BASEBOARD_FAB2(SCH_1):PAGE193_I31@DEV_DISCRETE.CAP_A(CHIPS)':
 C_PATH='@baseboard_fab2_lib.baseboard_fab2(sch_1):page193_i31@dev_discrete.cap_~
a(chips)',
 P_PATH='@baseboard_fab2_lib.baseboard_fab2(sch_1):page193_i31@dev_discrete.cap_~
a(chips)',
 PATH='I31',
 DRAWING='@BASEBOARD_FAB2_LIB.BASEBOARD_FAB2(SCH_1):PAGE193',
 TOLERANCE='10%',
 SEC_TYPE='0402V',
 MATERIAL='X6S',
 PHYS_PAGE='193',
 XY='(-1300,3950)',
 ROT='0',
 VER='1',
 VALUE='1.0UF',
 PACK_TYPE='0402V',
 PART_NUMBER='D97712-004',
 LOCATION='C3C2',
 ROOM='P0V95_FPGA_CPU1',
 GROUP='PWR_MCP_CAP',
 SEC='1',
 CDS_LIB='dev_discrete',
 CDS_PART_NAME='CAP_A_0402V-1.0UF,6.3V,10%,X6SA',
 VOLTAGE='6.3V',
 PRIM_FILE='./archive_libs/discrete/cap_a/chips/chips.prt';

PART_NAME
 C3D1 'CAP_A_0603V-22.0UF,4V,20%,X6S,A':
 GROUP='PWR_MLCC_CAP',
 ROOM='PVCCIN_CPU1_DECAP_VR';

SECTION_NUMBER 1
 '@BASEBOARD_FAB2_LIB.BASEBOARD_FAB2(SCH_1):PAGE228_I255@DEV_DISCRETE.CAP_A(CHIPS)':
 C_PATH='@baseboard_fab2_lib.baseboard_fab2(sch_1):page228_i255@dev_discrete.cap~
_a(chips)',
 P_PATH='@baseboard_fab2_lib.baseboard_fab2(sch_1):page228_i255@dev_discrete.cap~
_a(chips)',
 PATH='I255',
 DRAWING='@BASEBOARD_FAB2_LIB.BASEBOARD_FAB2(SCH_1):PAGE228',
 TOLERANCE='20%',
 MATERIAL='X6S',
 BOM_COST='PROC',
 PHYS_PAGE='228',
 XY='(1650,1800)',
 ROT='0',
 VER='1',
 VALUE='22.0UF',
 PACK_TYPE='0603V',
 PART_NUMBER='E15431-004',
 LOCATION='C3D1',
 ROOM='PVCCIN_CPU1_DECAP_VR',
 GROUP='PWR_MLCC_CAP',
 CDS_LIB='dev_discrete',
 CDS_PART_NAME='CAP_A_0603V-22.0UF,4V,20%,X6S,A',
 VOLTAGE='4V',
 PRIM_FILE='./archive_libs/discrete/cap_a/chips/chips.prt';

PART_NAME
 C3D2 'CAP_A_0603V-22.0UF,4V,20%,X6S,A':
 GROUP='PWR_MLCC_CAP',
 ROOM='PVCCIN_CPU1_DECAP_VR';

SECTION_NUMBER 1
 '@BASEBOARD_FAB2_LIB.BASEBOARD_FAB2(SCH_1):PAGE76_I69@DEV_DISCRETE.CAP_A(CHIPS)':
 C_PATH='@baseboard_fab2_lib.baseboard_fab2(sch_1):page76_i69@dev_discrete.cap_a~
(chips)',
 P_PATH='@baseboard_fab2_lib.baseboard_fab2(sch_1):page76_i69@dev_discrete.cap_a~
(chips)',
 PATH='I69',
 DRAWING='@BASEBOARD_FAB2_LIB.BASEBOARD_FAB2(SCH_1):PAGE76',
 TOLERANCE='20%',
 MATERIAL='X6S',
 BOM_COST='PROC',
 PHYS_PAGE='76',
 XY='(-7350,4450)',
 ROT='0',
 VER='1',
 VALUE='22.0UF',
 PACK_TYPE='0603V',
 PART_NUMBER='E15431-004',
 LOCATION='C3D2',
 ROOM='PVCCIN_CPU1_DECAP_VR',
 GROUP='PWR_MLCC_CAP',
 CDS_LIB='dev_discrete',
 CDS_PART_NAME='CAP_A_0603V-22.0UF,4V,20%,X6S,A',
 VOLTAGE='4V',
 PRIM_FILE='./archive_libs/discrete/cap_a/chips/chips.prt';

PART_NAME
 C3D3 'CAP_0603LF-10UF,4V,20%,X6S,E15A':
 GROUP='PWR_MCP_CAP',
 ROOM='CPU1';

SECTION_NUMBER 1
 '@BASEBOARD_FAB2_LIB.BASEBOARD_FAB2(SCH_1):PAGE72_I25@MSTR_DISCRETE.CAP(CHIPS)':
 C_PATH='@baseboard_fab2_lib.baseboard_fab2(sch_1):page72_i25@mstr_discrete.cap(~
chips)',
 P_PATH='@baseboard_fab2_lib.baseboard_fab2(sch_1):page72_i25@mstr_discrete.cap(~
chips)',
 PATH='I25',
 DRAWING='@BASEBOARD_FAB2_LIB.BASEBOARD_FAB2(SCH_1):PAGE72',
 TOLERANCE='20%',
 MATERIAL='X6S',
 BOM_COST='PROC_SOCKET',
 PHYS_PAGE='72',
 XY='(-700,1175)',
 ROT='0',
 VER='1',
 VALUE='10UF',
 PACK_TYPE='0603LF',
 PART_NUMBER='E15431-001',
 LOCATION='C3D3',
 ROOM='CPU1',
 GROUP='PWR_MCP_CAP',
 CDS_LIB='mstr_discrete',
 CDS_PART_NAME='CAP_0603LF-10UF,4V,20%,X6S,E15A',
 VOLTAGE='4V',
 PRIM_FILE='./archive_libs/mstr_discrete/cap/chips/chips.prt';

PART_NAME
 C3D4 'CAP_A_0603V-22.0UF,4V,20%,X6S,A':
 GROUP='PWR_MCP_CAP',
 ROOM='PVCCIN_CPU1_DECAP_VR';

SECTION_NUMBER 1
 '@BASEBOARD_FAB2_LIB.BASEBOARD_FAB2(SCH_1):PAGE76_I5@DEV_DISCRETE.CAP_A(CHIPS)':
 C_PATH='@baseboard_fab2_lib.baseboard_fab2(sch_1):page76_i5@dev_discrete.cap_a(~
chips)',
 P_PATH='@baseboard_fab2_lib.baseboard_fab2(sch_1):page76_i5@dev_discrete.cap_a(~
chips)',
 PATH='I5',
 DRAWING='@BASEBOARD_FAB2_LIB.BASEBOARD_FAB2(SCH_1):PAGE76',
 TOLERANCE='20%',
 MATERIAL='X6S',
 BOM_COST='PROC',
 PHYS_PAGE='76',
 XY='(-2175,4450)',
 ROT='0',
 VER='1',
 VALUE='22.0UF',
 PACK_TYPE='0603V',
 PART_NUMBER='E15431-004',
 LOCATION='C3D4',
 ROOM='PVCCIN_CPU1_DECAP_VR',
 GROUP='PWR_MCP_CAP',
 CDS_LIB='dev_discrete',
 CDS_PART_NAME='CAP_A_0603V-22.0UF,4V,20%,X6S,A',
 VOLTAGE='4V',
 PRIM_FILE='./archive_libs/discrete/cap_a/chips/chips.prt';

PART_NAME
 C3D5 'CAP_A_0603V-22.0UF,4V,20%,X6S,A':
 GROUP='PWR_MCP_CAP',
 ROOM='PVCCIN_CPU1_DECAP_VR';

SECTION_NUMBER 1
 '@BASEBOARD_FAB2_LIB.BASEBOARD_FAB2(SCH_1):PAGE76_I3@DEV_DISCRETE.CAP_A(CHIPS)':
 C_PATH='@baseboard_fab2_lib.baseboard_fab2(sch_1):page76_i3@dev_discrete.cap_a(~
chips)',
 P_PATH='@baseboard_fab2_lib.baseboard_fab2(sch_1):page76_i3@dev_discrete.cap_a(~
chips)',
 PATH='I3',
 DRAWING='@BASEBOARD_FAB2_LIB.BASEBOARD_FAB2(SCH_1):PAGE76',
 TOLERANCE='20%',
 MATERIAL='X6S',
 BOM_COST='PROC',
 PHYS_PAGE='76',
 XY='(-1600,4450)',
 ROT='0',
 VER='1',
 VALUE='22.0UF',
 PACK_TYPE='0603V',
 PART_NUMBER='E15431-004',
 LOCATION='C3D5',
 ROOM='PVCCIN_CPU1_DECAP_VR',
 GROUP='PWR_MCP_CAP',
 CDS_LIB='dev_discrete',
 CDS_PART_NAME='CAP_A_0603V-22.0UF,4V,20%,X6S,A',
 VOLTAGE='4V',
 PRIM_FILE='./archive_libs/discrete/cap_a/chips/chips.prt';

PART_NAME
 C3D6 'CAP_A_0603V-22.0UF,4V,20%,X6S,A':
 GROUP='PWR_MCP_CAP',
 ROOM='PVCCIN_CPU1_DECAP_VR';

SECTION_NUMBER 1
 '@BASEBOARD_FAB2_LIB.BASEBOARD_FAB2(SCH_1):PAGE76_I170@DEV_DISCRETE.CAP_A(CHIPS)':
 C_PATH='@baseboard_fab2_lib.baseboard_fab2(sch_1):page76_i170@dev_discrete.cap_~
a(chips)',
 P_PATH='@baseboard_fab2_lib.baseboard_fab2(sch_1):page76_i170@dev_discrete.cap_~
a(chips)',
 PATH='I170',
 DRAWING='@BASEBOARD_FAB2_LIB.BASEBOARD_FAB2(SCH_1):PAGE76',
 TOLERANCE='20%',
 MATERIAL='X6S',
 BOM_COST='PROC',
 PHYS_PAGE='76',
 XY='(-725,4450)',
 ROT='0',
 VER='1',
 VALUE='22.0UF',
 PACK_TYPE='0603V',
 PART_NUMBER='E15431-004',
 LOCATION='C3D6',
 ROOM='PVCCIN_CPU1_DECAP_VR',
 GROUP='PWR_MCP_CAP',
 CDS_LIB='dev_discrete',
 CDS_PART_NAME='CAP_A_0603V-22.0UF,4V,20%,X6S,A',
 VOLTAGE='4V',
 PRIM_FILE='./archive_libs/discrete/cap_a/chips/chips.prt';

PART_NAME
 C3D7 'CAP_A_0603V-22.0UF,4V,20%,X6S,A':
 GROUP='PWR_MCP_CAP',
 ROOM='PVCCIN_CPU1_DECAP_VR';

SECTION_NUMBER 1
 '@BASEBOARD_FAB2_LIB.BASEBOARD_FAB2(SCH_1):PAGE76_I164@DEV_DISCRETE.CAP_A(CHIPS)':
 C_PATH='@baseboard_fab2_lib.baseboard_fab2(sch_1):page76_i164@dev_discrete.cap_~
a(chips)',
 P_PATH='@baseboard_fab2_lib.baseboard_fab2(sch_1):page76_i164@dev_discrete.cap_~
a(chips)',
 PATH='I164',
 DRAWING='@BASEBOARD_FAB2_LIB.BASEBOARD_FAB2(SCH_1):PAGE76',
 TOLERANCE='20%',
 MATERIAL='X6S',
 PHYS_PAGE='76',
 XY='(-4000,4450)',
 ROT='0',
 VER='1',
 VALUE='22.0UF',
 PACK_TYPE='0603V',
 PART_NUMBER='E15431-004',
 LOCATION='C3D7',
 ROOM='PVCCIN_CPU1_DECAP_VR',
 GROUP='PWR_MCP_CAP',
 CDS_LIB='dev_discrete',
 CDS_PART_NAME='CAP_A_0603V-22.0UF,4V,20%,X6S,A',
 VOLTAGE='4V',
 PRIM_FILE='./archive_libs/discrete/cap_a/chips/chips.prt';

PART_NAME
 C3D8 'CAP_A_0603V-22.0UF,4V,20%,X6S,A':
 GROUP='PWR_MLCC_CAP',
 ROOM='PVCCIN_CPU1_DECAP_VR';

SECTION_NUMBER 1
 '@BASEBOARD_FAB2_LIB.BASEBOARD_FAB2(SCH_1):PAGE76_I18@DEV_DISCRETE.CAP_A(CHIPS)':
 C_PATH='@baseboard_fab2_lib.baseboard_fab2(sch_1):page76_i18@dev_discrete.cap_a~
(chips)',
 P_PATH='@baseboard_fab2_lib.baseboard_fab2(sch_1):page76_i18@dev_discrete.cap_a~
(chips)',
 PATH='I18',
 DRAWING='@BASEBOARD_FAB2_LIB.BASEBOARD_FAB2(SCH_1):PAGE76',
 TOLERANCE='20%',
 MATERIAL='X6S',
 BOM_COST='PROC',
 PHYS_PAGE='76',
 XY='(-2650,3750)',
 ROT='0',
 VER='1',
 VALUE='22.0UF',
 PACK_TYPE='0603V',
 PART_NUMBER='E15431-004',
 LOCATION='C3D8',
 ROOM='PVCCIN_CPU1_DECAP_VR',
 GROUP='PWR_MLCC_CAP',
 CDS_LIB='dev_discrete',
 CDS_PART_NAME='CAP_A_0603V-22.0UF,4V,20%,X6S,A',
 VOLTAGE='4V',
 PRIM_FILE='./archive_libs/discrete/cap_a/chips/chips.prt';

PART_NAME
 C3D9 'CAP_A_0603V-22.0UF,4V,20%,X6S,A':
 GROUP='PWR_MLCC_CAP',
 ROOM='PVCCIN_CPU1_DECAP_VR';

SECTION_NUMBER 1
 '@BASEBOARD_FAB2_LIB.BASEBOARD_FAB2(SCH_1):PAGE76_I15@DEV_DISCRETE.CAP_A(CHIPS)':
 C_PATH='@baseboard_fab2_lib.baseboard_fab2(sch_1):page76_i15@dev_discrete.cap_a~
(chips)',
 P_PATH='@baseboard_fab2_lib.baseboard_fab2(sch_1):page76_i15@dev_discrete.cap_a~
(chips)',
 PATH='I15',
 DRAWING='@BASEBOARD_FAB2_LIB.BASEBOARD_FAB2(SCH_1):PAGE76',
 TOLERANCE='20%',
 MATERIAL='X6S',
 BOM_COST='PROC',
 PHYS_PAGE='76',
 XY='(-2350,3750)',
 ROT='0',
 VER='1',
 VALUE='22.0UF',
 PACK_TYPE='0603V',
 PART_NUMBER='E15431-004',
 LOCATION='C3D9',
 ROOM='PVCCIN_CPU1_DECAP_VR',
 GROUP='PWR_MLCC_CAP',
 CDS_LIB='dev_discrete',
 CDS_PART_NAME='CAP_A_0603V-22.0UF,4V,20%,X6S,A',
 VOLTAGE='4V',
 PRIM_FILE='./archive_libs/discrete/cap_a/chips/chips.prt';

PART_NAME
 C3D10 'CAP_A_0603V-22.0UF,4V,20%,X6S,A':
 GROUP='PWR_MCP_CAP',
 ROOM='PVCCIN_CPU1_DECAP_VR';

SECTION_NUMBER 1
 '@BASEBOARD_FAB2_LIB.BASEBOARD_FAB2(SCH_1):PAGE76_I196@DEV_DISCRETE.CAP_A(CHIPS)':
 C_PATH='@baseboard_fab2_lib.baseboard_fab2(sch_1):page76_i196@dev_discrete.cap_~
a(chips)',
 P_PATH='@baseboard_fab2_lib.baseboard_fab2(sch_1):page76_i196@dev_discrete.cap_~
a(chips)',
 PATH='I196',
 DRAWING='@BASEBOARD_FAB2_LIB.BASEBOARD_FAB2(SCH_1):PAGE76',
 TOLERANCE='20%',
 MATERIAL='X6S',
 BOM_COST='PROC',
 PHYS_PAGE='76',
 XY='(-1975,3775)',
 ROT='0',
 VER='1',
 VALUE='22.0UF',
 PACK_TYPE='0603V',
 PART_NUMBER='E15431-004',
 LOCATION='C3D10',
 ROOM='PVCCIN_CPU1_DECAP_VR',
 GROUP='PWR_MCP_CAP',
 CDS_LIB='dev_discrete',
 CDS_PART_NAME='CAP_A_0603V-22.0UF,4V,20%,X6S,A',
 VOLTAGE='4V',
 PRIM_FILE='./archive_libs/discrete/cap_a/chips/chips.prt';

PART_NAME
 C3D11 'CAP_A_0603V-22.0UF,4V,20%,X6S,A':
 GROUP='PWR_MCP_CAP',
 ROOM='PVCCIN_CPU1_DECAP_VR';

SECTION_NUMBER 1
 '@BASEBOARD_FAB2_LIB.BASEBOARD_FAB2(SCH_1):PAGE76_I7@DEV_DISCRETE.CAP_A(CHIPS)':
 C_PATH='@baseboard_fab2_lib.baseboard_fab2(sch_1):page76_i7@dev_discrete.cap_a(~
chips)',
 P_PATH='@baseboard_fab2_lib.baseboard_fab2(sch_1):page76_i7@dev_discrete.cap_a(~
chips)',
 PATH='I7',
 DRAWING='@BASEBOARD_FAB2_LIB.BASEBOARD_FAB2(SCH_1):PAGE76',
 TOLERANCE='20%',
 MATERIAL='X6S',
 BOM_COST='PROC',
 PHYS_PAGE='76',
 XY='(-2450,4450)',
 ROT='0',
 VER='1',
 VALUE='22.0UF',
 PACK_TYPE='0603V',
 PART_NUMBER='E15431-004',
 LOCATION='C3D11',
 ROOM='PVCCIN_CPU1_DECAP_VR',
 GROUP='PWR_MCP_CAP',
 CDS_LIB='dev_discrete',
 CDS_PART_NAME='CAP_A_0603V-22.0UF,4V,20%,X6S,A',
 VOLTAGE='4V',
 PRIM_FILE='./archive_libs/discrete/cap_a/chips/chips.prt';

PART_NAME
 C3D12 'CAP_A_0603V-22.0UF,4V,20%,X6S,A':
 GROUP='PWR_MCP_CAP',
 ROOM='PVCCIN_CPU1_DECAP_VR';

SECTION_NUMBER 1
 '@BASEBOARD_FAB2_LIB.BASEBOARD_FAB2(SCH_1):PAGE76_I4@DEV_DISCRETE.CAP_A(CHIPS)':
 C_PATH='@baseboard_fab2_lib.baseboard_fab2(sch_1):page76_i4@dev_discrete.cap_a(~
chips)',
 P_PATH='@baseboard_fab2_lib.baseboard_fab2(sch_1):page76_i4@dev_discrete.cap_a(~
chips)',
 PATH='I4',
 DRAWING='@BASEBOARD_FAB2_LIB.BASEBOARD_FAB2(SCH_1):PAGE76',
 TOLERANCE='20%',
 MATERIAL='X6S',
 BOM_COST='PROC',
 PHYS_PAGE='76',
 XY='(-1875,4450)',
 ROT='0',
 VER='1',
 VALUE='22.0UF',
 PACK_TYPE='0603V',
 PART_NUMBER='E15431-004',
 LOCATION='C3D12',
 ROOM='PVCCIN_CPU1_DECAP_VR',
 GROUP='PWR_MCP_CAP',
 CDS_LIB='dev_discrete',
 CDS_PART_NAME='CAP_A_0603V-22.0UF,4V,20%,X6S,A',
 VOLTAGE='4V',
 PRIM_FILE='./archive_libs/discrete/cap_a/chips/chips.prt';

PART_NAME
 C3D13 'CAP_A_0603V-22.0UF,4V,20%,X6S,A':
 GROUP='PWR_MCP_CAP',
 ROOM='PVCCIN_CPU1_DECAP_VR';

SECTION_NUMBER 1
 '@BASEBOARD_FAB2_LIB.BASEBOARD_FAB2(SCH_1):PAGE76_I8@DEV_DISCRETE.CAP_A(CHIPS)':
 C_PATH='@baseboard_fab2_lib.baseboard_fab2(sch_1):page76_i8@dev_discrete.cap_a(~
chips)',
 P_PATH='@baseboard_fab2_lib.baseboard_fab2(sch_1):page76_i8@dev_discrete.cap_a(~
chips)',
 PATH='I8',
 DRAWING='@BASEBOARD_FAB2_LIB.BASEBOARD_FAB2(SCH_1):PAGE76',
 TOLERANCE='20%',
 MATERIAL='X6S',
 BOM_COST='PROC',
 PHYS_PAGE='76',
 XY='(-2975,4450)',
 ROT='0',
 VER='1',
 VALUE='22.0UF',
 PACK_TYPE='0603V',
 PART_NUMBER='E15431-004',
 LOCATION='C3D13',
 ROOM='PVCCIN_CPU1_DECAP_VR',
 GROUP='PWR_MCP_CAP',
 CDS_LIB='dev_discrete',
 CDS_PART_NAME='CAP_A_0603V-22.0UF,4V,20%,X6S,A',
 VOLTAGE='4V',
 PRIM_FILE='./archive_libs/discrete/cap_a/chips/chips.prt';

PART_NAME
 C3D14 'CAP_A_0603V-22.0UF,4V,20%,X6S,A':
 GROUP='PWR_MCP_CAP',
 ROOM='PVCCIN_CPU1_DECAP_VR';

SECTION_NUMBER 1
 '@BASEBOARD_FAB2_LIB.BASEBOARD_FAB2(SCH_1):PAGE76_I171@DEV_DISCRETE.CAP_A(CHIPS)':
 C_PATH='@baseboard_fab2_lib.baseboard_fab2(sch_1):page76_i171@dev_discrete.cap_~
a(chips)',
 P_PATH='@baseboard_fab2_lib.baseboard_fab2(sch_1):page76_i171@dev_discrete.cap_~
a(chips)',
 PATH='I171',
 DRAWING='@BASEBOARD_FAB2_LIB.BASEBOARD_FAB2(SCH_1):PAGE76',
 TOLERANCE='20%',
 MATERIAL='X6S',
 BOM_COST='PROC',
 PHYS_PAGE='76',
 XY='(-2725,4450)',
 ROT='0',
 VER='1',
 VALUE='22.0UF',
 PACK_TYPE='0603V',
 PART_NUMBER='E15431-004',
 LOCATION='C3D14',
 ROOM='PVCCIN_CPU1_DECAP_VR',
 GROUP='PWR_MCP_CAP',
 CDS_LIB='dev_discrete',
 CDS_PART_NAME='CAP_A_0603V-22.0UF,4V,20%,X6S,A',
 VOLTAGE='4V',
 PRIM_FILE='./archive_libs/discrete/cap_a/chips/chips.prt';

PART_NAME
 C3D15 'CAP_A_0603V-22.0UF,4V,20%,X6S,A':
 GROUP='PWR_MLCC_CAP',
 ROOM='PVCCIN_CPU1_DECAP_VR';

SECTION_NUMBER 1
 '@BASEBOARD_FAB2_LIB.BASEBOARD_FAB2(SCH_1):PAGE76_I174@DEV_DISCRETE.CAP_A(CHIPS)':
 C_PATH='@baseboard_fab2_lib.baseboard_fab2(sch_1):page76_i174@dev_discrete.cap_~
a(chips)',
 P_PATH='@baseboard_fab2_lib.baseboard_fab2(sch_1):page76_i174@dev_discrete.cap_~
a(chips)',
 PATH='I174',
 DRAWING='@BASEBOARD_FAB2_LIB.BASEBOARD_FAB2(SCH_1):PAGE76',
 TOLERANCE='20%',
 MATERIAL='X6S',
 BOM_COST='PROC',
 PHYS_PAGE='76',
 XY='(-3550,3750)',
 ROT='0',
 VER='1',
 VALUE='22.0UF',
 PACK_TYPE='0603V',
 PART_NUMBER='E15431-004',
 LOCATION='C3D15',
 ROOM='PVCCIN_CPU1_DECAP_VR',
 GROUP='PWR_MLCC_CAP',
 CDS_LIB='dev_discrete',
 CDS_PART_NAME='CAP_A_0603V-22.0UF,4V,20%,X6S,A',
 VOLTAGE='4V',
 PRIM_FILE='./archive_libs/discrete/cap_a/chips/chips.prt';

PART_NAME
 C3D16 'CAP_A_0603V-22.0UF,4V,20%,X6S,A':
 GROUP='PWR_MLCC_CAP',
 ROOM='PVCCIN_CPU1_DECAP_VR';

SECTION_NUMBER 1
 '@BASEBOARD_FAB2_LIB.BASEBOARD_FAB2(SCH_1):PAGE76_I176@DEV_DISCRETE.CAP_A(CHIPS)':
 C_PATH='@baseboard_fab2_lib.baseboard_fab2(sch_1):page76_i176@dev_discrete.cap_~
a(chips)',
 P_PATH='@baseboard_fab2_lib.baseboard_fab2(sch_1):page76_i176@dev_discrete.cap_~
a(chips)',
 PATH='I176',
 DRAWING='@BASEBOARD_FAB2_LIB.BASEBOARD_FAB2(SCH_1):PAGE76',
 TOLERANCE='20%',
 MATERIAL='X6S',
 BOM_COST='PROC',
 PHYS_PAGE='76',
 XY='(-2950,3750)',
 ROT='0',
 VER='1',
 VALUE='22.0UF',
 PACK_TYPE='0603V',
 PART_NUMBER='E15431-004',
 LOCATION='C3D16',
 ROOM='PVCCIN_CPU1_DECAP_VR',
 GROUP='PWR_MLCC_CAP',
 CDS_LIB='dev_discrete',
 CDS_PART_NAME='CAP_A_0603V-22.0UF,4V,20%,X6S,A',
 VOLTAGE='4V',
 PRIM_FILE='./archive_libs/discrete/cap_a/chips/chips.prt';

PART_NAME
 C3D17 'CAP_A_0603V-22.0UF,4V,20%,X6S,A':
 GROUP='PWR_MCP_CAP',
 ROOM='PVCCIN_CPU1_DECAP_VR';

SECTION_NUMBER 1
 '@BASEBOARD_FAB2_LIB.BASEBOARD_FAB2(SCH_1):PAGE76_I166@DEV_DISCRETE.CAP_A(CHIPS)':
 C_PATH='@baseboard_fab2_lib.baseboard_fab2(sch_1):page76_i166@dev_discrete.cap_~
a(chips)',
 P_PATH='@baseboard_fab2_lib.baseboard_fab2(sch_1):page76_i166@dev_discrete.cap_~
a(chips)',
 PATH='I166',
 DRAWING='@BASEBOARD_FAB2_LIB.BASEBOARD_FAB2(SCH_1):PAGE76',
 TOLERANCE='20%',
 MATERIAL='X6S',
 BOM_COST='PROC',
 PHYS_PAGE='76',
 XY='(-3500,4450)',
 ROT='0',
 VER='1',
 VALUE='22.0UF',
 PACK_TYPE='0603V',
 PART_NUMBER='E15431-004',
 LOCATION='C3D17',
 ROOM='PVCCIN_CPU1_DECAP_VR',
 GROUP='PWR_MCP_CAP',
 CDS_LIB='dev_discrete',
 CDS_PART_NAME='CAP_A_0603V-22.0UF,4V,20%,X6S,A',
 VOLTAGE='4V',
 PRIM_FILE='./archive_libs/discrete/cap_a/chips/chips.prt';

PART_NAME
 C3D18 'CAP_A_0603V-22.0UF,4V,20%,X6S,A':
 GROUP='PWR_MCP_CAP',
 ROOM='PVCCIN_CPU1_DECAP_VR';

SECTION_NUMBER 1
 '@BASEBOARD_FAB2_LIB.BASEBOARD_FAB2(SCH_1):PAGE76_I169@DEV_DISCRETE.CAP_A(CHIPS)':
 C_PATH='@baseboard_fab2_lib.baseboard_fab2(sch_1):page76_i169@dev_discrete.cap_~
a(chips)',
 P_PATH='@baseboard_fab2_lib.baseboard_fab2(sch_1):page76_i169@dev_discrete.cap_~
a(chips)',
 PATH='I169',
 DRAWING='@BASEBOARD_FAB2_LIB.BASEBOARD_FAB2(SCH_1):PAGE76',
 TOLERANCE='20%',
 MATERIAL='X6S',
 BOM_COST='PROC',
 PHYS_PAGE='76',
 XY='(-975,4450)',
 ROT='0',
 VER='1',
 VALUE='22.0UF',
 PACK_TYPE='0603V',
 PART_NUMBER='E15431-004',
 LOCATION='C3D18',
 ROOM='PVCCIN_CPU1_DECAP_VR',
 GROUP='PWR_MCP_CAP',
 CDS_LIB='dev_discrete',
 CDS_PART_NAME='CAP_A_0603V-22.0UF,4V,20%,X6S,A',
 VOLTAGE='4V',
 PRIM_FILE='./archive_libs/discrete/cap_a/chips/chips.prt';

PART_NAME
 C3D19 'CAP_A_0603V-22.0UF,4V,20%,X6S,A':
 GROUP='PWR_MCP_CAP',
 ROOM='PVCCIN_CPU1_DECAP_VR';

SECTION_NUMBER 1
 '@BASEBOARD_FAB2_LIB.BASEBOARD_FAB2(SCH_1):PAGE76_I208@DEV_DISCRETE.CAP_A(CHIPS)':
 C_PATH='@baseboard_fab2_lib.baseboard_fab2(sch_1):page76_i208@dev_discrete.cap_~
a(chips)',
 P_PATH='@baseboard_fab2_lib.baseboard_fab2(sch_1):page76_i208@dev_discrete.cap_~
a(chips)',
 PATH='I208',
 DRAWING='@BASEBOARD_FAB2_LIB.BASEBOARD_FAB2(SCH_1):PAGE76',
 TOLERANCE='20%',
 MATERIAL='X6S',
 BOM_COST='PROC',
 PHYS_PAGE='76',
 XY='(-975,3775)',
 ROT='0',
 VER='1',
 VALUE='22.0UF',
 PACK_TYPE='0603V',
 PART_NUMBER='E15431-004',
 LOCATION='C3D19',
 ROOM='PVCCIN_CPU1_DECAP_VR',
 GROUP='PWR_MCP_CAP',
 CDS_LIB='dev_discrete',
 CDS_PART_NAME='CAP_A_0603V-22.0UF,4V,20%,X6S,A',
 VOLTAGE='4V',
 PRIM_FILE='./archive_libs/discrete/cap_a/chips/chips.prt';

PART_NAME
 C3D20 'CAP_A_0603V-22.0UF,4V,20%,X6S,A':
 GROUP='PWR_MCP_CAP',
 ROOM='PVCCIN_CPU1_DECAP_VR';

SECTION_NUMBER 1
 '@BASEBOARD_FAB2_LIB.BASEBOARD_FAB2(SCH_1):PAGE76_I207@DEV_DISCRETE.CAP_A(CHIPS)':
 C_PATH='@baseboard_fab2_lib.baseboard_fab2(sch_1):page76_i207@dev_discrete.cap_~
a(chips)',
 P_PATH='@baseboard_fab2_lib.baseboard_fab2(sch_1):page76_i207@dev_discrete.cap_~
a(chips)',
 PATH='I207',
 DRAWING='@BASEBOARD_FAB2_LIB.BASEBOARD_FAB2(SCH_1):PAGE76',
 TOLERANCE='20%',
 MATERIAL='X6S',
 BOM_COST='PROC',
 PHYS_PAGE='76',
 XY='(-750,3775)',
 ROT='0',
 VER='1',
 VALUE='22.0UF',
 PACK_TYPE='0603V',
 PART_NUMBER='E15431-004',
 LOCATION='C3D20',
 ROOM='PVCCIN_CPU1_DECAP_VR',
 GROUP='PWR_MCP_CAP',
 CDS_LIB='dev_discrete',
 CDS_PART_NAME='CAP_A_0603V-22.0UF,4V,20%,X6S,A',
 VOLTAGE='4V',
 PRIM_FILE='./archive_libs/discrete/cap_a/chips/chips.prt';

PART_NAME
 C3D21 'CAP_A_0603V-22.0UF,4V,20%,X6S,A':
 GROUP='PWR_MCP_CAP',
 ROOM='PVCCIN_CPU1_DECAP_VR';

SECTION_NUMBER 1
 '@BASEBOARD_FAB2_LIB.BASEBOARD_FAB2(SCH_1):PAGE76_I1@DEV_DISCRETE.CAP_A(CHIPS)':
 C_PATH='@baseboard_fab2_lib.baseboard_fab2(sch_1):page76_i1@dev_discrete.cap_a(~
chips)',
 P_PATH='@baseboard_fab2_lib.baseboard_fab2(sch_1):page76_i1@dev_discrete.cap_a(~
chips)',
 PATH='I1',
 DRAWING='@BASEBOARD_FAB2_LIB.BASEBOARD_FAB2(SCH_1):PAGE76',
 TOLERANCE='20%',
 MATERIAL='X6S',
 BOM_COST='PROC',
 PHYS_PAGE='76',
 XY='(-1275,4450)',
 ROT='0',
 VER='1',
 VALUE='22.0UF',
 PACK_TYPE='0603V',
 PART_NUMBER='E15431-004',
 LOCATION='C3D21',
 ROOM='PVCCIN_CPU1_DECAP_VR',
 GROUP='PWR_MCP_CAP',
 CDS_LIB='dev_discrete',
 CDS_PART_NAME='CAP_A_0603V-22.0UF,4V,20%,X6S,A',
 VOLTAGE='4V',
 PRIM_FILE='./archive_libs/discrete/cap_a/chips/chips.prt';

PART_NAME
 C3D22 'CAP_0805-10UF,16V,10%,X7R,G106A':
 ROOM='DB1200ZL';

SECTION_NUMBER 1
 '@BASEBOARD_FAB2_LIB.BASEBOARD_FAB2(SCH_1):PAGE102_I10@MSTR_DISCRETE.CAP(CHIPS)':
 C_PATH='@baseboard_fab2_lib.baseboard_fab2(sch_1):page102_i10@mstr_discrete.cap~
(chips)',
 P_PATH='@baseboard_fab2_lib.baseboard_fab2(sch_1):page102_i10@mstr_discrete.cap~
(chips)',
 PATH='I10',
 DRAWING='@BASEBOARD_FAB2_LIB.BASEBOARD_FAB2(SCH_1):PAGE102',
 TOLERANCE='10%',
 SEC_TYPE='0805',
 MATERIAL='X7R',
 BOM_COST='SYS_CLOCK',
 PHYS_PAGE='102',
 XY='(1975,900)',
 ROT='0',
 VER='1',
 VALUE='10UF',
 PACK_TYPE='0805',
 PART_NUMBER='G10601-001',
 LOCATION='C3D22',
 ROOM='DB1200ZL',
 SEC='1',
 CDS_LIB='mstr_discrete',
 CDS_PART_NAME='CAP_0805-10UF,16V,10%,X7R,G106A',
 VOLTAGE='16V',
 PRIM_FILE='./archive_libs/mstr_discrete/cap/chips/chips.prt';

PART_NAME
 C3D23 'CAP_A_0603V-22.0UF,4V,20%,X6S,A':
 GROUP='PWR_MLCC_CAP',
 ROOM='PVCCIN_CPU1_DECAP_VR';

SECTION_NUMBER 1
 '@BASEBOARD_FAB2_LIB.BASEBOARD_FAB2(SCH_1):PAGE76_I172@DEV_DISCRETE.CAP_A(CHIPS)':
 C_PATH='@baseboard_fab2_lib.baseboard_fab2(sch_1):page76_i172@dev_discrete.cap_~
a(chips)',
 P_PATH='@baseboard_fab2_lib.baseboard_fab2(sch_1):page76_i172@dev_discrete.cap_~
a(chips)',
 PATH='I172',
 DRAWING='@BASEBOARD_FAB2_LIB.BASEBOARD_FAB2(SCH_1):PAGE76',
 TOLERANCE='20%',
 MATERIAL='X6S',
 BOM_COST='PROC',
 PHYS_PAGE='76',
 XY='(-3850,3750)',
 ROT='0',
 VER='1',
 VALUE='22.0UF',
 PACK_TYPE='0603V',
 PART_NUMBER='E15431-004',
 LOCATION='C3D23',
 ROOM='PVCCIN_CPU1_DECAP_VR',
 GROUP='PWR_MLCC_CAP',
 CDS_LIB='dev_discrete',
 CDS_PART_NAME='CAP_A_0603V-22.0UF,4V,20%,X6S,A',
 VOLTAGE='4V',
 PRIM_FILE='./archive_libs/discrete/cap_a/chips/chips.prt';

PART_NAME
 C3D24 'CAP_A_0603V-22.0UF,4V,20%,X6S,A':
 GROUP='PWR_MLCC_CAP',
 ROOM='PVCCIN_CPU1_DECAP_VR';

SECTION_NUMBER 1
 '@BASEBOARD_FAB2_LIB.BASEBOARD_FAB2(SCH_1):PAGE76_I175@DEV_DISCRETE.CAP_A(CHIPS)':
 C_PATH='@baseboard_fab2_lib.baseboard_fab2(sch_1):page76_i175@dev_discrete.cap_~
a(chips)',
 P_PATH='@baseboard_fab2_lib.baseboard_fab2(sch_1):page76_i175@dev_discrete.cap_~
a(chips)',
 PATH='I175',
 DRAWING='@BASEBOARD_FAB2_LIB.BASEBOARD_FAB2(SCH_1):PAGE76',
 TOLERANCE='20%',
 MATERIAL='X6S',
 BOM_COST='PROC',
 PHYS_PAGE='76',
 XY='(-3250,3750)',
 ROT='0',
 VER='1',
 VALUE='22.0UF',
 PACK_TYPE='0603V',
 PART_NUMBER='E15431-004',
 LOCATION='C3D24',
 ROOM='PVCCIN_CPU1_DECAP_VR',
 GROUP='PWR_MLCC_CAP',
 CDS_LIB='dev_discrete',
 CDS_PART_NAME='CAP_A_0603V-22.0UF,4V,20%,X6S,A',
 VOLTAGE='4V',
 PRIM_FILE='./archive_libs/discrete/cap_a/chips/chips.prt';

PART_NAME
 C3D25 'CAP_A_0603V-22.0UF,4V,20%,X6S,A':
 GROUP='PWR_MLCC_CAP',
 ROOM='PVCCIN_CPU1_DECAP_VR';

SECTION_NUMBER 1
 '@BASEBOARD_FAB2_LIB.BASEBOARD_FAB2(SCH_1):PAGE225_I262@DEV_DISCRETE.CAP_A(CHIPS)':
 C_PATH='@baseboard_fab2_lib.baseboard_fab2(sch_1):page225_i262@dev_discrete.cap~
_a(chips)',
 P_PATH='@baseboard_fab2_lib.baseboard_fab2(sch_1):page225_i262@dev_discrete.cap~
_a(chips)',
 PATH='I262',
 DRAWING='@BASEBOARD_FAB2_LIB.BASEBOARD_FAB2(SCH_1):PAGE225',
 TOLERANCE='20%',
 SEC_TYPE='0603V',
 MATERIAL='X6S',
 BOM_COST='PROC',
 PHYS_PAGE='225',
 XY='(1600,2100)',
 ROT='0',
 VER='1',
 VALUE='22.0UF',
 PACK_TYPE='0603V',
 PART_NUMBER='E15431-004',
 LOCATION='C3D25',
 ROOM='PVCCIN_CPU1_DECAP_VR',
 GROUP='PWR_MLCC_CAP',
 SEC='1',
 CDS_LIB='dev_discrete',
 CDS_PART_NAME='CAP_A_0603V-22.0UF,4V,20%,X6S,A',
 VOLTAGE='4V',
 PRIM_FILE='./archive_libs/discrete/cap_a/chips/chips.prt';

PART_NAME
 C3D27 'CAP_A_0402V-0.1UF,16V,10%,EMPTA':
 ROOM='PVCCIO_CPU1';

SECTION_NUMBER 1
 '@BASEBOARD_FAB2_LIB.BASEBOARD_FAB2(SCH_1):PAGE214_I96@DEV_DISCRETE.CAP_A(CHIPS)':
 C_PATH='@baseboard_fab2_lib.baseboard_fab2(sch_1):page214_i96@dev_discrete.cap_~
a(chips)',
 P_PATH='@baseboard_fab2_lib.baseboard_fab2(sch_1):page214_i96@dev_discrete.cap_~
a(chips)',
 PATH='I96',
 DRAWING='@BASEBOARD_FAB2_LIB.BASEBOARD_FAB2(SCH_1):PAGE214',
 TOLERANCE='10%',
 SEC_TYPE='0402V',
 MATERIAL='EMPTY',
 BOM_COST='PROC_VRD_VCCIO_CPU1',
 PHYS_PAGE='214',
 XY='(-1725,1575)',
 ROT='0',
 VER='1',
 VALUE='0.1UF',
 PACK_TYPE='0402V',
 PART_NUMBER='A36096-030',
 LOCATION='C3D27',
 ROOM='PVCCIO_CPU1',
 SEC='1',
 CDS_LIB='dev_discrete',
 CDS_PART_NAME='CAP_A_0402V-0.1UF,16V,10%,EMPTA',
 VOLTAGE='16V',
 PRIM_FILE='./archive_libs/discrete/cap_a/chips/chips.prt';

PART_NAME
 C3E1 'CAP_A_0603V-22.0UF,4V,20%,X6S,A':
 GROUP='PWR_MLCC_CAP',
 ROOM='PVCCIO_CPU1',
 REUSE_ID='281';

SECTION_NUMBER 1
 '@BASEBOARD_FAB2_LIB.BASEBOARD_FAB2(SCH_1):PAGE214_I108@DEV_DISCRETE.CAP_A(CHIPS)':
 C_PATH='@baseboard_fab2_lib.baseboard_fab2(sch_1):page214_i108@dev_discrete.cap~
_a(chips)',
 P_PATH='@baseboard_fab2_lib.baseboard_fab2(sch_1):page214_i108@dev_discrete.cap~
_a(chips)',
 PATH='I108',
 DRAWING='@BASEBOARD_FAB2_LIB.BASEBOARD_FAB2(SCH_1):PAGE214',
 TOLERANCE='20%',
 SEC_TYPE='0603V',
 MATERIAL='X6S',
 BOM_COST='PROC_VRD_PVCCIO_CPU1',
 PHYS_PAGE='214',
 REUSE_ID='281',
 XY='(3650,3450)',
 ROT='0',
 VER='1',
 VALUE='22.0UF',
 PACK_TYPE='0603V',
 PART_NUMBER='E15431-004',
 LOCATION='C3E1',
 ROOM='PVCCIO_CPU1',
 GROUP='PWR_MLCC_CAP',
 SEC='1',
 CDS_LIB='dev_discrete',
 CDS_PART_NAME='CAP_A_0603V-22.0UF,4V,20%,X6S,A',
 VOLTAGE='4V',
 PRIM_FILE='./archive_libs/discrete/cap_a/chips/chips.prt';

PART_NAME
 C3F1 'CAP_A_0603V-47UF,4V,20%,X5R,60A':
 GROUP='PWR_MCP_CAP';

SECTION_NUMBER 1
 '@BASEBOARD_FAB2_LIB.BASEBOARD_FAB2(SCH_1):PAGE193_I140@DEV_DISCRETE.CAP_A(CHIPS)':
 C_PATH='@baseboard_fab2_lib.baseboard_fab2(sch_1):page193_i140@dev_discrete.cap~
_a(chips)',
 P_PATH='@baseboard_fab2_lib.baseboard_fab2(sch_1):page193_i140@dev_discrete.cap~
_a(chips)',
 PATH='I140',
 DRAWING='@BASEBOARD_FAB2_LIB.BASEBOARD_FAB2(SCH_1):PAGE193',
 TOLERANCE='20%',
 SEC_TYPE='0603V',
 MATERIAL='X5R',
 PHYS_PAGE='193',
 XY='(-1900,2450)',
 ROT='0',
 VER='1',
 VALUE='47UF',
 PACK_TYPE='0603V',
 PART_NUMBER='602433-106',
 LOCATION='C3F1',
 GROUP='PWR_MCP_CAP',
 SEC='1',
 CDS_LIB='dev_discrete',
 CDS_PART_NAME='CAP_A_0603V-47UF,4V,20%,X5R,60A',
 VOLTAGE='4V',
 PRIM_FILE='./archive_libs/discrete/cap_a/chips/chips.prt';

PART_NAME
 C3F2 'CAP_A_0402V-0.1UF,16V,10%,X7R,A':
 ROOM='CLOCK_CPU1_OSC';

SECTION_NUMBER 1
 '@BASEBOARD_FAB2_LIB.BASEBOARD_FAB2(SCH_1):PAGE104_I34@DEV_DISCRETE.CAP_A(CHIPS)':
 C_PATH='@baseboard_fab2_lib.baseboard_fab2(sch_1):page104_i34@dev_discrete.cap_~
a(chips)',
 P_PATH='@baseboard_fab2_lib.baseboard_fab2(sch_1):page104_i34@dev_discrete.cap_~
a(chips)',
 PATH='I34',
 DRAWING='@BASEBOARD_FAB2_LIB.BASEBOARD_FAB2(SCH_1):PAGE104',
 TOLERANCE='10%',
 SEC_TYPE='0402V',
 MATERIAL='X7R',
 PHYS_PAGE='104',
 XY='(-4575,4225)',
 ROT='0',
 VER='1',
 VALUE='0.1UF',
 PACK_TYPE='0402V',
 PART_NUMBER='A36096-030',
 LOCATION='C3F2',
 ROOM='CLOCK_CPU1_OSC',
 SEC='1',
 CDS_LIB='dev_discrete',
 CDS_PART_NAME='CAP_A_0402V-0.1UF,16V,10%,X7R,A',
 VOLTAGE='16V',
 PRIM_FILE='./archive_libs/discrete/cap_a/chips/chips.prt';

PART_NAME
 C3F3 'CAP_0603LF-10UF,4V,20%,X6S,E15A':
 GROUP='PWR_MLCC_CAP',
 ROOM='PVPP_KLM_VR';

SECTION_NUMBER 1
 '@BASEBOARD_FAB2_LIB.BASEBOARD_FAB2(SCH_1):PAGE233_I116@MSTR_DISCRETE.CAP(CHIPS)':
 C_PATH='@baseboard_fab2_lib.baseboard_fab2(sch_1):page233_i116@mstr_discrete.ca~
p(chips)',
 P_PATH='@baseboard_fab2_lib.baseboard_fab2(sch_1):page233_i116@mstr_discrete.ca~
p(chips)',
 PATH='I116',
 DRAWING='@BASEBOARD_FAB2_LIB.BASEBOARD_FAB2(SCH_1):PAGE233',
 TOLERANCE='20%',
 MATERIAL='X6S',
 BOM_COST='MEM_VRD_PVPP_AB',
 PHYS_PAGE='233',
 XY='(-6750,725)',
 ROT='0',
 VER='1',
 VALUE='10UF',
 PACK_TYPE='0603LF',
 PART_NUMBER='E15431-001',
 LOCATION='C3F3',
 ROOM='PVPP_KLM_VR',
 GROUP='PWR_MLCC_CAP',
 CDS_LIB='mstr_discrete',
 CDS_PART_NAME='CAP_0603LF-10UF,4V,20%,X6S,E15A',
 VOLTAGE='4V',
 PRIM_FILE='./archive_libs/mstr_discrete/cap/chips/chips.prt';

PART_NAME
 C3F4 'CAP_0603LF-10UF,4V,20%,X6S,E15A':
 GROUP='PWR_MLCC_CAP',
 ROOM='PVPP_KLM_VR';

SECTION_NUMBER 1
 '@BASEBOARD_FAB2_LIB.BASEBOARD_FAB2(SCH_1):PAGE233_I117@MSTR_DISCRETE.CAP(CHIPS)':
 C_PATH='@baseboard_fab2_lib.baseboard_fab2(sch_1):page233_i117@mstr_discrete.ca~
p(chips)',
 P_PATH='@baseboard_fab2_lib.baseboard_fab2(sch_1):page233_i117@mstr_discrete.ca~
p(chips)',
 PATH='I117',
 DRAWING='@BASEBOARD_FAB2_LIB.BASEBOARD_FAB2(SCH_1):PAGE233',
 TOLERANCE='20%',
 MATERIAL='X6S',
 BOM_COST='MEM_VRD_PVPP_AB',
 PHYS_PAGE='233',
 XY='(-6475,725)',
 ROT='0',
 VER='1',
 VALUE='10UF',
 PACK_TYPE='0603LF',
 PART_NUMBER='E15431-001',
 LOCATION='C3F4',
 ROOM='PVPP_KLM_VR',
 GROUP='PWR_MLCC_CAP',
 CDS_LIB='mstr_discrete',
 CDS_PART_NAME='CAP_0603LF-10UF,4V,20%,X6S,E15A',
 VOLTAGE='4V',
 PRIM_FILE='./archive_libs/mstr_discrete/cap/chips/chips.prt';

PART_NAME
 C3G1 'CAP_A_0603V-47UF,4V,20%,X5R,60A':
 GROUP='PWR_MLCC_CAP';

SECTION_NUMBER 1
 '@BASEBOARD_FAB2_LIB.BASEBOARD_FAB2(SCH_1):PAGE225_I284@DEV_DISCRETE.CAP_A(CHIPS)':
 C_PATH='@baseboard_fab2_lib.baseboard_fab2(sch_1):page225_i284@dev_discrete.cap~
_a(chips)',
 P_PATH='@baseboard_fab2_lib.baseboard_fab2(sch_1):page225_i284@dev_discrete.cap~
_a(chips)',
 PATH='I284',
 DRAWING='@BASEBOARD_FAB2_LIB.BASEBOARD_FAB2(SCH_1):PAGE225',
 BOM_SS='E15431-004',
 TOLERANCE='20%',
 SEC_TYPE='0603V',
 MATERIAL='X5R',
 PHYS_PAGE='225',
 XY='(675,250)',
 ROT='0',
 VER='1',
 VALUE='47UF',
 PACK_TYPE='0603V',
 PART_NUMBER='602433-106',
 LOCATION='C3G1',
 GROUP='PWR_MLCC_CAP',
 SEC='1',
 CDS_LIB='dev_discrete',
 CDS_PART_NAME='CAP_A_0603V-47UF,4V,20%,X5R,60A',
 VOLTAGE='4V',
 PRIM_FILE='./archive_libs/discrete/cap_a/chips/chips.prt';

PART_NAME
 C3G2 'CAP_A_0603V-47UF,4V,20%,X5R,60A':
 GROUP='PWR_MLCC_CAP';

SECTION_NUMBER 1
 '@BASEBOARD_FAB2_LIB.BASEBOARD_FAB2(SCH_1):PAGE225_I285@DEV_DISCRETE.CAP_A(CHIPS)':
 C_PATH='@baseboard_fab2_lib.baseboard_fab2(sch_1):page225_i285@dev_discrete.cap~
_a(chips)',
 P_PATH='@baseboard_fab2_lib.baseboard_fab2(sch_1):page225_i285@dev_discrete.cap~
_a(chips)',
 PATH='I285',
 DRAWING='@BASEBOARD_FAB2_LIB.BASEBOARD_FAB2(SCH_1):PAGE225',
 BOM_SS='E15431-004',
 TOLERANCE='20%',
 SEC_TYPE='0603V',
 MATERIAL='X5R',
 PHYS_PAGE='225',
 XY='(950,250)',
 ROT='0',
 VER='1',
 VALUE='47UF',
 PACK_TYPE='0603V',
 PART_NUMBER='602433-106',
 LOCATION='C3G2',
 GROUP='PWR_MLCC_CAP',
 SEC='1',
 CDS_LIB='dev_discrete',
 CDS_PART_NAME='CAP_A_0603V-47UF,4V,20%,X5R,60A',
 VOLTAGE='4V',
 PRIM_FILE='./archive_libs/discrete/cap_a/chips/chips.prt';

PART_NAME
 C3G3 'CAP_0603LF-10UF,4V,20%,X6S,E15A':
 GROUP='PWR_MLCC_CAP',
 ROOM='PVPP_KLM_VR';

SECTION_NUMBER 1
 '@BASEBOARD_FAB2_LIB.BASEBOARD_FAB2(SCH_1):PAGE233_I118@MSTR_DISCRETE.CAP(CHIPS)':
 C_PATH='@baseboard_fab2_lib.baseboard_fab2(sch_1):page233_i118@mstr_discrete.ca~
p(chips)',
 P_PATH='@baseboard_fab2_lib.baseboard_fab2(sch_1):page233_i118@mstr_discrete.ca~
p(chips)',
 PATH='I118',
 DRAWING='@BASEBOARD_FAB2_LIB.BASEBOARD_FAB2(SCH_1):PAGE233',
 TOLERANCE='20%',
 MATERIAL='X6S',
 BOM_COST='MEM_VRD_PVPP_AB',
 PHYS_PAGE='233',
 XY='(-6175,725)',
 ROT='0',
 VER='1',
 VALUE='10UF',
 PACK_TYPE='0603LF',
 PART_NUMBER='E15431-001',
 LOCATION='C3G3',
 ROOM='PVPP_KLM_VR',
 GROUP='PWR_MLCC_CAP',
 CDS_LIB='mstr_discrete',
 CDS_PART_NAME='CAP_0603LF-10UF,4V,20%,X6S,E15A',
 VOLTAGE='4V',
 PRIM_FILE='./archive_libs/mstr_discrete/cap/chips/chips.prt';

PART_NAME
 C3G4 'CAP_0603LF-10UF,4V,20%,X6S,E15A':
 GROUP='PWR_MLCC_CAP',
 ROOM='PVPP_KLM_VR';

SECTION_NUMBER 1
 '@BASEBOARD_FAB2_LIB.BASEBOARD_FAB2(SCH_1):PAGE233_I133@MSTR_DISCRETE.CAP(CHIPS)':
 C_PATH='@baseboard_fab2_lib.baseboard_fab2(sch_1):page233_i133@mstr_discrete.ca~
p(chips)',
 P_PATH='@baseboard_fab2_lib.baseboard_fab2(sch_1):page233_i133@mstr_discrete.ca~
p(chips)',
 PATH='I133',
 DRAWING='@BASEBOARD_FAB2_LIB.BASEBOARD_FAB2(SCH_1):PAGE233',
 TOLERANCE='20%',
 MATERIAL='X6S',
 BOM_COST='MEM_VRD_PVPP_AB',
 PHYS_PAGE='233',
 XY='(-5600,725)',
 ROT='0',
 VER='1',
 VALUE='10UF',
 PACK_TYPE='0603LF',
 PART_NUMBER='E15431-001',
 LOCATION='C3G4',
 ROOM='PVPP_KLM_VR',
 GROUP='PWR_MLCC_CAP',
 CDS_LIB='mstr_discrete',
 CDS_PART_NAME='CAP_0603LF-10UF,4V,20%,X6S,E15A',
 VOLTAGE='4V',
 PRIM_FILE='./archive_libs/mstr_discrete/cap/chips/chips.prt';

PART_NAME
 C3G5 'CAP_A_0603V-47UF,4V,20%,X5R,60A':
 GROUP='PWR_MLCC_CAP';

SECTION_NUMBER 1
 '@BASEBOARD_FAB2_LIB.BASEBOARD_FAB2(SCH_1):PAGE225_I288@DEV_DISCRETE.CAP_A(CHIPS)':
 C_PATH='@baseboard_fab2_lib.baseboard_fab2(sch_1):page225_i288@dev_discrete.cap~
_a(chips)',
 P_PATH='@baseboard_fab2_lib.baseboard_fab2(sch_1):page225_i288@dev_discrete.cap~
_a(chips)',
 PATH='I288',
 DRAWING='@BASEBOARD_FAB2_LIB.BASEBOARD_FAB2(SCH_1):PAGE225',
 BOM_SS='E15431-004',
 TOLERANCE='20%',
 SEC_TYPE='0603V',
 MATERIAL='X5R',
 PHYS_PAGE='225',
 XY='(1825,250)',
 ROT='0',
 VER='1',
 VALUE='47UF',
 PACK_TYPE='0603V',
 PART_NUMBER='602433-106',
 LOCATION='C3G5',
 GROUP='PWR_MLCC_CAP',
 SEC='1',
 CDS_LIB='dev_discrete',
 CDS_PART_NAME='CAP_A_0603V-47UF,4V,20%,X5R,60A',
 VOLTAGE='4V',
 PRIM_FILE='./archive_libs/discrete/cap_a/chips/chips.prt';

PART_NAME
 C3G6 'CAP_A_0603V-47UF,4V,20%,X5R,60A':
 GROUP='PWR_MLCC_CAP';

SECTION_NUMBER 1
 '@BASEBOARD_FAB2_LIB.BASEBOARD_FAB2(SCH_1):PAGE225_I289@DEV_DISCRETE.CAP_A(CHIPS)':
 C_PATH='@baseboard_fab2_lib.baseboard_fab2(sch_1):page225_i289@dev_discrete.cap~
_a(chips)',
 P_PATH='@baseboard_fab2_lib.baseboard_fab2(sch_1):page225_i289@dev_discrete.cap~
_a(chips)',
 PATH='I289',
 DRAWING='@BASEBOARD_FAB2_LIB.BASEBOARD_FAB2(SCH_1):PAGE225',
 BOM_SS='E15431-004',
 TOLERANCE='20%',
 SEC_TYPE='0603V',
 MATERIAL='X5R',
 PHYS_PAGE='225',
 XY='(2100,250)',
 ROT='0',
 VER='1',
 VALUE='47UF',
 PACK_TYPE='0603V',
 PART_NUMBER='602433-106',
 LOCATION='C3G6',
 GROUP='PWR_MLCC_CAP',
 SEC='1',
 CDS_LIB='dev_discrete',
 CDS_PART_NAME='CAP_A_0603V-47UF,4V,20%,X5R,60A',
 VOLTAGE='4V',
 PRIM_FILE='./archive_libs/discrete/cap_a/chips/chips.prt';

PART_NAME
 C3G7 'CAP_0603LF-10UF,4V,20%,X6S,E15A':
 GROUP='PWR_MLCC_CAP',
 ROOM='PVPP_KLM_VR';

SECTION_NUMBER 1
 '@BASEBOARD_FAB2_LIB.BASEBOARD_FAB2(SCH_1):PAGE233_I132@MSTR_DISCRETE.CAP(CHIPS)':
 C_PATH='@baseboard_fab2_lib.baseboard_fab2(sch_1):page233_i132@mstr_discrete.ca~
p(chips)',
 P_PATH='@baseboard_fab2_lib.baseboard_fab2(sch_1):page233_i132@mstr_discrete.ca~
p(chips)',
 PATH='I132',
 DRAWING='@BASEBOARD_FAB2_LIB.BASEBOARD_FAB2(SCH_1):PAGE233',
 TOLERANCE='20%',
 MATERIAL='X6S',
 BOM_COST='MEM_VRD_PVPP_AB',
 PHYS_PAGE='233',
 XY='(-5875,725)',
 ROT='0',
 VER='1',
 VALUE='10UF',
 PACK_TYPE='0603LF',
 PART_NUMBER='E15431-001',
 LOCATION='C3G7',
 ROOM='PVPP_KLM_VR',
 GROUP='PWR_MLCC_CAP',
 CDS_LIB='mstr_discrete',
 CDS_PART_NAME='CAP_0603LF-10UF,4V,20%,X6S,E15A',
 VOLTAGE='4V',
 PRIM_FILE='./archive_libs/mstr_discrete/cap/chips/chips.prt';

PART_NAME
 C3G8 'CAP_0603LF-10UF,4V,20%,X6S,E15A':
 GROUP='PWR_MLCC_CAP',
 ROOM='PVPP_KLM_VR';

SECTION_NUMBER 1
 '@BASEBOARD_FAB2_LIB.BASEBOARD_FAB2(SCH_1):PAGE233_I135@MSTR_DISCRETE.CAP(CHIPS)':
 C_PATH='@baseboard_fab2_lib.baseboard_fab2(sch_1):page233_i135@mstr_discrete.ca~
p(chips)',
 P_PATH='@baseboard_fab2_lib.baseboard_fab2(sch_1):page233_i135@mstr_discrete.ca~
p(chips)',
 PATH='I135',
 DRAWING='@BASEBOARD_FAB2_LIB.BASEBOARD_FAB2(SCH_1):PAGE233',
 TOLERANCE='20%',
 MATERIAL='X6S',
 BOM_COST='MEM_VRD_PVPP_AB',
 PHYS_PAGE='233',
 XY='(-5325,725)',
 ROT='0',
 VER='1',
 VALUE='10UF',
 PACK_TYPE='0603LF',
 PART_NUMBER='E15431-001',
 LOCATION='C3G8',
 ROOM='PVPP_KLM_VR',
 GROUP='PWR_MLCC_CAP',
 CDS_LIB='mstr_discrete',
 CDS_PART_NAME='CAP_0603LF-10UF,4V,20%,X6S,E15A',
 VOLTAGE='4V',
 PRIM_FILE='./archive_libs/mstr_discrete/cap/chips/chips.prt';

PART_NAME
 C3L1 'SC1U10V2KX-4-GP_SMD-BCG6-SC1U1A':;

SECTION_NUMBER 1
 '@BASEBOARD_FAB2_LIB.BASEBOARD_FAB2(SCH_1):PAGE236_I180@W_HDL.SC1U10V2KX-4-GP(CHIPS)':
 C_PATH='@baseboard_fab2_lib.baseboard_fab2(sch_1):page236_i180@w_hdl.\sc1u10v2k~
x-4-gp\(chips)',
 P_PATH='@baseboard_fab2_lib.baseboard_fab2(sch_1):page236_i180@w_hdl.\sc1u10v2k~
x-4-gp\(chips)',
 PATH='I180',
 DRAWING='@BASEBOARD_FAB2_LIB.BASEBOARD_FAB2(SCH_1):PAGE236',
 PACK_SIZE='0402',
 RATED='10V',
 ATTRIBUTE='1UF',
 TOLERANCE='10%',
 SEC_TYPE='SMD-BCG6',
 PHYS_PAGE='236',
 XY='(7800,4525)',
 ROT='0',
 VER='1',
 VALUE='SC1U10V2KX-4-GP',
 PACK_TYPE='SMD-BCG6',
 PART_NUMBER='78.10523.8FL',
 LOCATION='C3L1',
 SEC='1',
 CDS_LIB='w_hdl',
 CDS_PART_NAME='SC1U10V2KX-4-GP_SMD-BCG6-SC1U1A',
 PRIM_FILE='C:/<user>/w_hdl/sc1u10v2kx#2d4#2dgp/chips/chips.prt';

PART_NAME
 C3L2 'CAP_0805-10UF,16V,10%,X6S,C953A':
 ROOM='VDDQ_DEF_PWR_VR';

SECTION_NUMBER 1
 '@BASEBOARD_FAB2_LIB.BASEBOARD_FAB2(SCH_1):PAGE219_I45@MSTR_DISCRETE.CAP(CHIPS)':
 C_PATH='@baseboard_fab2_lib.baseboard_fab2(sch_1):page219_i45@mstr_discrete.cap~
(chips)',
 P_PATH='@baseboard_fab2_lib.baseboard_fab2(sch_1):page219_i45@mstr_discrete.cap~
(chips)',
 PATH='I45',
 DRAWING='@BASEBOARD_FAB2_LIB.BASEBOARD_FAB2(SCH_1):PAGE219',
 TOLERANCE='10%',
 SEC_TYPE='0805',
 MATERIAL='X6S',
 PHYS_PAGE='219',
 XY='(-2225,2425)',
 ROT='0',
 VER='1',
 VALUE='10UF',
 PACK_TYPE='0805',
 PART_NUMBER='C95333-007',
 LOCATION='C3L2',
 ROOM='VDDQ_DEF_PWR_VR',
 SEC='1',
 CDS_LIB='mstr_discrete',
 CDS_PART_NAME='CAP_0805-10UF,16V,10%,X6S,C953A',
 VOLTAGE='16V',
 PRIM_FILE='./archive_libs/mstr_discrete/cap/chips/chips.prt';

PART_NAME
 C3L4 'CAP_0805-10UF,16V,10%,X6S,C953A':
 ROOM='VDDQ_DEF_PWR_VR';

SECTION_NUMBER 1
 '@BASEBOARD_FAB2_LIB.BASEBOARD_FAB2(SCH_1):PAGE219_I46@MSTR_DISCRETE.CAP(CHIPS)':
 C_PATH='@baseboard_fab2_lib.baseboard_fab2(sch_1):page219_i46@mstr_discrete.cap~
(chips)',
 P_PATH='@baseboard_fab2_lib.baseboard_fab2(sch_1):page219_i46@mstr_discrete.cap~
(chips)',
 PATH='I46',
 DRAWING='@BASEBOARD_FAB2_LIB.BASEBOARD_FAB2(SCH_1):PAGE219',
 TOLERANCE='10%',
 SEC_TYPE='0805',
 MATERIAL='X6S',
 PHYS_PAGE='219',
 XY='(-2000,2425)',
 ROT='0',
 VER='1',
 VALUE='10UF',
 PACK_TYPE='0805',
 PART_NUMBER='C95333-007',
 LOCATION='C3L4',
 ROOM='VDDQ_DEF_PWR_VR',
 SEC='1',
 CDS_LIB='mstr_discrete',
 CDS_PART_NAME='CAP_0805-10UF,16V,10%,X6S,C953A',
 VOLTAGE='16V',
 PRIM_FILE='./archive_libs/mstr_discrete/cap/chips/chips.prt';

PART_NAME
 C3L6 'CAPP_3018-470UF,2.5V,20%,ALUM,A':
 GROUP='PWR_BULK_CAP',
 ROOM='VDDQ_DEF_PWR_VR';

SECTION_NUMBER 1
 '@BASEBOARD_FAB2_LIB.BASEBOARD_FAB2(SCH_1):PAGE220_I75@MSTR_DISCRETE.CAPP(CHIPS)':
 C_PATH='@baseboard_fab2_lib.baseboard_fab2(sch_1):page220_i75@mstr_discrete.cap~
p(chips)',
 P_PATH='@baseboard_fab2_lib.baseboard_fab2(sch_1):page220_i75@mstr_discrete.cap~
p(chips)',
 PATH='I75',
 DRAWING='@BASEBOARD_FAB2_LIB.BASEBOARD_FAB2(SCH_1):PAGE220',
 TOLERANCE='20%',
 SEC_TYPE='3018',
 MATERIAL='ALUM',
 PHYS_PAGE='220',
 XY='(2900,-100)',
 ROT='0',
 VER='1',
 VALUE='470UF',
 PACK_TYPE='3018',
 PART_NUMBER='699013-049',
 LOCATION='C3L6',
 ROOM='VDDQ_DEF_PWR_VR',
 GROUP='PWR_BULK_CAP',
 SEC='1',
 CDS_LIB='mstr_discrete',
 CDS_PART_NAME='CAPP_3018-470UF,2.5V,20%,ALUM,A',
 VOLTAGE='2.5V',
 PRIM_FILE='./archive_libs/mstr_discrete/capp/chips/chips.prt';

PART_NAME
 C3L7 'CAP_0805-10UF,16V,10%,X6S,C953A':
 ROOM='P1V05_PCH_STBY_VR';

SECTION_NUMBER 1
 '@BASEBOARD_FAB2_LIB.BASEBOARD_FAB2(SCH_1):PAGE236_I31@MSTR_DISCRETE.CAP(CHIPS)':
 C_PATH='@baseboard_fab2_lib.baseboard_fab2(sch_1):page236_i31@mstr_discrete.cap~
(chips)',
 P_PATH='@baseboard_fab2_lib.baseboard_fab2(sch_1):page236_i31@mstr_discrete.cap~
(chips)',
 PATH='I31',
 DRAWING='@BASEBOARD_FAB2_LIB.BASEBOARD_FAB2(SCH_1):PAGE236',
 TOLERANCE='10%',
 SEC_TYPE='0805',
 MATERIAL='X6S',
 PHYS_PAGE='236',
 XY='(6250,2800)',
 ROT='0',
 VER='1',
 VALUE='10UF',
 PACK_TYPE='0805',
 PART_NUMBER='C95333-007',
 LOCATION='C3L7',
 ROOM='P1V05_PCH_STBY_VR',
 SEC='1',
 CDS_LIB='mstr_discrete',
 CDS_PART_NAME='CAP_0805-10UF,16V,10%,X6S,C953A',
 VOLTAGE='16V',
 PRIM_FILE='./archive_libs/mstr_discrete/cap/chips/chips.prt';

PART_NAME
 C3L8 'CAP_0805-10UF,16V,10%,X6S,C953A':
 ROOM='PVNN_PCH_STBY';

SECTION_NUMBER 1
 '@BASEBOARD_FAB2_LIB.BASEBOARD_FAB2(SCH_1):PAGE236_I26@MSTR_DISCRETE.CAP(CHIPS)':
 C_PATH='@baseboard_fab2_lib.baseboard_fab2(sch_1):page236_i26@mstr_discrete.cap~
(chips)',
 P_PATH='@baseboard_fab2_lib.baseboard_fab2(sch_1):page236_i26@mstr_discrete.cap~
(chips)',
 PATH='I26',
 DRAWING='@BASEBOARD_FAB2_LIB.BASEBOARD_FAB2(SCH_1):PAGE236',
 TOLERANCE='10%',
 SEC_TYPE='0805',
 MATERIAL='X6S',
 PHYS_PAGE='236',
 XY='(6000,4550)',
 ROT='0',
 VER='1',
 VALUE='10UF',
 PACK_TYPE='0805',
 PART_NUMBER='C95333-007',
 LOCATION='C3L8',
 ROOM='PVNN_PCH_STBY',
 SEC='1',
 CDS_LIB='mstr_discrete',
 CDS_PART_NAME='CAP_0805-10UF,16V,10%,X6S,C953A',
 VOLTAGE='16V',
 PRIM_FILE='./archive_libs/mstr_discrete/cap/chips/chips.prt';

PART_NAME
 C3L9 'CAP_0805-10UF,16V,10%,X6S,C953A':
 ROOM='P1V05_PCH_STBY_VR';

SECTION_NUMBER 1
 '@BASEBOARD_FAB2_LIB.BASEBOARD_FAB2(SCH_1):PAGE236_I29@MSTR_DISCRETE.CAP(CHIPS)':
 C_PATH='@baseboard_fab2_lib.baseboard_fab2(sch_1):page236_i29@mstr_discrete.cap~
(chips)',
 P_PATH='@baseboard_fab2_lib.baseboard_fab2(sch_1):page236_i29@mstr_discrete.cap~
(chips)',
 PATH='I29',
 DRAWING='@BASEBOARD_FAB2_LIB.BASEBOARD_FAB2(SCH_1):PAGE236',
 TOLERANCE='10%',
 SEC_TYPE='0805',
 MATERIAL='X6S',
 PHYS_PAGE='236',
 XY='(6025,2875)',
 ROT='0',
 VER='1',
 VALUE='10UF',
 PACK_TYPE='0805',
 PART_NUMBER='C95333-007',
 LOCATION='C3L9',
 ROOM='P1V05_PCH_STBY_VR',
 SEC='1',
 CDS_LIB='mstr_discrete',
 CDS_PART_NAME='CAP_0805-10UF,16V,10%,X6S,C953A',
 VOLTAGE='16V',
 PRIM_FILE='./archive_libs/mstr_discrete/cap/chips/chips.prt';

PART_NAME
 C3L10 'CAP_0805-10UF,16V,10%,X6S,C953A':
 ROOM='P1V05_PCH_STBY_VR';

SECTION_NUMBER 1
 '@BASEBOARD_FAB2_LIB.BASEBOARD_FAB2(SCH_1):PAGE236_I32@MSTR_DISCRETE.CAP(CHIPS)':
 C_PATH='@baseboard_fab2_lib.baseboard_fab2(sch_1):page236_i32@mstr_discrete.cap~
(chips)',
 P_PATH='@baseboard_fab2_lib.baseboard_fab2(sch_1):page236_i32@mstr_discrete.cap~
(chips)',
 PATH='I32',
 DRAWING='@BASEBOARD_FAB2_LIB.BASEBOARD_FAB2(SCH_1):PAGE236',
 TOLERANCE='10%',
 SEC_TYPE='0805',
 MATERIAL='X6S',
 PHYS_PAGE='236',
 XY='(6475,2875)',
 ROT='0',
 VER='1',
 VALUE='10UF',
 PACK_TYPE='0805',
 PART_NUMBER='C95333-007',
 LOCATION='C3L10',
 ROOM='P1V05_PCH_STBY_VR',
 SEC='1',
 CDS_LIB='mstr_discrete',
 CDS_PART_NAME='CAP_0805-10UF,16V,10%,X6S,C953A',
 VOLTAGE='16V',
 PRIM_FILE='./archive_libs/mstr_discrete/cap/chips/chips.prt';

PART_NAME
 C3L11 'CAP_0805-10UF,16V,10%,X6S,C953A':
 ROOM='PVNN_PCH_STBY';

SECTION_NUMBER 1
 '@BASEBOARD_FAB2_LIB.BASEBOARD_FAB2(SCH_1):PAGE236_I24@MSTR_DISCRETE.CAP(CHIPS)':
 C_PATH='@baseboard_fab2_lib.baseboard_fab2(sch_1):page236_i24@mstr_discrete.cap~
(chips)',
 P_PATH='@baseboard_fab2_lib.baseboard_fab2(sch_1):page236_i24@mstr_discrete.cap~
(chips)',
 PATH='I24',
 DRAWING='@BASEBOARD_FAB2_LIB.BASEBOARD_FAB2(SCH_1):PAGE236',
 TOLERANCE='10%',
 SEC_TYPE='0805',
 MATERIAL='X6S',
 PHYS_PAGE='236',
 XY='(6275,4500)',
 ROT='0',
 VER='1',
 VALUE='10UF',
 PACK_TYPE='0805',
 PART_NUMBER='C95333-007',
 LOCATION='C3L11',
 ROOM='PVNN_PCH_STBY',
 SEC='1',
 CDS_LIB='mstr_discrete',
 CDS_PART_NAME='CAP_0805-10UF,16V,10%,X6S,C953A',
 VOLTAGE='16V',
 PRIM_FILE='./archive_libs/mstr_discrete/cap/chips/chips.prt';

PART_NAME
 C3L12 'CAP_0805-10UF,16V,10%,X6S,C953A':
 ROOM='PVNN_PCH_STBY';

SECTION_NUMBER 1
 '@BASEBOARD_FAB2_LIB.BASEBOARD_FAB2(SCH_1):PAGE236_I23@MSTR_DISCRETE.CAP(CHIPS)':
 C_PATH='@baseboard_fab2_lib.baseboard_fab2(sch_1):page236_i23@mstr_discrete.cap~
(chips)',
 P_PATH='@baseboard_fab2_lib.baseboard_fab2(sch_1):page236_i23@mstr_discrete.cap~
(chips)',
 PATH='I23',
 DRAWING='@BASEBOARD_FAB2_LIB.BASEBOARD_FAB2(SCH_1):PAGE236',
 TOLERANCE='10%',
 SEC_TYPE='0805',
 MATERIAL='X6S',
 PHYS_PAGE='236',
 XY='(6525,4550)',
 ROT='0',
 VER='1',
 VALUE='10UF',
 PACK_TYPE='0805',
 PART_NUMBER='C95333-007',
 LOCATION='C3L12',
 ROOM='PVNN_PCH_STBY',
 SEC='1',
 CDS_LIB='mstr_discrete',
 CDS_PART_NAME='CAP_0805-10UF,16V,10%,X6S,C953A',
 VOLTAGE='16V',
 PRIM_FILE='./archive_libs/mstr_discrete/cap/chips/chips.prt';

PART_NAME
 C3L13 'CAP_0805-10UF,16V,10%,X6S,C953A':
 ROOM='VDDQ_DEF_PWR_VR';

SECTION_NUMBER 1
 '@BASEBOARD_FAB2_LIB.BASEBOARD_FAB2(SCH_1):PAGE219_I47@MSTR_DISCRETE.CAP(CHIPS)':
 C_PATH='@baseboard_fab2_lib.baseboard_fab2(sch_1):page219_i47@mstr_discrete.cap~
(chips)',
 P_PATH='@baseboard_fab2_lib.baseboard_fab2(sch_1):page219_i47@mstr_discrete.cap~
(chips)',
 PATH='I47',
 DRAWING='@BASEBOARD_FAB2_LIB.BASEBOARD_FAB2(SCH_1):PAGE219',
 TOLERANCE='10%',
 SEC_TYPE='0805',
 MATERIAL='X6S',
 PHYS_PAGE='219',
 XY='(-1775,2425)',
 ROT='0',
 VER='1',
 VALUE='10UF',
 PACK_TYPE='0805',
 PART_NUMBER='C95333-007',
 LOCATION='C3L13',
 ROOM='VDDQ_DEF_PWR_VR',
 SEC='1',
 CDS_LIB='mstr_discrete',
 CDS_PART_NAME='CAP_0805-10UF,16V,10%,X6S,C953A',
 VOLTAGE='16V',
 PRIM_FILE='./archive_libs/mstr_discrete/cap/chips/chips.prt';

PART_NAME
 C3L14 'CAPP_3018-470UF,2.5V,20%,ALUM,A':
 GROUP='PWR_BULK_CAP',
 ROOM='VDDQ_DEF_PWR_VR';

SECTION_NUMBER 1
 '@BASEBOARD_FAB2_LIB.BASEBOARD_FAB2(SCH_1):PAGE220_I76@MSTR_DISCRETE.CAPP(CHIPS)':
 C_PATH='@baseboard_fab2_lib.baseboard_fab2(sch_1):page220_i76@mstr_discrete.cap~
p(chips)',
 P_PATH='@baseboard_fab2_lib.baseboard_fab2(sch_1):page220_i76@mstr_discrete.cap~
p(chips)',
 PATH='I76',
 DRAWING='@BASEBOARD_FAB2_LIB.BASEBOARD_FAB2(SCH_1):PAGE220',
 TOLERANCE='20%',
 SEC_TYPE='3018',
 MATERIAL='ALUM',
 PHYS_PAGE='220',
 XY='(3200,-100)',
 ROT='0',
 VER='1',
 VALUE='470UF',
 PACK_TYPE='3018',
 PART_NUMBER='699013-049',
 LOCATION='C3L14',
 ROOM='VDDQ_DEF_PWR_VR',
 GROUP='PWR_BULK_CAP',
 SEC='1',
 CDS_LIB='mstr_discrete',
 CDS_PART_NAME='CAPP_3018-470UF,2.5V,20%,ALUM,A',
 VOLTAGE='2.5V',
 PRIM_FILE='./archive_libs/mstr_discrete/capp/chips/chips.prt';

PART_NAME
 C3L15 'CAP_0805-10UF,16V,10%,X6S,C953A':
 ROOM='VDDQ_DEF_PWR_VR';

SECTION_NUMBER 1
 '@BASEBOARD_FAB2_LIB.BASEBOARD_FAB2(SCH_1):PAGE219_I84@MSTR_DISCRETE.CAP(CHIPS)':
 C_PATH='@baseboard_fab2_lib.baseboard_fab2(sch_1):page219_i84@mstr_discrete.cap~
(chips)',
 P_PATH='@baseboard_fab2_lib.baseboard_fab2(sch_1):page219_i84@mstr_discrete.cap~
(chips)',
 PATH='I84',
 DRAWING='@BASEBOARD_FAB2_LIB.BASEBOARD_FAB2(SCH_1):PAGE219',
 TOLERANCE='10%',
 SEC_TYPE='0805',
 MATERIAL='X6S',
 PHYS_PAGE='219',
 XY='(-2200,75)',
 ROT='0',
 VER='1',
 VALUE='10UF',
 PACK_TYPE='0805',
 PART_NUMBER='C95333-007',
 LOCATION='C3L15',
 ROOM='VDDQ_DEF_PWR_VR',
 SEC='1',
 CDS_LIB='mstr_discrete',
 CDS_PART_NAME='CAP_0805-10UF,16V,10%,X6S,C953A',
 VOLTAGE='16V',
 PRIM_FILE='./archive_libs/mstr_discrete/cap/chips/chips.prt';

PART_NAME
 C3L16 'CAP_0805-10UF,16V,10%,X6S,C953A':
 ROOM='VDDQ_DEF_PWR_VR';

SECTION_NUMBER 1
 '@BASEBOARD_FAB2_LIB.BASEBOARD_FAB2(SCH_1):PAGE219_I81@MSTR_DISCRETE.CAP(CHIPS)':
 C_PATH='@baseboard_fab2_lib.baseboard_fab2(sch_1):page219_i81@mstr_discrete.cap~
(chips)',
 P_PATH='@baseboard_fab2_lib.baseboard_fab2(sch_1):page219_i81@mstr_discrete.cap~
(chips)',
 PATH='I81',
 DRAWING='@BASEBOARD_FAB2_LIB.BASEBOARD_FAB2(SCH_1):PAGE219',
 TOLERANCE='10%',
 SEC_TYPE='0805',
 MATERIAL='X6S',
 PHYS_PAGE='219',
 XY='(-1975,75)',
 ROT='0',
 VER='1',
 VALUE='10UF',
 PACK_TYPE='0805',
 PART_NUMBER='C95333-007',
 LOCATION='C3L16',
 ROOM='VDDQ_DEF_PWR_VR',
 SEC='1',
 CDS_LIB='mstr_discrete',
 CDS_PART_NAME='CAP_0805-10UF,16V,10%,X6S,C953A',
 VOLTAGE='16V',
 PRIM_FILE='./archive_libs/mstr_discrete/cap/chips/chips.prt';

PART_NAME
 C3L17 'CAP_0805-10UF,16V,10%,X6S,C953A':
 ROOM='VDDQ_DEF_PWR_VR';

SECTION_NUMBER 1
 '@BASEBOARD_FAB2_LIB.BASEBOARD_FAB2(SCH_1):PAGE219_I80@MSTR_DISCRETE.CAP(CHIPS)':
 C_PATH='@baseboard_fab2_lib.baseboard_fab2(sch_1):page219_i80@mstr_discrete.cap~
(chips)',
 P_PATH='@baseboard_fab2_lib.baseboard_fab2(sch_1):page219_i80@mstr_discrete.cap~
(chips)',
 PATH='I80',
 DRAWING='@BASEBOARD_FAB2_LIB.BASEBOARD_FAB2(SCH_1):PAGE219',
 TOLERANCE='10%',
 SEC_TYPE='0805',
 MATERIAL='X6S',
 PHYS_PAGE='219',
 XY='(-1750,75)',
 ROT='0',
 VER='1',
 VALUE='10UF',
 PACK_TYPE='0805',
 PART_NUMBER='C95333-007',
 LOCATION='C3L17',
 ROOM='VDDQ_DEF_PWR_VR',
 SEC='1',
 CDS_LIB='mstr_discrete',
 CDS_PART_NAME='CAP_0805-10UF,16V,10%,X6S,C953A',
 VOLTAGE='16V',
 PRIM_FILE='./archive_libs/mstr_discrete/cap/chips/chips.prt';

PART_NAME
 C3L18 'CAPP_SM-470UF,2V,20%,ALUM,6990A':
 ROOM='PVNN_PCH_STBY';

SECTION_NUMBER 1
 '@BASEBOARD_FAB2_LIB.BASEBOARD_FAB2(SCH_1):PAGE236_I71@MSTR_DISCRETE.CAPP(CHIPS)':
 C_PATH='@baseboard_fab2_lib.baseboard_fab2(sch_1):page236_i71@mstr_discrete.cap~
p(chips)',
 P_PATH='@baseboard_fab2_lib.baseboard_fab2(sch_1):page236_i71@mstr_discrete.cap~
p(chips)',
 PATH='I71',
 DRAWING='@BASEBOARD_FAB2_LIB.BASEBOARD_FAB2(SCH_1):PAGE236',
 TOLERANCE='20%',
 SEC_TYPE='SM',
 MATERIAL='ALUM',
 PHYS_PAGE='236',
 XY='(12025,3775)',
 ROT='0',
 VER='1',
 VALUE='470UF',
 PACK_TYPE='SM',
 PART_NUMBER='699013-031',
 LOCATION='C3L18',
 ROOM='PVNN_PCH_STBY',
 SEC='1',
 CDS_LIB='mstr_discrete',
 CDS_PART_NAME='CAPP_SM-470UF,2V,20%,ALUM,6990A',
 VOLTAGE='2V',
 PRIM_FILE='./archive_libs/mstr_discrete/capp/chips/chips.prt';

PART_NAME
 C3L19 'CAPP_SM-470UF,2V,20%,ALUM,6990A':
 ROOM='P1V05_PCH_STBY';

SECTION_NUMBER 1
 '@BASEBOARD_FAB2_LIB.BASEBOARD_FAB2(SCH_1):PAGE236_I76@MSTR_DISCRETE.CAPP(CHIPS)':
 C_PATH='@baseboard_fab2_lib.baseboard_fab2(sch_1):page236_i76@mstr_discrete.cap~
p(chips)',
 P_PATH='@baseboard_fab2_lib.baseboard_fab2(sch_1):page236_i76@mstr_discrete.cap~
p(chips)',
 PATH='I76',
 DRAWING='@BASEBOARD_FAB2_LIB.BASEBOARD_FAB2(SCH_1):PAGE236',
 TOLERANCE='20%',
 SEC_TYPE='SM',
 MATERIAL='ALUM',
 PHYS_PAGE='236',
 XY='(11925,2050)',
 ROT='0',
 VER='1',
 VALUE='470UF',
 PACK_TYPE='SM',
 PART_NUMBER='699013-031',
 LOCATION='C3L19',
 ROOM='P1V05_PCH_STBY',
 SEC='1',
 CDS_LIB='mstr_discrete',
 CDS_PART_NAME='CAPP_SM-470UF,2V,20%,ALUM,6990A',
 VOLTAGE='2V',
 PRIM_FILE='./archive_libs/mstr_discrete/capp/chips/chips.prt';

PART_NAME
 C3L20 'CAPP_SM-470UF,2V,20%,ALUM,6990A':
 ROOM='PVNN_PCH_STBY';

SECTION_NUMBER 1
 '@BASEBOARD_FAB2_LIB.BASEBOARD_FAB2(SCH_1):PAGE236_I73@MSTR_DISCRETE.CAPP(CHIPS)':
 C_PATH='@baseboard_fab2_lib.baseboard_fab2(sch_1):page236_i73@mstr_discrete.cap~
p(chips)',
 P_PATH='@baseboard_fab2_lib.baseboard_fab2(sch_1):page236_i73@mstr_discrete.cap~
p(chips)',
 PATH='I73',
 DRAWING='@BASEBOARD_FAB2_LIB.BASEBOARD_FAB2(SCH_1):PAGE236',
 TOLERANCE='20%',
 SEC_TYPE='SM',
 MATERIAL='ALUM',
 PHYS_PAGE='236',
 XY='(12325,3775)',
 ROT='0',
 VER='1',
 VALUE='470UF',
 PACK_TYPE='SM',
 PART_NUMBER='699013-031',
 LOCATION='C3L20',
 ROOM='PVNN_PCH_STBY',
 SEC='1',
 CDS_LIB='mstr_discrete',
 CDS_PART_NAME='CAPP_SM-470UF,2V,20%,ALUM,6990A',
 VOLTAGE='2V',
 PRIM_FILE='./archive_libs/mstr_discrete/capp/chips/chips.prt';

PART_NAME
 C3L21 'CAPP_SM-470UF,2V,20%,ALUM,6990A':
 ROOM='PVNN_PCH_STBY';

SECTION_NUMBER 1
 '@BASEBOARD_FAB2_LIB.BASEBOARD_FAB2(SCH_1):PAGE236_I74@MSTR_DISCRETE.CAPP(CHIPS)':
 C_PATH='@baseboard_fab2_lib.baseboard_fab2(sch_1):page236_i74@mstr_discrete.cap~
p(chips)',
 P_PATH='@baseboard_fab2_lib.baseboard_fab2(sch_1):page236_i74@mstr_discrete.cap~
p(chips)',
 PATH='I74',
 DRAWING='@BASEBOARD_FAB2_LIB.BASEBOARD_FAB2(SCH_1):PAGE236',
 TOLERANCE='20%',
 SEC_TYPE='SM',
 MATERIAL='ALUM',
 PHYS_PAGE='236',
 XY='(12600,3775)',
 ROT='0',
 VER='1',
 VALUE='470UF',
 PACK_TYPE='SM',
 PART_NUMBER='699013-031',
 LOCATION='C3L21',
 ROOM='PVNN_PCH_STBY',
 SEC='1',
 CDS_LIB='mstr_discrete',
 CDS_PART_NAME='CAPP_SM-470UF,2V,20%,ALUM,6990A',
 VOLTAGE='2V',
 PRIM_FILE='./archive_libs/mstr_discrete/capp/chips/chips.prt';

PART_NAME
 C3L22 'CAP_A_0603V-22.0UF,4V,20%,X6S,A':
 ROOM='SB_DECOUPLING';

SECTION_NUMBER 1
 '@BASEBOARD_FAB2_LIB.BASEBOARD_FAB2(SCH_1):PAGE132_I54@DEV_DISCRETE.CAP_A(CHIPS)':
 C_PATH='@baseboard_fab2_lib.baseboard_fab2(sch_1):page132_i54@dev_discrete.cap_~
a(chips)',
 P_PATH='@baseboard_fab2_lib.baseboard_fab2(sch_1):page132_i54@dev_discrete.cap_~
a(chips)',
 PATH='I54',
 DRAWING='@BASEBOARD_FAB2_LIB.BASEBOARD_FAB2(SCH_1):PAGE132',
 TOLERANCE='20%',
 MATERIAL='X6S',
 BOM_COST='SB',
 PHYS_PAGE='132',
 XY='(-2950,1925)',
 ROT='0',
 VER='1',
 VALUE='22.0UF',
 PACK_TYPE='0603V',
 PART_NUMBER='E15431-004',
 LOCATION='C3L22',
 ROOM='SB_DECOUPLING',
 CDS_LIB='dev_discrete',
 CDS_PART_NAME='CAP_A_0603V-22.0UF,4V,20%,X6S,A',
 VOLTAGE='4V',
 PRIM_FILE='./archive_libs/discrete/cap_a/chips/chips.prt';

PART_NAME
 C3L23 'CAP_A_0603V-22.0UF,4V,20%,X6S,A':
 ROOM='SB_DECOUPLING';

SECTION_NUMBER 1
 '@BASEBOARD_FAB2_LIB.BASEBOARD_FAB2(SCH_1):PAGE132_I52@DEV_DISCRETE.CAP_A(CHIPS)':
 C_PATH='@baseboard_fab2_lib.baseboard_fab2(sch_1):page132_i52@dev_discrete.cap_~
a(chips)',
 P_PATH='@baseboard_fab2_lib.baseboard_fab2(sch_1):page132_i52@dev_discrete.cap_~
a(chips)',
 PATH='I52',
 DRAWING='@BASEBOARD_FAB2_LIB.BASEBOARD_FAB2(SCH_1):PAGE132',
 TOLERANCE='20%',
 MATERIAL='X6S',
 BOM_COST='SB',
 PHYS_PAGE='132',
 XY='(-2550,1925)',
 ROT='0',
 VER='1',
 VALUE='22.0UF',
 PACK_TYPE='0603V',
 PART_NUMBER='E15431-004',
 LOCATION='C3L23',
 ROOM='SB_DECOUPLING',
 CDS_LIB='dev_discrete',
 CDS_PART_NAME='CAP_A_0603V-22.0UF,4V,20%,X6S,A',
 VOLTAGE='4V',
 PRIM_FILE='./archive_libs/discrete/cap_a/chips/chips.prt';

PART_NAME
 C3L24 'CAP_A_0603V-22.0UF,4V,20%,X6S,A':
 ROOM='SB_DECOUPLING';

SECTION_NUMBER 1
 '@BASEBOARD_FAB2_LIB.BASEBOARD_FAB2(SCH_1):PAGE132_I56@DEV_DISCRETE.CAP_A(CHIPS)':
 C_PATH='@baseboard_fab2_lib.baseboard_fab2(sch_1):page132_i56@dev_discrete.cap_~
a(chips)',
 P_PATH='@baseboard_fab2_lib.baseboard_fab2(sch_1):page132_i56@dev_discrete.cap_~
a(chips)',
 PATH='I56',
 DRAWING='@BASEBOARD_FAB2_LIB.BASEBOARD_FAB2(SCH_1):PAGE132',
 TOLERANCE='20%',
 MATERIAL='X6S',
 BOM_COST='SB',
 PHYS_PAGE='132',
 XY='(-3425,1925)',
 ROT='0',
 VER='1',
 VALUE='22.0UF',
 PACK_TYPE='0603V',
 PART_NUMBER='E15431-004',
 LOCATION='C3L24',
 ROOM='SB_DECOUPLING',
 CDS_LIB='dev_discrete',
 CDS_PART_NAME='CAP_A_0603V-22.0UF,4V,20%,X6S,A',
 VOLTAGE='4V',
 PRIM_FILE='./archive_libs/discrete/cap_a/chips/chips.prt';

PART_NAME
 C3L25 'CAP_A_0603V-22.0UF,4V,20%,X6S,A':
 ROOM='SB_DECOUPLING';

SECTION_NUMBER 1
 '@BASEBOARD_FAB2_LIB.BASEBOARD_FAB2(SCH_1):PAGE132_I1@DEV_DISCRETE.CAP_A(CHIPS)':
 C_PATH='@baseboard_fab2_lib.baseboard_fab2(sch_1):page132_i1@dev_discrete.cap_a~
(chips)',
 P_PATH='@baseboard_fab2_lib.baseboard_fab2(sch_1):page132_i1@dev_discrete.cap_a~
(chips)',
 PATH='I1',
 DRAWING='@BASEBOARD_FAB2_LIB.BASEBOARD_FAB2(SCH_1):PAGE132',
 TOLERANCE='20%',
 MATERIAL='X6S',
 BOM_COST='SB',
 PHYS_PAGE='132',
 XY='(2575,4475)',
 ROT='0',
 VER='1',
 VALUE='22.0UF',
 PACK_TYPE='0603V',
 PART_NUMBER='E15431-004',
 LOCATION='C3L25',
 ROOM='SB_DECOUPLING',
 CDS_LIB='dev_discrete',
 CDS_PART_NAME='CAP_A_0603V-22.0UF,4V,20%,X6S,A',
 VOLTAGE='4V',
 PRIM_FILE='./archive_libs/discrete/cap_a/chips/chips.prt';

PART_NAME
 C3L26 'CAP_A_0603V-22.0UF,4V,20%,X6S,A':
 ROOM='SB_DECOUPLING';

SECTION_NUMBER 1
 '@BASEBOARD_FAB2_LIB.BASEBOARD_FAB2(SCH_1):PAGE132_I3@DEV_DISCRETE.CAP_A(CHIPS)':
 C_PATH='@baseboard_fab2_lib.baseboard_fab2(sch_1):page132_i3@dev_discrete.cap_a~
(chips)',
 P_PATH='@baseboard_fab2_lib.baseboard_fab2(sch_1):page132_i3@dev_discrete.cap_a~
(chips)',
 PATH='I3',
 DRAWING='@BASEBOARD_FAB2_LIB.BASEBOARD_FAB2(SCH_1):PAGE132',
 TOLERANCE='20%',
 MATERIAL='X6S',
 BOM_COST='SB',
 PHYS_PAGE='132',
 XY='(1825,4475)',
 ROT='0',
 VER='1',
 VALUE='22.0UF',
 PACK_TYPE='0603V',
 PART_NUMBER='E15431-004',
 LOCATION='C3L26',
 ROOM='SB_DECOUPLING',
 CDS_LIB='dev_discrete',
 CDS_PART_NAME='CAP_A_0603V-22.0UF,4V,20%,X6S,A',
 VOLTAGE='4V',
 PRIM_FILE='./archive_libs/discrete/cap_a/chips/chips.prt';

PART_NAME
 C3L27 'CAP_A_0603V-22.0UF,4V,20%,X6S,A':
 ROOM='SB_DECOUPLING';

SECTION_NUMBER 1
 '@BASEBOARD_FAB2_LIB.BASEBOARD_FAB2(SCH_1):PAGE132_I4@DEV_DISCRETE.CAP_A(CHIPS)':
 C_PATH='@baseboard_fab2_lib.baseboard_fab2(sch_1):page132_i4@dev_discrete.cap_a~
(chips)',
 P_PATH='@baseboard_fab2_lib.baseboard_fab2(sch_1):page132_i4@dev_discrete.cap_a~
(chips)',
 PATH='I4',
 DRAWING='@BASEBOARD_FAB2_LIB.BASEBOARD_FAB2(SCH_1):PAGE132',
 TOLERANCE='20%',
 MATERIAL='X6S',
 BOM_COST='SB',
 PHYS_PAGE='132',
 XY='(1450,4475)',
 ROT='0',
 VER='1',
 VALUE='22.0UF',
 PACK_TYPE='0603V',
 PART_NUMBER='E15431-004',
 LOCATION='C3L27',
 ROOM='SB_DECOUPLING',
 CDS_LIB='dev_discrete',
 CDS_PART_NAME='CAP_A_0603V-22.0UF,4V,20%,X6S,A',
 VOLTAGE='4V',
 PRIM_FILE='./archive_libs/discrete/cap_a/chips/chips.prt';

PART_NAME
 C3L29 'SC1U10V2KX-4-GP_SMD-BCG6-SC1U1A':;

SECTION_NUMBER 1
 '@BASEBOARD_FAB2_LIB.BASEBOARD_FAB2(SCH_1):PAGE236_I181@W_HDL.SC1U10V2KX-4-GP(CHIPS)':
 C_PATH='@baseboard_fab2_lib.baseboard_fab2(sch_1):page236_i181@w_hdl.\sc1u10v2k~
x-4-gp\(chips)',
 P_PATH='@baseboard_fab2_lib.baseboard_fab2(sch_1):page236_i181@w_hdl.\sc1u10v2k~
x-4-gp\(chips)',
 PATH='I181',
 DRAWING='@BASEBOARD_FAB2_LIB.BASEBOARD_FAB2(SCH_1):PAGE236',
 PACK_SIZE='0402',
 RATED='10V',
 ATTRIBUTE='1UF',
 TOLERANCE='10%',
 SEC_TYPE='SMD-BCG6',
 PHYS_PAGE='236',
 XY='(7625,2775)',
 ROT='0',
 VER='1',
 VALUE='SC1U10V2KX-4-GP',
 PACK_TYPE='SMD-BCG6',
 PART_NUMBER='78.10523.8FL',
 LOCATION='C3L29',
 SEC='1',
 CDS_LIB='w_hdl',
 CDS_PART_NAME='SC1U10V2KX-4-GP_SMD-BCG6-SC1U1A',
 PRIM_FILE='C:/<user>/w_hdl/sc1u10v2kx#2d4#2dgp/chips/chips.prt';

PART_NAME
 C3M1 'CAP_0402-0.22UF,16V,10%,X7R,A3A':
 GROUP='PCIE_UPLINK',
 ROOM='OCP_STEERING';

SECTION_NUMBER 1
 '@BASEBOARD_FAB2_LIB.BASEBOARD_FAB2(SCH_1):PAGE105_I255@MSTR_DISCRETE.CAP(CHIPS)':
 C_PATH='@baseboard_fab2_lib.baseboard_fab2(sch_1):page105_i255@mstr_discrete.ca~
p(chips)',
 P_PATH='@baseboard_fab2_lib.baseboard_fab2(sch_1):page105_i255@mstr_discrete.ca~
p(chips)',
 PATH='I255',
 DRAWING='@BASEBOARD_FAB2_LIB.BASEBOARD_FAB2(SCH_1):PAGE105',
 TOLERANCE='10%',
 MATERIAL='X7R',
 PHYS_PAGE='105',
 XY='(1050,1025)',
 ROT='2',
 VER='1',
 VALUE='0.22UF',
 PACK_TYPE='0402',
 PART_NUMBER='A36096-155',
 LOCATION='C3M1',
 ROOM='OCP_STEERING',
 GROUP='PCIE_UPLINK',
 CDS_LIB='mstr_discrete',
 CDS_PART_NAME='CAP_0402-0.22UF,16V,10%,X7R,A3A',
 VOLTAGE='16V',
 PRIM_FILE='./archive_libs/mstr_discrete/cap/chips/chips.prt';

PART_NAME
 C3M2 'CAP_0402-0.22UF,16V,10%,X7R,A3A':
 GROUP='PCIE_UPLINK',
 ROOM='OCP_STEERING';

SECTION_NUMBER 1
 '@BASEBOARD_FAB2_LIB.BASEBOARD_FAB2(SCH_1):PAGE105_I247@MSTR_DISCRETE.CAP(CHIPS)':
 C_PATH='@baseboard_fab2_lib.baseboard_fab2(sch_1):page105_i247@mstr_discrete.ca~
p(chips)',
 P_PATH='@baseboard_fab2_lib.baseboard_fab2(sch_1):page105_i247@mstr_discrete.ca~
p(chips)',
 PATH='I247',
 DRAWING='@BASEBOARD_FAB2_LIB.BASEBOARD_FAB2(SCH_1):PAGE105',
 TOLERANCE='10%',
 MATERIAL='X7R',
 PHYS_PAGE='105',
 XY='(1000,2025)',
 ROT='2',
 VER='1',
 VALUE='0.22UF',
 PACK_TYPE='0402',
 PART_NUMBER='A36096-155',
 LOCATION='C3M2',
 ROOM='OCP_STEERING',
 GROUP='PCIE_UPLINK',
 CDS_LIB='mstr_discrete',
 CDS_PART_NAME='CAP_0402-0.22UF,16V,10%,X7R,A3A',
 VOLTAGE='16V',
 PRIM_FILE='./archive_libs/mstr_discrete/cap/chips/chips.prt';

PART_NAME
 C3M3 'CAP_0402-0.22UF,16V,10%,X7R,A3A':
 GROUP='PCIE_UPLINK',
 ROOM='OCP_STEERING';

SECTION_NUMBER 1
 '@BASEBOARD_FAB2_LIB.BASEBOARD_FAB2(SCH_1):PAGE105_I232@MSTR_DISCRETE.CAP(CHIPS)':
 C_PATH='@baseboard_fab2_lib.baseboard_fab2(sch_1):page105_i232@mstr_discrete.ca~
p(chips)',
 P_PATH='@baseboard_fab2_lib.baseboard_fab2(sch_1):page105_i232@mstr_discrete.ca~
p(chips)',
 PATH='I232',
 DRAWING='@BASEBOARD_FAB2_LIB.BASEBOARD_FAB2(SCH_1):PAGE105',
 TOLERANCE='10%',
 MATERIAL='X7R',
 PHYS_PAGE='105',
 XY='(1600,2325)',
 ROT='2',
 VER='1',
 VALUE='0.22UF',
 PACK_TYPE='0402',
 PART_NUMBER='A36096-155',
 LOCATION='C3M3',
 ROOM='OCP_STEERING',
 GROUP='PCIE_UPLINK',
 CDS_LIB='mstr_discrete',
 CDS_PART_NAME='CAP_0402-0.22UF,16V,10%,X7R,A3A',
 VOLTAGE='16V',
 PRIM_FILE='./archive_libs/mstr_discrete/cap/chips/chips.prt';

PART_NAME
 C3M4 'CAP_0402-0.22UF,16V,10%,X7R,A3A':
 GROUP='PCIE_UPLINK',
 ROOM='OCP_STEERING';

SECTION_NUMBER 1
 '@BASEBOARD_FAB2_LIB.BASEBOARD_FAB2(SCH_1):PAGE105_I244@MSTR_DISCRETE.CAP(CHIPS)':
 C_PATH='@baseboard_fab2_lib.baseboard_fab2(sch_1):page105_i244@mstr_discrete.ca~
p(chips)',
 P_PATH='@baseboard_fab2_lib.baseboard_fab2(sch_1):page105_i244@mstr_discrete.ca~
p(chips)',
 PATH='I244',
 DRAWING='@BASEBOARD_FAB2_LIB.BASEBOARD_FAB2(SCH_1):PAGE105',
 TOLERANCE='10%',
 MATERIAL='X7R',
 PHYS_PAGE='105',
 XY='(1650,1325)',
 ROT='2',
 VER='1',
 VALUE='0.22UF',
 PACK_TYPE='0402',
 PART_NUMBER='A36096-155',
 LOCATION='C3M4',
 ROOM='OCP_STEERING',
 GROUP='PCIE_UPLINK',
 CDS_LIB='mstr_discrete',
 CDS_PART_NAME='CAP_0402-0.22UF,16V,10%,X7R,A3A',
 VOLTAGE='16V',
 PRIM_FILE='./archive_libs/mstr_discrete/cap/chips/chips.prt';

PART_NAME
 C3M6 'CAP_A_0603V-22.0UF,4V,20%,X6S,A':
 ROOM='SB_DECOUPLING';

SECTION_NUMBER 1
 '@BASEBOARD_FAB2_LIB.BASEBOARD_FAB2(SCH_1):PAGE132_I6@DEV_DISCRETE.CAP_A(CHIPS)':
 C_PATH='@baseboard_fab2_lib.baseboard_fab2(sch_1):page132_i6@dev_discrete.cap_a~
(chips)',
 P_PATH='@baseboard_fab2_lib.baseboard_fab2(sch_1):page132_i6@dev_discrete.cap_a~
(chips)',
 PATH='I6',
 DRAWING='@BASEBOARD_FAB2_LIB.BASEBOARD_FAB2(SCH_1):PAGE132',
 TOLERANCE='20%',
 MATERIAL='X6S',
 BOM_COST='SB',
 PHYS_PAGE='132',
 XY='(1075,4475)',
 ROT='0',
 VER='1',
 VALUE='22.0UF',
 PACK_TYPE='0603V',
 PART_NUMBER='E15431-004',
 LOCATION='C3M6',
 ROOM='SB_DECOUPLING',
 CDS_LIB='dev_discrete',
 CDS_PART_NAME='CAP_A_0603V-22.0UF,4V,20%,X6S,A',
 VOLTAGE='4V',
 PRIM_FILE='./archive_libs/discrete/cap_a/chips/chips.prt';

PART_NAME
 C3M7 'CAP_A_0603V-22.0UF,4V,20%,X6S,A':
 ROOM='SB_DECOUPLING';

SECTION_NUMBER 1
 '@BASEBOARD_FAB2_LIB.BASEBOARD_FAB2(SCH_1):PAGE132_I2@DEV_DISCRETE.CAP_A(CHIPS)':
 C_PATH='@baseboard_fab2_lib.baseboard_fab2(sch_1):page132_i2@dev_discrete.cap_a~
(chips)',
 P_PATH='@baseboard_fab2_lib.baseboard_fab2(sch_1):page132_i2@dev_discrete.cap_a~
(chips)',
 PATH='I2',
 DRAWING='@BASEBOARD_FAB2_LIB.BASEBOARD_FAB2(SCH_1):PAGE132',
 TOLERANCE='20%',
 MATERIAL='X6S',
 BOM_COST='SB',
 PHYS_PAGE='132',
 XY='(2200,4475)',
 ROT='0',
 VER='1',
 VALUE='22.0UF',
 PACK_TYPE='0603V',
 PART_NUMBER='E15431-004',
 LOCATION='C3M7',
 ROOM='SB_DECOUPLING',
 CDS_LIB='dev_discrete',
 CDS_PART_NAME='CAP_A_0603V-22.0UF,4V,20%,X6S,A',
 VOLTAGE='4V',
 PRIM_FILE='./archive_libs/discrete/cap_a/chips/chips.prt';

PART_NAME
 C3M8 'CAP_0805-10UF,16V,10%,X6S,C953A':;

SECTION_NUMBER 1
 '@BASEBOARD_FAB2_LIB.BASEBOARD_FAB2(SCH_1):PAGE232_I259@MSTR_DISCRETE.CAP(CHIPS)':
 C_PATH='@baseboard_fab2_lib.baseboard_fab2(sch_1):page232_i259@mstr_discrete.ca~
p(chips)',
 P_PATH='@baseboard_fab2_lib.baseboard_fab2(sch_1):page232_i259@mstr_discrete.ca~
p(chips)',
 PATH='I259',
 DRAWING='@BASEBOARD_FAB2_LIB.BASEBOARD_FAB2(SCH_1):PAGE232',
 TOLERANCE='10%',
 SEC_TYPE='0805',
 MATERIAL='X6S',
 PHYS_PAGE='232',
 XY='(-6950,4100)',
 ROT='0',
 VER='1',
 VALUE='10UF',
 PACK_TYPE='0805',
 PART_NUMBER='C95333-007',
 LOCATION='C3M8',
 SEC='1',
 CDS_LIB='mstr_discrete',
 CDS_PART_NAME='CAP_0805-10UF,16V,10%,X6S,C953A',
 VOLTAGE='16V',
 PRIM_FILE='./archive_libs/mstr_discrete/cap/chips/chips.prt';

PART_NAME
 C3M9 'CAP_0402-1.0UF,16V,10%,X6S,D97A':
 ROOM='PVPP_KLM_VR',
 REUSE_ID='1';

SECTION_NUMBER 1
 '@BASEBOARD_FAB2_LIB.BASEBOARD_FAB2(SCH_1):PAGE232_I207@MSTR_DISCRETE.CAP(CHIPS)':
 C_PATH='@baseboard_fab2_lib.baseboard_fab2(sch_1):page232_i207@mstr_discrete.ca~
p(chips)',
 P_PATH='@baseboard_fab2_lib.baseboard_fab2(sch_1):page232_i207@mstr_discrete.ca~
p(chips)',
 PATH='I207',
 DRAWING='@BASEBOARD_FAB2_LIB.BASEBOARD_FAB2(SCH_1):PAGE232',
 FIN='VR_1P2',
 TOLERANCE='10%',
 MATERIAL='X6S',
 BOM_COST='PVPP_KLM_VR',
 PHYS_PAGE='232',
 REUSE_ID='1',
 XY='(-5425,4150)',
 ROT='0',
 VER='1',
 VALUE='1.0UF',
 PACK_TYPE='0402',
 PART_NUMBER='D97712-011',
 LOCATION='C3M9',
 ROOM='PVPP_KLM_VR',
 CDS_LIB='mstr_discrete',
 CDS_PART_NAME='CAP_0402-1.0UF,16V,10%,X6S,D97A',
 VOLTAGE='16V',
 PRIM_FILE='./archive_libs/mstr_discrete/cap/chips/chips.prt';

PART_NAME
 C3M10 'CAP_0603-4.7UF,6.3V,10%,X6S,E1A':
 ROOM='PVPP_KLM_VR',
 REUSE_ID='26';

SECTION_NUMBER 1
 '@BASEBOARD_FAB2_LIB.BASEBOARD_FAB2(SCH_1):PAGE232_I253@MSTR_DISCRETE.CAP(CHIPS)':
 C_PATH='@baseboard_fab2_lib.baseboard_fab2(sch_1):page232_i253@mstr_discrete.ca~
p(chips)',
 P_PATH='@baseboard_fab2_lib.baseboard_fab2(sch_1):page232_i253@mstr_discrete.ca~
p(chips)',
 PATH='I253',
 DRAWING='@BASEBOARD_FAB2_LIB.BASEBOARD_FAB2(SCH_1):PAGE232',
 CONFIG='078.47521.08BD',
 TOLERANCE='10%',
 SEC_TYPE='0603',
 MATERIAL='X6S',
 BOM_COST='PVPP_KLM_VR',
 PHYS_PAGE='232',
 REUSE_ID='26',
 XY='(-6125,2425)',
 ROT='0',
 VER='1',
 VALUE='4.7UF',
 PACK_TYPE='0603',
 PART_NUMBER='E15431-003',
 LOCATION='C3M10',
 ROOM='PVPP_KLM_VR',
 SEC='1',
 CDS_LIB='mstr_discrete',
 CDS_PART_NAME='CAP_0603-4.7UF,6.3V,10%,X6S,E1A',
 VOLTAGE='6.3V',
 PRIM_FILE='./archive_libs/mstr_discrete/cap/chips/chips.prt';

PART_NAME
 C3M11 'CAP_0402-0.22UF,16V,10%,X7R,A3A':
 GROUP='PCIE_UPLINK',
 ROOM='OCP_STEERING';

SECTION_NUMBER 1
 '@BASEBOARD_FAB2_LIB.BASEBOARD_FAB2(SCH_1):PAGE105_I234@MSTR_DISCRETE.CAP(CHIPS)':
 C_PATH='@baseboard_fab2_lib.baseboard_fab2(sch_1):page105_i234@mstr_discrete.ca~
p(chips)',
 P_PATH='@baseboard_fab2_lib.baseboard_fab2(sch_1):page105_i234@mstr_discrete.ca~
p(chips)',
 PATH='I234',
 DRAWING='@BASEBOARD_FAB2_LIB.BASEBOARD_FAB2(SCH_1):PAGE105',
 TOLERANCE='10%',
 MATERIAL='X7R',
 PHYS_PAGE='105',
 XY='(1200,2325)',
 ROT='2',
 VER='1',
 VALUE='0.22UF',
 PACK_TYPE='0402',
 PART_NUMBER='A36096-155',
 LOCATION='C3M11',
 ROOM='OCP_STEERING',
 GROUP='PCIE_UPLINK',
 CDS_LIB='mstr_discrete',
 CDS_PART_NAME='CAP_0402-0.22UF,16V,10%,X7R,A3A',
 VOLTAGE='16V',
 PRIM_FILE='./archive_libs/mstr_discrete/cap/chips/chips.prt';

PART_NAME
 C3M12 'CAP_0402-0.22UF,16V,10%,X7R,A3A':
 GROUP='PCIE_UPLINK',
 ROOM='OCP_STEERING';

SECTION_NUMBER 1
 '@BASEBOARD_FAB2_LIB.BASEBOARD_FAB2(SCH_1):PAGE105_I246@MSTR_DISCRETE.CAP(CHIPS)':
 C_PATH='@baseboard_fab2_lib.baseboard_fab2(sch_1):page105_i246@mstr_discrete.ca~
p(chips)',
 P_PATH='@baseboard_fab2_lib.baseboard_fab2(sch_1):page105_i246@mstr_discrete.ca~
p(chips)',
 PATH='I246',
 DRAWING='@BASEBOARD_FAB2_LIB.BASEBOARD_FAB2(SCH_1):PAGE105',
 TOLERANCE='10%',
 MATERIAL='X7R',
 PHYS_PAGE='105',
 XY='(1250,1325)',
 ROT='2',
 VER='1',
 VALUE='0.22UF',
 PACK_TYPE='0402',
 PART_NUMBER='A36096-155',
 LOCATION='C3M12',
 ROOM='OCP_STEERING',
 GROUP='PCIE_UPLINK',
 CDS_LIB='mstr_discrete',
 CDS_PART_NAME='CAP_0402-0.22UF,16V,10%,X7R,A3A',
 VOLTAGE='16V',
 PRIM_FILE='./archive_libs/mstr_discrete/cap/chips/chips.prt';

PART_NAME
 C3M13 'CAP_0402-0.22UF,16V,10%,X7R,A3A':
 GROUP='PCIE_UPLINK',
 ROOM='OCP_STEERING';

SECTION_NUMBER 1
 '@BASEBOARD_FAB2_LIB.BASEBOARD_FAB2(SCH_1):PAGE105_I239@MSTR_DISCRETE.CAP(CHIPS)':
 C_PATH='@baseboard_fab2_lib.baseboard_fab2(sch_1):page105_i239@mstr_discrete.ca~
p(chips)',
 P_PATH='@baseboard_fab2_lib.baseboard_fab2(sch_1):page105_i239@mstr_discrete.ca~
p(chips)',
 PATH='I239',
 DRAWING='@BASEBOARD_FAB2_LIB.BASEBOARD_FAB2(SCH_1):PAGE105',
 TOLERANCE='10%',
 MATERIAL='X7R',
 PHYS_PAGE='105',
 XY='(1400,2025)',
 ROT='2',
 VER='1',
 VALUE='0.22UF',
 PACK_TYPE='0402',
 PART_NUMBER='A36096-155',
 LOCATION='C3M13',
 ROOM='OCP_STEERING',
 GROUP='PCIE_UPLINK',
 CDS_LIB='mstr_discrete',
 CDS_PART_NAME='CAP_0402-0.22UF,16V,10%,X7R,A3A',
 VOLTAGE='16V',
 PRIM_FILE='./archive_libs/mstr_discrete/cap/chips/chips.prt';

PART_NAME
 C3M14 'CAP_0402-0.22UF,16V,10%,X7R,A3A':
 GROUP='PCIE_UPLINK',
 ROOM='OCP_STEERING';

SECTION_NUMBER 1
 '@BASEBOARD_FAB2_LIB.BASEBOARD_FAB2(SCH_1):PAGE105_I253@MSTR_DISCRETE.CAP(CHIPS)':
 C_PATH='@baseboard_fab2_lib.baseboard_fab2(sch_1):page105_i253@mstr_discrete.ca~
p(chips)',
 P_PATH='@baseboard_fab2_lib.baseboard_fab2(sch_1):page105_i253@mstr_discrete.ca~
p(chips)',
 PATH='I253',
 DRAWING='@BASEBOARD_FAB2_LIB.BASEBOARD_FAB2(SCH_1):PAGE105',
 TOLERANCE='10%',
 MATERIAL='X7R',
 PHYS_PAGE='105',
 XY='(1450,1025)',
 ROT='2',
 VER='1',
 VALUE='0.22UF',
 PACK_TYPE='0402',
 PART_NUMBER='A36096-155',
 LOCATION='C3M14',
 ROOM='OCP_STEERING',
 GROUP='PCIE_UPLINK',
 CDS_LIB='mstr_discrete',
 CDS_PART_NAME='CAP_0402-0.22UF,16V,10%,X7R,A3A',
 VOLTAGE='16V',
 PRIM_FILE='./archive_libs/mstr_discrete/cap/chips/chips.prt';

PART_NAME
 C3M15 'CAP_0805-10UF,16V,10%,X6S,C953A':;

SECTION_NUMBER 1
 '@BASEBOARD_FAB2_LIB.BASEBOARD_FAB2(SCH_1):PAGE232_I260@MSTR_DISCRETE.CAP(CHIPS)':
 C_PATH='@baseboard_fab2_lib.baseboard_fab2(sch_1):page232_i260@mstr_discrete.ca~
p(chips)',
 P_PATH='@baseboard_fab2_lib.baseboard_fab2(sch_1):page232_i260@mstr_discrete.ca~
p(chips)',
 PATH='I260',
 DRAWING='@BASEBOARD_FAB2_LIB.BASEBOARD_FAB2(SCH_1):PAGE232',
 TOLERANCE='10%',
 SEC_TYPE='0805',
 MATERIAL='X6S',
 PHYS_PAGE='232',
 XY='(-6600,4100)',
 ROT='0',
 VER='1',
 VALUE='10UF',
 PACK_TYPE='0805',
 PART_NUMBER='C95333-007',
 LOCATION='C3M15',
 SEC='1',
 CDS_LIB='mstr_discrete',
 CDS_PART_NAME='CAP_0805-10UF,16V,10%,X6S,C953A',
 VOLTAGE='16V',
 PRIM_FILE='./archive_libs/mstr_discrete/cap/chips/chips.prt';

PART_NAME
 C3M16 'CAP_0805-10UF,16V,10%,X6S,C953A':;

SECTION_NUMBER 1
 '@BASEBOARD_FAB2_LIB.BASEBOARD_FAB2(SCH_1):PAGE232_I261@MSTR_DISCRETE.CAP(CHIPS)':
 C_PATH='@baseboard_fab2_lib.baseboard_fab2(sch_1):page232_i261@mstr_discrete.ca~
p(chips)',
 P_PATH='@baseboard_fab2_lib.baseboard_fab2(sch_1):page232_i261@mstr_discrete.ca~
p(chips)',
 PATH='I261',
 DRAWING='@BASEBOARD_FAB2_LIB.BASEBOARD_FAB2(SCH_1):PAGE232',
 TOLERANCE='10%',
 SEC_TYPE='0805',
 MATERIAL='X6S',
 PHYS_PAGE='232',
 XY='(-6225,4100)',
 ROT='0',
 VER='1',
 VALUE='10UF',
 PACK_TYPE='0805',
 PART_NUMBER='C95333-007',
 LOCATION='C3M16',
 SEC='1',
 CDS_LIB='mstr_discrete',
 CDS_PART_NAME='CAP_0805-10UF,16V,10%,X6S,C953A',
 VOLTAGE='16V',
 PRIM_FILE='./archive_libs/mstr_discrete/cap/chips/chips.prt';

PART_NAME
 C3M17 'CAP_0603LF-10UF,4V,20%,X6S,E15A':
 ROOM='SB_FILTER_PLL0';

SECTION_NUMBER 1
 '@BASEBOARD_FAB2_LIB.BASEBOARD_FAB2(SCH_1):PAGE127_I86@MSTR_DISCRETE.CAP(CHIPS)':
 C_PATH='@baseboard_fab2_lib.baseboard_fab2(sch_1):page127_i86@mstr_discrete.cap~
(chips)',
 P_PATH='@baseboard_fab2_lib.baseboard_fab2(sch_1):page127_i86@mstr_discrete.cap~
(chips)',
 PATH='I86',
 DRAWING='@BASEBOARD_FAB2_LIB.BASEBOARD_FAB2(SCH_1):PAGE127',
 TOLERANCE='20%',
 SEC_TYPE='0603LF',
 MATERIAL='X6S',
 BOM_COST='SB',
 PHYS_PAGE='127',
 XY='(-2575,-1075)',
 ROT='0',
 VER='1',
 VALUE='10UF',
 PACK_TYPE='0603LF',
 PART_NUMBER='E15431-001',
 LOCATION='C3M17',
 ROOM='SB_FILTER_PLL0',
 SEC='1',
 CDS_LIB='mstr_discrete',
 CDS_PART_NAME='CAP_0603LF-10UF,4V,20%,X6S,E15A',
 VOLTAGE='4V',
 PRIM_FILE='./archive_libs/mstr_discrete/cap/chips/chips.prt';

PART_NAME
 C3M18 'CAP_0603LF-10UF,4V,20%,X6S,E15A':
 ROOM='SB_FILTER_PLL1';

SECTION_NUMBER 1
 '@BASEBOARD_FAB2_LIB.BASEBOARD_FAB2(SCH_1):PAGE127_I85@MSTR_DISCRETE.CAP(CHIPS)':
 C_PATH='@baseboard_fab2_lib.baseboard_fab2(sch_1):page127_i85@mstr_discrete.cap~
(chips)',
 P_PATH='@baseboard_fab2_lib.baseboard_fab2(sch_1):page127_i85@mstr_discrete.cap~
(chips)',
 PATH='I85',
 DRAWING='@BASEBOARD_FAB2_LIB.BASEBOARD_FAB2(SCH_1):PAGE127',
 TOLERANCE='20%',
 SEC_TYPE='0603LF',
 MATERIAL='X6S',
 BOM_COST='SB',
 PHYS_PAGE='127',
 XY='(-2575,-2325)',
 ROT='0',
 VER='1',
 VALUE='10UF',
 PACK_TYPE='0603LF',
 PART_NUMBER='E15431-001',
 LOCATION='C3M18',
 ROOM='SB_FILTER_PLL1',
 SEC='1',
 CDS_LIB='mstr_discrete',
 CDS_PART_NAME='CAP_0603LF-10UF,4V,20%,X6S,E15A',
 VOLTAGE='4V',
 PRIM_FILE='./archive_libs/mstr_discrete/cap/chips/chips.prt';

PART_NAME
 C3M19 'CAP_A_0402V-1.0UF,6.3V,10%,X6SA':
 ROOM='SB_FILTER_PLL0';

SECTION_NUMBER 1
 '@BASEBOARD_FAB2_LIB.BASEBOARD_FAB2(SCH_1):PAGE127_I87@DEV_DISCRETE.CAP_A(CHIPS)':
 C_PATH='@baseboard_fab2_lib.baseboard_fab2(sch_1):page127_i87@dev_discrete.cap_~
a(chips)',
 P_PATH='@baseboard_fab2_lib.baseboard_fab2(sch_1):page127_i87@dev_discrete.cap_~
a(chips)',
 PATH='I87',
 DRAWING='@BASEBOARD_FAB2_LIB.BASEBOARD_FAB2(SCH_1):PAGE127',
 TOLERANCE='10%',
 SEC_TYPE='0402V',
 MATERIAL='X6S',
 BOM_COST='SB',
 PHYS_PAGE='127',
 XY='(-3450,-1050)',
 ROT='0',
 VER='1',
 VALUE='1.0UF',
 PACK_TYPE='0402V',
 PART_NUMBER='D97712-004',
 LOCATION='C3M19',
 ROOM='SB_FILTER_PLL0',
 SEC='1',
 CDS_LIB='dev_discrete',
 CDS_PART_NAME='CAP_A_0402V-1.0UF,6.3V,10%,X6SA',
 VOLTAGE='6.3V',
 PRIM_FILE='./archive_libs/discrete/cap_a/chips/chips.prt';

PART_NAME
 C3M20 'CAP_A_0402V-1.0UF,6.3V,10%,X6SA':
 ROOM='SB_FILTER_PLL1';

SECTION_NUMBER 1
 '@BASEBOARD_FAB2_LIB.BASEBOARD_FAB2(SCH_1):PAGE127_I84@DEV_DISCRETE.CAP_A(CHIPS)':
 C_PATH='@baseboard_fab2_lib.baseboard_fab2(sch_1):page127_i84@dev_discrete.cap_~
a(chips)',
 P_PATH='@baseboard_fab2_lib.baseboard_fab2(sch_1):page127_i84@dev_discrete.cap_~
a(chips)',
 PATH='I84',
 DRAWING='@BASEBOARD_FAB2_LIB.BASEBOARD_FAB2(SCH_1):PAGE127',
 TOLERANCE='10%',
 SEC_TYPE='0402V',
 MATERIAL='X6S',
 BOM_COST='SB',
 PHYS_PAGE='127',
 XY='(-3425,-2250)',
 ROT='0',
 VER='1',
 VALUE='1.0UF',
 PACK_TYPE='0402V',
 PART_NUMBER='D97712-004',
 LOCATION='C3M20',
 ROOM='SB_FILTER_PLL1',
 SEC='1',
 CDS_LIB='dev_discrete',
 CDS_PART_NAME='CAP_A_0402V-1.0UF,6.3V,10%,X6SA',
 VOLTAGE='6.3V',
 PRIM_FILE='./archive_libs/discrete/cap_a/chips/chips.prt';

PART_NAME
 C3M21 'CAP_A_0402V-1.0UF,6.3V,10%,X6SA':
 ROOM='SB_FILTER_PLL0';

SECTION_NUMBER 1
 '@BASEBOARD_FAB2_LIB.BASEBOARD_FAB2(SCH_1):PAGE127_I9@DEV_DISCRETE.CAP_A(CHIPS)':
 C_PATH='@baseboard_fab2_lib.baseboard_fab2(sch_1):page127_i9@dev_discrete.cap_a~
(chips)',
 P_PATH='@baseboard_fab2_lib.baseboard_fab2(sch_1):page127_i9@dev_discrete.cap_a~
(chips)',
 PATH='I9',
 DRAWING='@BASEBOARD_FAB2_LIB.BASEBOARD_FAB2(SCH_1):PAGE127',
 TOLERANCE='10%',
 SEC_TYPE='0402V',
 MATERIAL='X6S',
 BOM_COST='SB',
 PHYS_PAGE='127',
 XY='(-4300,-1050)',
 ROT='2',
 VER='1',
 VALUE='1.0UF',
 PACK_TYPE='0402V',
 PART_NUMBER='D97712-004',
 LOCATION='C3M21',
 ROOM='SB_FILTER_PLL0',
 SEC='1',
 CDS_LIB='dev_discrete',
 CDS_PART_NAME='CAP_A_0402V-1.0UF,6.3V,10%,X6SA',
 VOLTAGE='6.3V',
 PRIM_FILE='./archive_libs/discrete/cap_a/chips/chips.prt';

PART_NAME
 C3M22 'CAP_A_0402V-1.0UF,6.3V,10%,X6SA':
 ROOM='SB_FILTER_PLL1';

SECTION_NUMBER 1
 '@BASEBOARD_FAB2_LIB.BASEBOARD_FAB2(SCH_1):PAGE127_I18@DEV_DISCRETE.CAP_A(CHIPS)':
 C_PATH='@baseboard_fab2_lib.baseboard_fab2(sch_1):page127_i18@dev_discrete.cap_~
a(chips)',
 P_PATH='@baseboard_fab2_lib.baseboard_fab2(sch_1):page127_i18@dev_discrete.cap_~
a(chips)',
 PATH='I18',
 DRAWING='@BASEBOARD_FAB2_LIB.BASEBOARD_FAB2(SCH_1):PAGE127',
 TOLERANCE='10%',
 SEC_TYPE='0402V',
 MATERIAL='X6S',
 BOM_COST='SB',
 PHYS_PAGE='127',
 XY='(-4275,-2250)',
 ROT='2',
 VER='1',
 VALUE='1.0UF',
 PACK_TYPE='0402V',
 PART_NUMBER='D97712-004',
 LOCATION='C3M22',
 ROOM='SB_FILTER_PLL1',
 SEC='1',
 CDS_LIB='dev_discrete',
 CDS_PART_NAME='CAP_A_0402V-1.0UF,6.3V,10%,X6SA',
 VOLTAGE='6.3V',
 PRIM_FILE='./archive_libs/discrete/cap_a/chips/chips.prt';

PART_NAME
 C3M23 'CAP_0603LF-10UF,4V,20%,X6S,E15A':
 ROOM='SB_FILTER_XTAL';

SECTION_NUMBER 1
 '@BASEBOARD_FAB2_LIB.BASEBOARD_FAB2(SCH_1):PAGE127_I82@MSTR_DISCRETE.CAP(CHIPS)':
 C_PATH='@baseboard_fab2_lib.baseboard_fab2(sch_1):page127_i82@mstr_discrete.cap~
(chips)',
 P_PATH='@baseboard_fab2_lib.baseboard_fab2(sch_1):page127_i82@mstr_discrete.cap~
(chips)',
 PATH='I82',
 DRAWING='@BASEBOARD_FAB2_LIB.BASEBOARD_FAB2(SCH_1):PAGE127',
 TOLERANCE='20%',
 SEC_TYPE='0603LF',
 MATERIAL='X6S',
 BOM_COST='SB',
 PHYS_PAGE='127',
 XY='(-2550,-3600)',
 ROT='0',
 VER='1',
 VALUE='10UF',
 PACK_TYPE='0603LF',
 PART_NUMBER='E15431-001',
 LOCATION='C3M23',
 ROOM='SB_FILTER_XTAL',
 SEC='1',
 CDS_LIB='mstr_discrete',
 CDS_PART_NAME='CAP_0603LF-10UF,4V,20%,X6S,E15A',
 VOLTAGE='4V',
 PRIM_FILE='./archive_libs/mstr_discrete/cap/chips/chips.prt';

PART_NAME
 C3M24 'CAP_0603LF-10UF,4V,20%,X6S,E15A':
 ROOM='SB_FILTER_ISCLK';

SECTION_NUMBER 1
 '@BASEBOARD_FAB2_LIB.BASEBOARD_FAB2(SCH_1):PAGE127_I81@MSTR_DISCRETE.CAP(CHIPS)':
 C_PATH='@baseboard_fab2_lib.baseboard_fab2(sch_1):page127_i81@mstr_discrete.cap~
(chips)',
 P_PATH='@baseboard_fab2_lib.baseboard_fab2(sch_1):page127_i81@mstr_discrete.cap~
(chips)',
 PATH='I81',
 DRAWING='@BASEBOARD_FAB2_LIB.BASEBOARD_FAB2(SCH_1):PAGE127',
 TOLERANCE='20%',
 SEC_TYPE='0603LF',
 MATERIAL='X6S',
 BOM_COST='SB',
 PHYS_PAGE='127',
 XY='(1700,-3275)',
 ROT='0',
 VER='1',
 VALUE='10UF',
 PACK_TYPE='0603LF',
 PART_NUMBER='E15431-001',
 LOCATION='C3M24',
 ROOM='SB_FILTER_ISCLK',
 SEC='1',
 CDS_LIB='mstr_discrete',
 CDS_PART_NAME='CAP_0603LF-10UF,4V,20%,X6S,E15A',
 VOLTAGE='4V',
 PRIM_FILE='./archive_libs/mstr_discrete/cap/chips/chips.prt';

PART_NAME
 C3M25 'CAP_0402-0.22UF,16V,10%,X7R,A3A':
 GROUP='PCIE_UPLINK',
 ROOM='OCP_STEERING';

SECTION_NUMBER 1
 '@BASEBOARD_FAB2_LIB.BASEBOARD_FAB2(SCH_1):PAGE105_I205@MSTR_DISCRETE.CAP(CHIPS)':
 C_PATH='@baseboard_fab2_lib.baseboard_fab2(sch_1):page105_i205@mstr_discrete.ca~
p(chips)',
 P_PATH='@baseboard_fab2_lib.baseboard_fab2(sch_1):page105_i205@mstr_discrete.ca~
p(chips)',
 PATH='I205',
 DRAWING='@BASEBOARD_FAB2_LIB.BASEBOARD_FAB2(SCH_1):PAGE105',
 TOLERANCE='10%',
 MATERIAL='X7R',
 PHYS_PAGE='105',
 XY='(1800,2025)',
 ROT='2',
 VER='1',
 VALUE='0.22UF',
 PACK_TYPE='0402',
 PART_NUMBER='A36096-155',
 LOCATION='C3M25',
 ROOM='OCP_STEERING',
 GROUP='PCIE_UPLINK',
 CDS_LIB='mstr_discrete',
 CDS_PART_NAME='CAP_0402-0.22UF,16V,10%,X7R,A3A',
 VOLTAGE='16V',
 PRIM_FILE='./archive_libs/mstr_discrete/cap/chips/chips.prt';

PART_NAME
 C3M26 'CAP_0402-0.22UF,16V,10%,X7R,A3A':
 GROUP='PCIE_UPLINK',
 ROOM='OCP_STEERING';

SECTION_NUMBER 1
 '@BASEBOARD_FAB2_LIB.BASEBOARD_FAB2(SCH_1):PAGE105_I229@MSTR_DISCRETE.CAP(CHIPS)':
 C_PATH='@baseboard_fab2_lib.baseboard_fab2(sch_1):page105_i229@mstr_discrete.ca~
p(chips)',
 P_PATH='@baseboard_fab2_lib.baseboard_fab2(sch_1):page105_i229@mstr_discrete.ca~
p(chips)',
 PATH='I229',
 DRAWING='@BASEBOARD_FAB2_LIB.BASEBOARD_FAB2(SCH_1):PAGE105',
 TOLERANCE='10%',
 MATERIAL='X7R',
 PHYS_PAGE='105',
 XY='(1850,1025)',
 ROT='2',
 VER='1',
 VALUE='0.22UF',
 PACK_TYPE='0402',
 PART_NUMBER='A36096-155',
 LOCATION='C3M26',
 ROOM='OCP_STEERING',
 GROUP='PCIE_UPLINK',
 CDS_LIB='mstr_discrete',
 CDS_PART_NAME='CAP_0402-0.22UF,16V,10%,X7R,A3A',
 VOLTAGE='16V',
 PRIM_FILE='./archive_libs/mstr_discrete/cap/chips/chips.prt';

PART_NAME
 C3M27 'CAP_A_0402V-1.0UF,6.3V,10%,X6SA':
 ROOM='SB_FILTER_XTAL';

SECTION_NUMBER 1
 '@BASEBOARD_FAB2_LIB.BASEBOARD_FAB2(SCH_1):PAGE127_I83@DEV_DISCRETE.CAP_A(CHIPS)':
 C_PATH='@baseboard_fab2_lib.baseboard_fab2(sch_1):page127_i83@dev_discrete.cap_~
a(chips)',
 P_PATH='@baseboard_fab2_lib.baseboard_fab2(sch_1):page127_i83@dev_discrete.cap_~
a(chips)',
 PATH='I83',
 DRAWING='@BASEBOARD_FAB2_LIB.BASEBOARD_FAB2(SCH_1):PAGE127',
 TOLERANCE='10%',
 SEC_TYPE='0402V',
 MATERIAL='X6S',
 BOM_COST='SB',
 PHYS_PAGE='127',
 XY='(-3400,-3550)',
 ROT='0',
 VER='1',
 VALUE='1.0UF',
 PACK_TYPE='0402V',
 PART_NUMBER='D97712-004',
 LOCATION='C3M27',
 ROOM='SB_FILTER_XTAL',
 SEC='1',
 CDS_LIB='dev_discrete',
 CDS_PART_NAME='CAP_A_0402V-1.0UF,6.3V,10%,X6SA',
 VOLTAGE='6.3V',
 PRIM_FILE='./archive_libs/discrete/cap_a/chips/chips.prt';

PART_NAME
 C3M28 'CAP_0402-0.22UF,16V,10%,X7R,A3A':
 GROUP='PCIE_UPLINK',
 ROOM='OCP_STEERING';

SECTION_NUMBER 1
 '@BASEBOARD_FAB2_LIB.BASEBOARD_FAB2(SCH_1):PAGE105_I212@MSTR_DISCRETE.CAP(CHIPS)':
 C_PATH='@baseboard_fab2_lib.baseboard_fab2(sch_1):page105_i212@mstr_discrete.ca~
p(chips)',
 P_PATH='@baseboard_fab2_lib.baseboard_fab2(sch_1):page105_i212@mstr_discrete.ca~
p(chips)',
 PATH='I212',
 DRAWING='@BASEBOARD_FAB2_LIB.BASEBOARD_FAB2(SCH_1):PAGE105',
 TOLERANCE='10%',
 MATERIAL='X7R',
 PHYS_PAGE='105',
 XY='(2000,2325)',
 ROT='2',
 VER='1',
 VALUE='0.22UF',
 PACK_TYPE='0402',
 PART_NUMBER='A36096-155',
 LOCATION='C3M28',
 ROOM='OCP_STEERING',
 GROUP='PCIE_UPLINK',
 CDS_LIB='mstr_discrete',
 CDS_PART_NAME='CAP_0402-0.22UF,16V,10%,X7R,A3A',
 VOLTAGE='16V',
 PRIM_FILE='./archive_libs/mstr_discrete/cap/chips/chips.prt';

PART_NAME
 C3M29 'CAP_A_0402V-1.0UF,6.3V,10%,X6SA':
 ROOM='SB_FILTER_ISCLK';

SECTION_NUMBER 1
 '@BASEBOARD_FAB2_LIB.BASEBOARD_FAB2(SCH_1):PAGE127_I80@DEV_DISCRETE.CAP_A(CHIPS)':
 C_PATH='@baseboard_fab2_lib.baseboard_fab2(sch_1):page127_i80@dev_discrete.cap_~
a(chips)',
 P_PATH='@baseboard_fab2_lib.baseboard_fab2(sch_1):page127_i80@dev_discrete.cap_~
a(chips)',
 PATH='I80',
 DRAWING='@BASEBOARD_FAB2_LIB.BASEBOARD_FAB2(SCH_1):PAGE127',
 TOLERANCE='10%',
 SEC_TYPE='0402V',
 MATERIAL='X6S',
 BOM_COST='SB',
 PHYS_PAGE='127',
 XY='(1400,-3275)',
 ROT='0',
 VER='1',
 VALUE='1.0UF',
 PACK_TYPE='0402V',
 PART_NUMBER='D97712-004',
 LOCATION='C3M29',
 ROOM='SB_FILTER_ISCLK',
 SEC='1',
 CDS_LIB='dev_discrete',
 CDS_PART_NAME='CAP_A_0402V-1.0UF,6.3V,10%,X6SA',
 VOLTAGE='6.3V',
 PRIM_FILE='./archive_libs/discrete/cap_a/chips/chips.prt';

PART_NAME
 C3M30 'CAP_A_0402V-1.0UF,6.3V,10%,X6SA':
 ROOM='SB_FILTER_XTAL';

SECTION_NUMBER 1
 '@BASEBOARD_FAB2_LIB.BASEBOARD_FAB2(SCH_1):PAGE127_I27@DEV_DISCRETE.CAP_A(CHIPS)':
 C_PATH='@baseboard_fab2_lib.baseboard_fab2(sch_1):page127_i27@dev_discrete.cap_~
a(chips)',
 P_PATH='@baseboard_fab2_lib.baseboard_fab2(sch_1):page127_i27@dev_discrete.cap_~
a(chips)',
 PATH='I27',
 DRAWING='@BASEBOARD_FAB2_LIB.BASEBOARD_FAB2(SCH_1):PAGE127',
 TOLERANCE='10%',
 SEC_TYPE='0402V',
 MATERIAL='X6S',
 BOM_COST='SB',
 PHYS_PAGE='127',
 XY='(-4250,-3550)',
 ROT='2',
 VER='1',
 VALUE='1.0UF',
 PACK_TYPE='0402V',
 PART_NUMBER='D97712-004',
 LOCATION='C3M30',
 ROOM='SB_FILTER_XTAL',
 SEC='1',
 CDS_LIB='dev_discrete',
 CDS_PART_NAME='CAP_A_0402V-1.0UF,6.3V,10%,X6SA',
 VOLTAGE='6.3V',
 PRIM_FILE='./archive_libs/discrete/cap_a/chips/chips.prt';

PART_NAME
 C3M31 'CAP_A_0402V-1.0UF,6.3V,10%,X6SA':
 ROOM='SB_FILTER_ISCLK';

SECTION_NUMBER 1
 '@BASEBOARD_FAB2_LIB.BASEBOARD_FAB2(SCH_1):PAGE127_I57@DEV_DISCRETE.CAP_A(CHIPS)':
 C_PATH='@baseboard_fab2_lib.baseboard_fab2(sch_1):page127_i57@dev_discrete.cap_~
a(chips)',
 P_PATH='@baseboard_fab2_lib.baseboard_fab2(sch_1):page127_i57@dev_discrete.cap_~
a(chips)',
 PATH='I57',
 DRAWING='@BASEBOARD_FAB2_LIB.BASEBOARD_FAB2(SCH_1):PAGE127',
 TOLERANCE='10%',
 SEC_TYPE='0402V',
 MATERIAL='X6S',
 BOM_COST='SB',
 PHYS_PAGE='127',
 XY='(950,-3275)',
 ROT='2',
 VER='1',
 VALUE='1.0UF',
 PACK_TYPE='0402V',
 PART_NUMBER='D97712-004',
 LOCATION='C3M31',
 ROOM='SB_FILTER_ISCLK',
 SEC='1',
 CDS_LIB='dev_discrete',
 CDS_PART_NAME='CAP_A_0402V-1.0UF,6.3V,10%,X6SA',
 VOLTAGE='6.3V',
 PRIM_FILE='./archive_libs/discrete/cap_a/chips/chips.prt';

PART_NAME
 C3M32 'CAP_0402-0.22UF,16V,10%,X7R,A3A':
 GROUP='PCIE_UPLINK',
 ROOM='OCP_STEERING';

SECTION_NUMBER 1
 '@BASEBOARD_FAB2_LIB.BASEBOARD_FAB2(SCH_1):PAGE105_I223@MSTR_DISCRETE.CAP(CHIPS)':
 C_PATH='@baseboard_fab2_lib.baseboard_fab2(sch_1):page105_i223@mstr_discrete.ca~
p(chips)',
 P_PATH='@baseboard_fab2_lib.baseboard_fab2(sch_1):page105_i223@mstr_discrete.ca~
p(chips)',
 PATH='I223',
 DRAWING='@BASEBOARD_FAB2_LIB.BASEBOARD_FAB2(SCH_1):PAGE105',
 TOLERANCE='10%',
 MATERIAL='X7R',
 PHYS_PAGE='105',
 XY='(2050,1325)',
 ROT='2',
 VER='1',
 VALUE='0.22UF',
 PACK_TYPE='0402',
 PART_NUMBER='A36096-155',
 LOCATION='C3M32',
 ROOM='OCP_STEERING',
 GROUP='PCIE_UPLINK',
 CDS_LIB='mstr_discrete',
 CDS_PART_NAME='CAP_0402-0.22UF,16V,10%,X7R,A3A',
 VOLTAGE='16V',
 PRIM_FILE='./archive_libs/mstr_discrete/cap/chips/chips.prt';

PART_NAME
 C3M33 'CAP_0402-0.22UF,16V,10%,X7R,A3A':
 GROUP='PCIE_UPLINK',
 ROOM='OCP_STEERING';

SECTION_NUMBER 1
 '@BASEBOARD_FAB2_LIB.BASEBOARD_FAB2(SCH_1):PAGE105_I217@MSTR_DISCRETE.CAP(CHIPS)':
 C_PATH='@baseboard_fab2_lib.baseboard_fab2(sch_1):page105_i217@mstr_discrete.ca~
p(chips)',
 P_PATH='@baseboard_fab2_lib.baseboard_fab2(sch_1):page105_i217@mstr_discrete.ca~
p(chips)',
 PATH='I217',
 DRAWING='@BASEBOARD_FAB2_LIB.BASEBOARD_FAB2(SCH_1):PAGE105',
 TOLERANCE='10%',
 MATERIAL='X7R',
 PHYS_PAGE='105',
 XY='(2450,1325)',
 ROT='2',
 VER='1',
 VALUE='0.22UF',
 PACK_TYPE='0402',
 PART_NUMBER='A36096-155',
 LOCATION='C3M33',
 ROOM='OCP_STEERING',
 GROUP='PCIE_UPLINK',
 CDS_LIB='mstr_discrete',
 CDS_PART_NAME='CAP_0402-0.22UF,16V,10%,X7R,A3A',
 VOLTAGE='16V',
 PRIM_FILE='./archive_libs/mstr_discrete/cap/chips/chips.prt';

PART_NAME
 C3M34 'CAP_0402-0.22UF,16V,10%,X7R,A3A':
 GROUP='PCIE_UPLINK',
 ROOM='OCP_STEERING';

SECTION_NUMBER 1
 '@BASEBOARD_FAB2_LIB.BASEBOARD_FAB2(SCH_1):PAGE105_I206@MSTR_DISCRETE.CAP(CHIPS)':
 C_PATH='@baseboard_fab2_lib.baseboard_fab2(sch_1):page105_i206@mstr_discrete.ca~
p(chips)',
 P_PATH='@baseboard_fab2_lib.baseboard_fab2(sch_1):page105_i206@mstr_discrete.ca~
p(chips)',
 PATH='I206',
 DRAWING='@BASEBOARD_FAB2_LIB.BASEBOARD_FAB2(SCH_1):PAGE105',
 TOLERANCE='10%',
 MATERIAL='X7R',
 PHYS_PAGE='105',
 XY='(2400,2325)',
 ROT='2',
 VER='1',
 VALUE='0.22UF',
 PACK_TYPE='0402',
 PART_NUMBER='A36096-155',
 LOCATION='C3M34',
 ROOM='OCP_STEERING',
 GROUP='PCIE_UPLINK',
 CDS_LIB='mstr_discrete',
 CDS_PART_NAME='CAP_0402-0.22UF,16V,10%,X7R,A3A',
 VOLTAGE='16V',
 PRIM_FILE='./archive_libs/mstr_discrete/cap/chips/chips.prt';

PART_NAME
 C3M35 'CAP_0402-0.22UF,16V,10%,X7R,A3A':
 GROUP='PCIE_UPLINK',
 ROOM='OCP_STEERING';

SECTION_NUMBER 1
 '@BASEBOARD_FAB2_LIB.BASEBOARD_FAB2(SCH_1):PAGE105_I225@MSTR_DISCRETE.CAP(CHIPS)':
 C_PATH='@baseboard_fab2_lib.baseboard_fab2(sch_1):page105_i225@mstr_discrete.ca~
p(chips)',
 P_PATH='@baseboard_fab2_lib.baseboard_fab2(sch_1):page105_i225@mstr_discrete.ca~
p(chips)',
 PATH='I225',
 DRAWING='@BASEBOARD_FAB2_LIB.BASEBOARD_FAB2(SCH_1):PAGE105',
 TOLERANCE='10%',
 MATERIAL='X7R',
 PHYS_PAGE='105',
 XY='(2250,1025)',
 ROT='2',
 VER='1',
 VALUE='0.22UF',
 PACK_TYPE='0402',
 PART_NUMBER='A36096-155',
 LOCATION='C3M35',
 ROOM='OCP_STEERING',
 GROUP='PCIE_UPLINK',
 CDS_LIB='mstr_discrete',
 CDS_PART_NAME='CAP_0402-0.22UF,16V,10%,X7R,A3A',
 VOLTAGE='16V',
 PRIM_FILE='./archive_libs/mstr_discrete/cap/chips/chips.prt';

PART_NAME
 C3M36 'CAP_0402-0.22UF,16V,10%,X7R,A3A':
 GROUP='PCIE_UPLINK',
 ROOM='OCP_STEERING';

SECTION_NUMBER 1
 '@BASEBOARD_FAB2_LIB.BASEBOARD_FAB2(SCH_1):PAGE105_I218@MSTR_DISCRETE.CAP(CHIPS)':
 C_PATH='@baseboard_fab2_lib.baseboard_fab2(sch_1):page105_i218@mstr_discrete.ca~
p(chips)',
 P_PATH='@baseboard_fab2_lib.baseboard_fab2(sch_1):page105_i218@mstr_discrete.ca~
p(chips)',
 PATH='I218',
 DRAWING='@BASEBOARD_FAB2_LIB.BASEBOARD_FAB2(SCH_1):PAGE105',
 TOLERANCE='10%',
 MATERIAL='X7R',
 PHYS_PAGE='105',
 XY='(2200,2025)',
 ROT='2',
 VER='1',
 VALUE='0.22UF',
 PACK_TYPE='0402',
 PART_NUMBER='A36096-155',
 LOCATION='C3M36',
 ROOM='OCP_STEERING',
 GROUP='PCIE_UPLINK',
 CDS_LIB='mstr_discrete',
 CDS_PART_NAME='CAP_0402-0.22UF,16V,10%,X7R,A3A',
 VOLTAGE='16V',
 PRIM_FILE='./archive_libs/mstr_discrete/cap/chips/chips.prt';

PART_NAME
 C3M37 'CAP_0402-0.22UF,16V,10%,X7R,A3A':
 ROOM='DMI';

SECTION_NUMBER 1
 '@BASEBOARD_FAB2_LIB.BASEBOARD_FAB2(SCH_1):PAGE129_I73@MSTR_DISCRETE.CAP(CHIPS)':
 C_PATH='@baseboard_fab2_lib.baseboard_fab2(sch_1):page129_i73@mstr_discrete.cap~
(chips)',
 P_PATH='@baseboard_fab2_lib.baseboard_fab2(sch_1):page129_i73@mstr_discrete.cap~
(chips)',
 PATH='I73',
 DRAWING='@BASEBOARD_FAB2_LIB.BASEBOARD_FAB2(SCH_1):PAGE129',
 TOLERANCE='10%',
 MATERIAL='X7R',
 BOM_COST='SB',
 PHYS_PAGE='129',
 XY='(-3650,3575)',
 ROT='1',
 VER='1',
 VALUE='0.22UF',
 PACK_TYPE='0402',
 PART_NUMBER='A36096-155',
 LOCATION='C3M37',
 ROOM='DMI',
 CDS_LIB='mstr_discrete',
 CDS_PART_NAME='CAP_0402-0.22UF,16V,10%,X7R,A3A',
 VOLTAGE='16V',
 PRIM_FILE='./archive_libs/mstr_discrete/cap/chips/chips.prt';

PART_NAME
 C3M38 'CAP_A_0402V-1.0UF,6.3V,10%,X6SA':
 ROOM='SB_DECOUPLING';

SECTION_NUMBER 1
 '@BASEBOARD_FAB2_LIB.BASEBOARD_FAB2(SCH_1):PAGE131_I32@DEV_DISCRETE.CAP_A(CHIPS)':
 C_PATH='@baseboard_fab2_lib.baseboard_fab2(sch_1):page131_i32@dev_discrete.cap_~
a(chips)',
 P_PATH='@baseboard_fab2_lib.baseboard_fab2(sch_1):page131_i32@dev_discrete.cap_~
a(chips)',
 PATH='I32',
 DRAWING='@BASEBOARD_FAB2_LIB.BASEBOARD_FAB2(SCH_1):PAGE131',
 TOLERANCE='10%',
 MATERIAL='X6S',
 BOM_COST='SB',
 PHYS_PAGE='131',
 XY='(-3225,3525)',
 ROT='0',
 VER='1',
 VALUE='1.0UF',
 PACK_TYPE='0402V',
 PART_NUMBER='D97712-004',
 LOCATION='C3M38',
 ROOM='SB_DECOUPLING',
 CDS_LIB='dev_discrete',
 CDS_PART_NAME='CAP_A_0402V-1.0UF,6.3V,10%,X6SA',
 VOLTAGE='6.3V',
 PRIM_FILE='./archive_libs/discrete/cap_a/chips/chips.prt';

PART_NAME
 C3M39 'CAP_A_0402V-1.0UF,6.3V,10%,X6SA':
 ROOM='SB_DECOUPLING';

SECTION_NUMBER 1
 '@BASEBOARD_FAB2_LIB.BASEBOARD_FAB2(SCH_1):PAGE131_I44@DEV_DISCRETE.CAP_A(CHIPS)':
 C_PATH='@baseboard_fab2_lib.baseboard_fab2(sch_1):page131_i44@dev_discrete.cap_~
a(chips)',
 P_PATH='@baseboard_fab2_lib.baseboard_fab2(sch_1):page131_i44@dev_discrete.cap_~
a(chips)',
 PATH='I44',
 DRAWING='@BASEBOARD_FAB2_LIB.BASEBOARD_FAB2(SCH_1):PAGE131',
 TOLERANCE='10%',
 MATERIAL='X6S',
 BOM_COST='SB',
 PHYS_PAGE='131',
 XY='(-4375,3525)',
 ROT='0',
 VER='1',
 VALUE='1.0UF',
 PACK_TYPE='0402V',
 PART_NUMBER='D97712-004',
 LOCATION='C3M39',
 ROOM='SB_DECOUPLING',
 CDS_LIB='dev_discrete',
 CDS_PART_NAME='CAP_A_0402V-1.0UF,6.3V,10%,X6SA',
 VOLTAGE='6.3V',
 PRIM_FILE='./archive_libs/discrete/cap_a/chips/chips.prt';

PART_NAME
 C3M40 'CAP_0402-0.22UF,16V,10%,X7R,A3A':
 ROOM='DMI';

SECTION_NUMBER 1
 '@BASEBOARD_FAB2_LIB.BASEBOARD_FAB2(SCH_1):PAGE129_I72@MSTR_DISCRETE.CAP(CHIPS)':
 C_PATH='@baseboard_fab2_lib.baseboard_fab2(sch_1):page129_i72@mstr_discrete.cap~
(chips)',
 P_PATH='@baseboard_fab2_lib.baseboard_fab2(sch_1):page129_i72@mstr_discrete.cap~
(chips)',
 PATH='I72',
 DRAWING='@BASEBOARD_FAB2_LIB.BASEBOARD_FAB2(SCH_1):PAGE129',
 TOLERANCE='10%',
 MATERIAL='X7R',
 BOM_COST='SB',
 PHYS_PAGE='129',
 XY='(-3300,3375)',
 ROT='1',
 VER='1',
 VALUE='0.22UF',
 PACK_TYPE='0402',
 PART_NUMBER='A36096-155',
 LOCATION='C3M40',
 ROOM='DMI',
 CDS_LIB='mstr_discrete',
 CDS_PART_NAME='CAP_0402-0.22UF,16V,10%,X7R,A3A',
 VOLTAGE='16V',
 PRIM_FILE='./archive_libs/mstr_discrete/cap/chips/chips.prt';

PART_NAME
 C3M41 'CAP_0402-0.22UF,16V,10%,X7R,A3A':
 ROOM='DMI';

SECTION_NUMBER 1
 '@BASEBOARD_FAB2_LIB.BASEBOARD_FAB2(SCH_1):PAGE129_I81@MSTR_DISCRETE.CAP(CHIPS)':
 C_PATH='@baseboard_fab2_lib.baseboard_fab2(sch_1):page129_i81@mstr_discrete.cap~
(chips)',
 P_PATH='@baseboard_fab2_lib.baseboard_fab2(sch_1):page129_i81@mstr_discrete.cap~
(chips)',
 PATH='I81',
 DRAWING='@BASEBOARD_FAB2_LIB.BASEBOARD_FAB2(SCH_1):PAGE129',
 TOLERANCE='10%',
 MATERIAL='X7R',
 BOM_COST='SB',
 PHYS_PAGE='129',
 XY='(400,3575)',
 ROT='1',
 VER='1',
 VALUE='0.22UF',
 PACK_TYPE='0402',
 PART_NUMBER='A36096-155',
 LOCATION='C3M41',
 ROOM='DMI',
 CDS_LIB='mstr_discrete',
 CDS_PART_NAME='CAP_0402-0.22UF,16V,10%,X7R,A3A',
 VOLTAGE='16V',
 PRIM_FILE='./archive_libs/mstr_discrete/cap/chips/chips.prt';

PART_NAME
 C3M42 'CAP_A_0402V-1.0UF,6.3V,10%,X6SA':
 ROOM='SB_DECOUPLING';

SECTION_NUMBER 1
 '@BASEBOARD_FAB2_LIB.BASEBOARD_FAB2(SCH_1):PAGE131_I45@DEV_DISCRETE.CAP_A(CHIPS)':
 C_PATH='@baseboard_fab2_lib.baseboard_fab2(sch_1):page131_i45@dev_discrete.cap_~
a(chips)',
 P_PATH='@baseboard_fab2_lib.baseboard_fab2(sch_1):page131_i45@dev_discrete.cap_~
a(chips)',
 PATH='I45',
 DRAWING='@BASEBOARD_FAB2_LIB.BASEBOARD_FAB2(SCH_1):PAGE131',
 TOLERANCE='10%',
 MATERIAL='X6S',
 BOM_COST='SB',
 PHYS_PAGE='131',
 XY='(-4750,4725)',
 ROT='0',
 VER='1',
 VALUE='1.0UF',
 PACK_TYPE='0402V',
 PART_NUMBER='D97712-004',
 LOCATION='C3M42',
 ROOM='SB_DECOUPLING',
 CDS_LIB='dev_discrete',
 CDS_PART_NAME='CAP_A_0402V-1.0UF,6.3V,10%,X6SA',
 VOLTAGE='6.3V',
 PRIM_FILE='./archive_libs/discrete/cap_a/chips/chips.prt';

PART_NAME
 C3M43 'CAP_A_0402V-1.0UF,6.3V,10%,X6SA':
 ROOM='SB_DECOUPLING';

SECTION_NUMBER 1
 '@BASEBOARD_FAB2_LIB.BASEBOARD_FAB2(SCH_1):PAGE131_I42@DEV_DISCRETE.CAP_A(CHIPS)':
 C_PATH='@baseboard_fab2_lib.baseboard_fab2(sch_1):page131_i42@dev_discrete.cap_~
a(chips)',
 P_PATH='@baseboard_fab2_lib.baseboard_fab2(sch_1):page131_i42@dev_discrete.cap_~
a(chips)',
 PATH='I42',
 DRAWING='@BASEBOARD_FAB2_LIB.BASEBOARD_FAB2(SCH_1):PAGE131',
 TOLERANCE='10%',
 MATERIAL='X6S',
 BOM_COST='SB',
 PHYS_PAGE='131',
 XY='(-3600,3525)',
 ROT='0',
 VER='1',
 VALUE='1.0UF',
 PACK_TYPE='0402V',
 PART_NUMBER='D97712-004',
 LOCATION='C3M43',
 ROOM='SB_DECOUPLING',
 CDS_LIB='dev_discrete',
 CDS_PART_NAME='CAP_A_0402V-1.0UF,6.3V,10%,X6SA',
 VOLTAGE='6.3V',
 PRIM_FILE='./archive_libs/discrete/cap_a/chips/chips.prt';

PART_NAME
 C3M44 'CAP_0402-0.22UF,16V,10%,X7R,A3A':
 ROOM='DMI';

SECTION_NUMBER 1
 '@BASEBOARD_FAB2_LIB.BASEBOARD_FAB2(SCH_1):PAGE129_I80@MSTR_DISCRETE.CAP(CHIPS)':
 C_PATH='@baseboard_fab2_lib.baseboard_fab2(sch_1):page129_i80@mstr_discrete.cap~
(chips)',
 P_PATH='@baseboard_fab2_lib.baseboard_fab2(sch_1):page129_i80@mstr_discrete.cap~
(chips)',
 PATH='I80',
 DRAWING='@BASEBOARD_FAB2_LIB.BASEBOARD_FAB2(SCH_1):PAGE129',
 TOLERANCE='10%',
 MATERIAL='X7R',
 BOM_COST='SB',
 PHYS_PAGE='129',
 XY='(750,3375)',
 ROT='1',
 VER='1',
 VALUE='0.22UF',
 PACK_TYPE='0402',
 PART_NUMBER='A36096-155',
 LOCATION='C3M44',
 ROOM='DMI',
 CDS_LIB='mstr_discrete',
 CDS_PART_NAME='CAP_0402-0.22UF,16V,10%,X7R,A3A',
 VOLTAGE='16V',
 PRIM_FILE='./archive_libs/mstr_discrete/cap/chips/chips.prt';

PART_NAME
 C3M45 'CAP_0402-0.22UF,16V,10%,X7R,A3A':
 ROOM='DMI';

SECTION_NUMBER 1
 '@BASEBOARD_FAB2_LIB.BASEBOARD_FAB2(SCH_1):PAGE129_I82@MSTR_DISCRETE.CAP(CHIPS)':
 C_PATH='@baseboard_fab2_lib.baseboard_fab2(sch_1):page129_i82@mstr_discrete.cap~
(chips)',
 P_PATH='@baseboard_fab2_lib.baseboard_fab2(sch_1):page129_i82@mstr_discrete.cap~
(chips)',
 PATH='I82',
 DRAWING='@BASEBOARD_FAB2_LIB.BASEBOARD_FAB2(SCH_1):PAGE129',
 TOLERANCE='10%',
 MATERIAL='X7R',
 BOM_COST='SB',
 PHYS_PAGE='129',
 XY='(750,3775)',
 ROT='1',
 VER='1',
 VALUE='0.22UF',
 PACK_TYPE='0402',
 PART_NUMBER='A36096-155',
 LOCATION='C3M45',
 ROOM='DMI',
 CDS_LIB='mstr_discrete',
 CDS_PART_NAME='CAP_0402-0.22UF,16V,10%,X7R,A3A',
 VOLTAGE='16V',
 PRIM_FILE='./archive_libs/mstr_discrete/cap/chips/chips.prt';

PART_NAME
 C3M46 'CAP_A_0402V-1.0UF,6.3V,10%,X6SA':
 GROUP='PWR_MCP_CAP',
 ROOM='P0V95_MCP_CPU0';

SECTION_NUMBER 1
 '@BASEBOARD_FAB2_LIB.BASEBOARD_FAB2(SCH_1):PAGE194_I99@DEV_DISCRETE.CAP_A(CHIPS)':
 C_PATH='@baseboard_fab2_lib.baseboard_fab2(sch_1):page194_i99@dev_discrete.cap_~
a(chips)',
 P_PATH='@baseboard_fab2_lib.baseboard_fab2(sch_1):page194_i99@dev_discrete.cap_~
a(chips)',
 PATH='I99',
 DRAWING='@BASEBOARD_FAB2_LIB.BASEBOARD_FAB2(SCH_1):PAGE194',
 TOLERANCE='10%',
 SEC_TYPE='0402V',
 MATERIAL='X6S',
 PHYS_PAGE='194',
 XY='(-1400,3100)',
 ROT='0',
 VER='1',
 VALUE='1.0UF',
 PACK_TYPE='0402V',
 PART_NUMBER='D97712-004',
 LOCATION='C3M46',
 ROOM='P0V95_MCP_CPU0',
 GROUP='PWR_MCP_CAP',
 SEC='1',
 CDS_LIB='dev_discrete',
 CDS_PART_NAME='CAP_A_0402V-1.0UF,6.3V,10%,X6SA',
 VOLTAGE='6.3V',
 PRIM_FILE='./archive_libs/discrete/cap_a/chips/chips.prt';

PART_NAME
 C3N1 'CAP_A_0402V-1.0UF,6.3V,10%,X6SA':
 ROOM='SB_DECOUPLING';

SECTION_NUMBER 1
 '@BASEBOARD_FAB2_LIB.BASEBOARD_FAB2(SCH_1):PAGE132_I34@DEV_DISCRETE.CAP_A(CHIPS)':
 C_PATH='@baseboard_fab2_lib.baseboard_fab2(sch_1):page132_i34@dev_discrete.cap_~
a(chips)',
 P_PATH='@baseboard_fab2_lib.baseboard_fab2(sch_1):page132_i34@dev_discrete.cap_~
a(chips)',
 PATH='I34',
 DRAWING='@BASEBOARD_FAB2_LIB.BASEBOARD_FAB2(SCH_1):PAGE132',
 TOLERANCE='10%',
 MATERIAL='X6S',
 BOM_COST='SB',
 PHYS_PAGE='132',
 XY='(-1075,3025)',
 ROT='0',
 VER='1',
 VALUE='1.0UF',
 PACK_TYPE='0402V',
 PART_NUMBER='D97712-004',
 LOCATION='C3N1',
 ROOM='SB_DECOUPLING',
 CDS_LIB='dev_discrete',
 CDS_PART_NAME='CAP_A_0402V-1.0UF,6.3V,10%,X6SA',
 VOLTAGE='6.3V',
 PRIM_FILE='./archive_libs/discrete/cap_a/chips/chips.prt';

PART_NAME
 C3N2 'CAP_A_0402V-1.0UF,6.3V,10%,X6SA':
 ROOM='SB_DECOUPLING';

SECTION_NUMBER 1
 '@BASEBOARD_FAB2_LIB.BASEBOARD_FAB2(SCH_1):PAGE132_I43@DEV_DISCRETE.CAP_A(CHIPS)':
 C_PATH='@baseboard_fab2_lib.baseboard_fab2(sch_1):page132_i43@dev_discrete.cap_~
a(chips)',
 P_PATH='@baseboard_fab2_lib.baseboard_fab2(sch_1):page132_i43@dev_discrete.cap_~
a(chips)',
 PATH='I43',
 DRAWING='@BASEBOARD_FAB2_LIB.BASEBOARD_FAB2(SCH_1):PAGE132',
 TOLERANCE='10%',
 MATERIAL='X6S',
 BOM_COST='SB',
 PHYS_PAGE='132',
 XY='(-2625,4050)',
 ROT='0',
 VER='1',
 VALUE='1.0UF',
 PACK_TYPE='0402V',
 PART_NUMBER='D97712-004',
 LOCATION='C3N2',
 ROOM='SB_DECOUPLING',
 CDS_LIB='dev_discrete',
 CDS_PART_NAME='CAP_A_0402V-1.0UF,6.3V,10%,X6SA',
 VOLTAGE='6.3V',
 PRIM_FILE='./archive_libs/discrete/cap_a/chips/chips.prt';

PART_NAME
 C3N3 'CAP_A_0402V-1.0UF,6.3V,10%,X6SA':
 ROOM='SB_DECOUPLING';

SECTION_NUMBER 1
 '@BASEBOARD_FAB2_LIB.BASEBOARD_FAB2(SCH_1):PAGE132_I32@DEV_DISCRETE.CAP_A(CHIPS)':
 C_PATH='@baseboard_fab2_lib.baseboard_fab2(sch_1):page132_i32@dev_discrete.cap_~
a(chips)',
 P_PATH='@baseboard_fab2_lib.baseboard_fab2(sch_1):page132_i32@dev_discrete.cap_~
a(chips)',
 PATH='I32',
 DRAWING='@BASEBOARD_FAB2_LIB.BASEBOARD_FAB2(SCH_1):PAGE132',
 TOLERANCE='10%',
 MATERIAL='X6S',
 BOM_COST='SB',
 PHYS_PAGE='132',
 XY='(-1850,4050)',
 ROT='0',
 VER='1',
 VALUE='1.0UF',
 PACK_TYPE='0402V',
 PART_NUMBER='D97712-004',
 LOCATION='C3N3',
 ROOM='SB_DECOUPLING',
 CDS_LIB='dev_discrete',
 CDS_PART_NAME='CAP_A_0402V-1.0UF,6.3V,10%,X6SA',
 VOLTAGE='6.3V',
 PRIM_FILE='./archive_libs/discrete/cap_a/chips/chips.prt';

PART_NAME
 C3N4 'CAP_A_0402V-1.0UF,6.3V,10%,X6SA':
 ROOM='SB_DECOUPLING';

SECTION_NUMBER 1
 '@BASEBOARD_FAB2_LIB.BASEBOARD_FAB2(SCH_1):PAGE132_I46@DEV_DISCRETE.CAP_A(CHIPS)':
 C_PATH='@baseboard_fab2_lib.baseboard_fab2(sch_1):page132_i46@dev_discrete.cap_~
a(chips)',
 P_PATH='@baseboard_fab2_lib.baseboard_fab2(sch_1):page132_i46@dev_discrete.cap_~
a(chips)',
 PATH='I46',
 DRAWING='@BASEBOARD_FAB2_LIB.BASEBOARD_FAB2(SCH_1):PAGE132',
 TOLERANCE='10%',
 MATERIAL='X6S',
 BOM_COST='SB',
 PHYS_PAGE='132',
 XY='(-3000,4050)',
 ROT='0',
 VER='1',
 VALUE='1.0UF',
 PACK_TYPE='0402V',
 PART_NUMBER='D97712-004',
 LOCATION='C3N4',
 ROOM='SB_DECOUPLING',
 CDS_LIB='dev_discrete',
 CDS_PART_NAME='CAP_A_0402V-1.0UF,6.3V,10%,X6SA',
 VOLTAGE='6.3V',
 PRIM_FILE='./archive_libs/discrete/cap_a/chips/chips.prt';

PART_NAME
 C3N5 'CAP_A_0402V-1.0UF,6.3V,10%,X6SA':
 ROOM='SB_DECOUPLING';

SECTION_NUMBER 1
 '@BASEBOARD_FAB2_LIB.BASEBOARD_FAB2(SCH_1):PAGE132_I48@DEV_DISCRETE.CAP_A(CHIPS)':
 C_PATH='@baseboard_fab2_lib.baseboard_fab2(sch_1):page132_i48@dev_discrete.cap_~
a(chips)',
 P_PATH='@baseboard_fab2_lib.baseboard_fab2(sch_1):page132_i48@dev_discrete.cap_~
a(chips)',
 PATH='I48',
 DRAWING='@BASEBOARD_FAB2_LIB.BASEBOARD_FAB2(SCH_1):PAGE132',
 TOLERANCE='10%',
 MATERIAL='X6S',
 BOM_COST='SB',
 PHYS_PAGE='132',
 XY='(-3400,4050)',
 ROT='0',
 VER='1',
 VALUE='1.0UF',
 PACK_TYPE='0402V',
 PART_NUMBER='D97712-004',
 LOCATION='C3N5',
 ROOM='SB_DECOUPLING',
 CDS_LIB='dev_discrete',
 CDS_PART_NAME='CAP_A_0402V-1.0UF,6.3V,10%,X6SA',
 VOLTAGE='6.3V',
 PRIM_FILE='./archive_libs/discrete/cap_a/chips/chips.prt';

PART_NAME
 C3N6 'CAP_A_0402V-1.0UF,6.3V,10%,X6SA':
 ROOM='SB_DECOUPLING';

SECTION_NUMBER 1
 '@BASEBOARD_FAB2_LIB.BASEBOARD_FAB2(SCH_1):PAGE132_I44@DEV_DISCRETE.CAP_A(CHIPS)':
 C_PATH='@baseboard_fab2_lib.baseboard_fab2(sch_1):page132_i44@dev_discrete.cap_~
a(chips)',
 P_PATH='@baseboard_fab2_lib.baseboard_fab2(sch_1):page132_i44@dev_discrete.cap_~
a(chips)',
 PATH='I44',
 DRAWING='@BASEBOARD_FAB2_LIB.BASEBOARD_FAB2(SCH_1):PAGE132',
 TOLERANCE='10%',
 MATERIAL='X6S',
 BOM_COST='SB',
 PHYS_PAGE='132',
 XY='(-2200,3025)',
 ROT='0',
 VER='1',
 VALUE='1.0UF',
 PACK_TYPE='0402V',
 PART_NUMBER='D97712-004',
 LOCATION='C3N6',
 ROOM='SB_DECOUPLING',
 CDS_LIB='dev_discrete',
 CDS_PART_NAME='CAP_A_0402V-1.0UF,6.3V,10%,X6SA',
 VOLTAGE='6.3V',
 PRIM_FILE='./archive_libs/discrete/cap_a/chips/chips.prt';

PART_NAME
 C3N7 'CAP_A_0402V-1.0UF,6.3V,10%,X6SA':
 ROOM='SB_DECOUPLING';

SECTION_NUMBER 1
 '@BASEBOARD_FAB2_LIB.BASEBOARD_FAB2(SCH_1):PAGE132_I35@DEV_DISCRETE.CAP_A(CHIPS)':
 C_PATH='@baseboard_fab2_lib.baseboard_fab2(sch_1):page132_i35@dev_discrete.cap_~
a(chips)',
 P_PATH='@baseboard_fab2_lib.baseboard_fab2(sch_1):page132_i35@dev_discrete.cap_~
a(chips)',
 PATH='I35',
 DRAWING='@BASEBOARD_FAB2_LIB.BASEBOARD_FAB2(SCH_1):PAGE132',
 TOLERANCE='10%',
 MATERIAL='X6S',
 BOM_COST='SB',
 PHYS_PAGE='132',
 XY='(-1450,3025)',
 ROT='0',
 VER='1',
 VALUE='1.0UF',
 PACK_TYPE='0402V',
 PART_NUMBER='D97712-004',
 LOCATION='C3N7',
 ROOM='SB_DECOUPLING',
 CDS_LIB='dev_discrete',
 CDS_PART_NAME='CAP_A_0402V-1.0UF,6.3V,10%,X6SA',
 VOLTAGE='6.3V',
 PRIM_FILE='./archive_libs/discrete/cap_a/chips/chips.prt';

PART_NAME
 C3N8 'CAP_0402-0.22UF,16V,10%,X7R,A3A':
 ROOM='DMI';

SECTION_NUMBER 1
 '@BASEBOARD_FAB2_LIB.BASEBOARD_FAB2(SCH_1):PAGE129_I75@MSTR_DISCRETE.CAP(CHIPS)':
 C_PATH='@baseboard_fab2_lib.baseboard_fab2(sch_1):page129_i75@mstr_discrete.cap~
(chips)',
 P_PATH='@baseboard_fab2_lib.baseboard_fab2(sch_1):page129_i75@mstr_discrete.cap~
(chips)',
 PATH='I75',
 DRAWING='@BASEBOARD_FAB2_LIB.BASEBOARD_FAB2(SCH_1):PAGE129',
 TOLERANCE='10%',
 MATERIAL='X7R',
 BOM_COST='SB',
 PHYS_PAGE='129',
 XY='(-3650,3975)',
 ROT='1',
 VER='1',
 VALUE='0.22UF',
 PACK_TYPE='0402',
 PART_NUMBER='A36096-155',
 LOCATION='C3N8',
 ROOM='DMI',
 CDS_LIB='mstr_discrete',
 CDS_PART_NAME='CAP_0402-0.22UF,16V,10%,X7R,A3A',
 VOLTAGE='16V',
 PRIM_FILE='./archive_libs/mstr_discrete/cap/chips/chips.prt';

PART_NAME
 C3N9 'CAP_0402-0.22UF,16V,10%,X7R,A3A':
 ROOM='DMI';

SECTION_NUMBER 1
 '@BASEBOARD_FAB2_LIB.BASEBOARD_FAB2(SCH_1):PAGE129_I74@MSTR_DISCRETE.CAP(CHIPS)':
 C_PATH='@baseboard_fab2_lib.baseboard_fab2(sch_1):page129_i74@mstr_discrete.cap~
(chips)',
 P_PATH='@baseboard_fab2_lib.baseboard_fab2(sch_1):page129_i74@mstr_discrete.cap~
(chips)',
 PATH='I74',
 DRAWING='@BASEBOARD_FAB2_LIB.BASEBOARD_FAB2(SCH_1):PAGE129',
 TOLERANCE='10%',
 MATERIAL='X7R',
 BOM_COST='SB',
 PHYS_PAGE='129',
 XY='(-3300,3775)',
 ROT='1',
 VER='1',
 VALUE='0.22UF',
 PACK_TYPE='0402',
 PART_NUMBER='A36096-155',
 LOCATION='C3N9',
 ROOM='DMI',
 CDS_LIB='mstr_discrete',
 CDS_PART_NAME='CAP_0402-0.22UF,16V,10%,X7R,A3A',
 VOLTAGE='16V',
 PRIM_FILE='./archive_libs/mstr_discrete/cap/chips/chips.prt';

PART_NAME
 C3N10 'CAP_A_0603V-22.0UF,4V,20%,X6S,A':
 ROOM='SB_DECOUPLING';

SECTION_NUMBER 1
 '@BASEBOARD_FAB2_LIB.BASEBOARD_FAB2(SCH_1):PAGE132_I13@DEV_DISCRETE.CAP_A(CHIPS)':
 C_PATH='@baseboard_fab2_lib.baseboard_fab2(sch_1):page132_i13@dev_discrete.cap_~
a(chips)',
 P_PATH='@baseboard_fab2_lib.baseboard_fab2(sch_1):page132_i13@dev_discrete.cap_~
a(chips)',
 PATH='I13',
 DRAWING='@BASEBOARD_FAB2_LIB.BASEBOARD_FAB2(SCH_1):PAGE132',
 TOLERANCE='20%',
 MATERIAL='X6S',
 BOM_COST='SB',
 PHYS_PAGE='132',
 XY='(1450,3500)',
 ROT='0',
 VER='1',
 VALUE='22.0UF',
 PACK_TYPE='0603V',
 PART_NUMBER='E15431-004',
 LOCATION='C3N10',
 ROOM='SB_DECOUPLING',
 CDS_LIB='dev_discrete',
 CDS_PART_NAME='CAP_A_0603V-22.0UF,4V,20%,X6S,A',
 VOLTAGE='4V',
 PRIM_FILE='./archive_libs/discrete/cap_a/chips/chips.prt';

PART_NAME
 C3N11 'CAP_A_0603V-22.0UF,4V,20%,X6S,A':
 ROOM='SB_DECOUPLING';

SECTION_NUMBER 1
 '@BASEBOARD_FAB2_LIB.BASEBOARD_FAB2(SCH_1):PAGE132_I19@DEV_DISCRETE.CAP_A(CHIPS)':
 C_PATH='@baseboard_fab2_lib.baseboard_fab2(sch_1):page132_i19@dev_discrete.cap_~
a(chips)',
 P_PATH='@baseboard_fab2_lib.baseboard_fab2(sch_1):page132_i19@dev_discrete.cap_~
a(chips)',
 PATH='I19',
 DRAWING='@BASEBOARD_FAB2_LIB.BASEBOARD_FAB2(SCH_1):PAGE132',
 TOLERANCE='20%',
 MATERIAL='X6S',
 BOM_COST='SB',
 PHYS_PAGE='132',
 XY='(1075,3500)',
 ROT='0',
 VER='1',
 VALUE='22.0UF',
 PACK_TYPE='0603V',
 PART_NUMBER='E15431-004',
 LOCATION='C3N11',
 ROOM='SB_DECOUPLING',
 CDS_LIB='dev_discrete',
 CDS_PART_NAME='CAP_A_0603V-22.0UF,4V,20%,X6S,A',
 VOLTAGE='4V',
 PRIM_FILE='./archive_libs/discrete/cap_a/chips/chips.prt';

PART_NAME
 C3N12 'CAP_A_0603V-22.0UF,4V,20%,X6S,A':
 ROOM='SB_DECOUPLING';

SECTION_NUMBER 1
 '@BASEBOARD_FAB2_LIB.BASEBOARD_FAB2(SCH_1):PAGE132_I12@DEV_DISCRETE.CAP_A(CHIPS)':
 C_PATH='@baseboard_fab2_lib.baseboard_fab2(sch_1):page132_i12@dev_discrete.cap_~
a(chips)',
 P_PATH='@baseboard_fab2_lib.baseboard_fab2(sch_1):page132_i12@dev_discrete.cap_~
a(chips)',
 PATH='I12',
 DRAWING='@BASEBOARD_FAB2_LIB.BASEBOARD_FAB2(SCH_1):PAGE132',
 TOLERANCE='20%',
 MATERIAL='X6S',
 BOM_COST='SB',
 PHYS_PAGE='132',
 XY='(1825,3500)',
 ROT='0',
 VER='1',
 VALUE='22.0UF',
 PACK_TYPE='0603V',
 PART_NUMBER='E15431-004',
 LOCATION='C3N12',
 ROOM='SB_DECOUPLING',
 CDS_LIB='dev_discrete',
 CDS_PART_NAME='CAP_A_0603V-22.0UF,4V,20%,X6S,A',
 VOLTAGE='4V',
 PRIM_FILE='./archive_libs/discrete/cap_a/chips/chips.prt';

PART_NAME
 C3N13 'CAP_0402-0.22UF,16V,10%,X7R,A3A':
 ROOM='DMI';

SECTION_NUMBER 1
 '@BASEBOARD_FAB2_LIB.BASEBOARD_FAB2(SCH_1):PAGE129_I83@MSTR_DISCRETE.CAP(CHIPS)':
 C_PATH='@baseboard_fab2_lib.baseboard_fab2(sch_1):page129_i83@mstr_discrete.cap~
(chips)',
 P_PATH='@baseboard_fab2_lib.baseboard_fab2(sch_1):page129_i83@mstr_discrete.cap~
(chips)',
 PATH='I83',
 DRAWING='@BASEBOARD_FAB2_LIB.BASEBOARD_FAB2(SCH_1):PAGE129',
 TOLERANCE='10%',
 MATERIAL='X7R',
 BOM_COST='SB',
 PHYS_PAGE='129',
 XY='(400,3975)',
 ROT='1',
 VER='1',
 VALUE='0.22UF',
 PACK_TYPE='0402',
 PART_NUMBER='A36096-155',
 LOCATION='C3N13',
 ROOM='DMI',
 CDS_LIB='mstr_discrete',
 CDS_PART_NAME='CAP_0402-0.22UF,16V,10%,X7R,A3A',
 VOLTAGE='16V',
 PRIM_FILE='./archive_libs/mstr_discrete/cap/chips/chips.prt';

PART_NAME
 C3N14 'CAPP_3018-470UF,2.5V,20%,ALUM,A':
 GROUP='PWR_MCP_CAP',
 ROOM='P0V95_MCP_CPU0_DECAP_VR';

SECTION_NUMBER 1
 '@BASEBOARD_FAB2_LIB.BASEBOARD_FAB2(SCH_1):PAGE194_I101@MSTR_DISCRETE.CAPP(CHIPS)':
 C_PATH='@baseboard_fab2_lib.baseboard_fab2(sch_1):page194_i101@mstr_discrete.ca~
pp(chips)',
 P_PATH='@baseboard_fab2_lib.baseboard_fab2(sch_1):page194_i101@mstr_discrete.ca~
pp(chips)',
 PATH='I101',
 DRAWING='@BASEBOARD_FAB2_LIB.BASEBOARD_FAB2(SCH_1):PAGE194',
 TOLERANCE='20%',
 SEC_TYPE='3018',
 MATERIAL='ALUM',
 BOM_COST='PROC_VRD_VCCIN_CPU0',
 PHYS_PAGE='194',
 XY='(-1900,3100)',
 ROT='0',
 VER='1',
 VALUE='470UF',
 PACK_TYPE='3018',
 PART_NUMBER='699013-049',
 LOCATION='C3N14',
 ROOM='P0V95_MCP_CPU0_DECAP_VR',
 GROUP='PWR_MCP_CAP',
 SEC='1',
 CDS_LIB='mstr_discrete',
 CDS_PART_NAME='CAPP_3018-470UF,2.5V,20%,ALUM,A',
 VOLTAGE='2.5V',
 PRIM_FILE='./archive_libs/mstr_discrete/capp/chips/chips.prt';

PART_NAME
 C3N15 'CAP_A_0402V-1.0UF,6.3V,10%,X6SA':
 ROOM='SB_DECOUPLING';

SECTION_NUMBER 1
 '@BASEBOARD_FAB2_LIB.BASEBOARD_FAB2(SCH_1):PAGE132_I49@DEV_DISCRETE.CAP_A(CHIPS)':
 C_PATH='@baseboard_fab2_lib.baseboard_fab2(sch_1):page132_i49@dev_discrete.cap_~
a(chips)',
 P_PATH='@baseboard_fab2_lib.baseboard_fab2(sch_1):page132_i49@dev_discrete.cap_~
a(chips)',
 PATH='I49',
 DRAWING='@BASEBOARD_FAB2_LIB.BASEBOARD_FAB2(SCH_1):PAGE132',
 TOLERANCE='10%',
 MATERIAL='X6S',
 BOM_COST='SB',
 PHYS_PAGE='132',
 XY='(-2975,3025)',
 ROT='0',
 VER='1',
 VALUE='1.0UF',
 PACK_TYPE='0402V',
 PART_NUMBER='D97712-004',
 LOCATION='C3N15',
 ROOM='SB_DECOUPLING',
 CDS_LIB='dev_discrete',
 CDS_PART_NAME='CAP_A_0402V-1.0UF,6.3V,10%,X6SA',
 VOLTAGE='6.3V',
 PRIM_FILE='./archive_libs/discrete/cap_a/chips/chips.prt';

PART_NAME
 C3N16 'CAP_A_0402V-1.0UF,6.3V,10%,X6SA':
 ROOM='SB_DECOUPLING';

SECTION_NUMBER 1
 '@BASEBOARD_FAB2_LIB.BASEBOARD_FAB2(SCH_1):PAGE132_I36@DEV_DISCRETE.CAP_A(CHIPS)':
 C_PATH='@baseboard_fab2_lib.baseboard_fab2(sch_1):page132_i36@dev_discrete.cap_~
a(chips)',
 P_PATH='@baseboard_fab2_lib.baseboard_fab2(sch_1):page132_i36@dev_discrete.cap_~
a(chips)',
 PATH='I36',
 DRAWING='@BASEBOARD_FAB2_LIB.BASEBOARD_FAB2(SCH_1):PAGE132',
 TOLERANCE='10%',
 MATERIAL='X6S',
 BOM_COST='SB',
 PHYS_PAGE='132',
 XY='(-1825,3025)',
 ROT='0',
 VER='1',
 VALUE='1.0UF',
 PACK_TYPE='0402V',
 PART_NUMBER='D97712-004',
 LOCATION='C3N16',
 ROOM='SB_DECOUPLING',
 CDS_LIB='dev_discrete',
 CDS_PART_NAME='CAP_A_0402V-1.0UF,6.3V,10%,X6SA',
 VOLTAGE='6.3V',
 PRIM_FILE='./archive_libs/discrete/cap_a/chips/chips.prt';

PART_NAME
 C3N17 'CAP_A_0402V-1.0UF,6.3V,10%,X6SA':
 ROOM='SB_DECOUPLING';

SECTION_NUMBER 1
 '@BASEBOARD_FAB2_LIB.BASEBOARD_FAB2(SCH_1):PAGE132_I45@DEV_DISCRETE.CAP_A(CHIPS)':
 C_PATH='@baseboard_fab2_lib.baseboard_fab2(sch_1):page132_i45@dev_discrete.cap_~
a(chips)',
 P_PATH='@baseboard_fab2_lib.baseboard_fab2(sch_1):page132_i45@dev_discrete.cap_~
a(chips)',
 PATH='I45',
 DRAWING='@BASEBOARD_FAB2_LIB.BASEBOARD_FAB2(SCH_1):PAGE132',
 TOLERANCE='10%',
 MATERIAL='X6S',
 BOM_COST='SB',
 PHYS_PAGE='132',
 XY='(-2600,3025)',
 ROT='0',
 VER='1',
 VALUE='1.0UF',
 PACK_TYPE='0402V',
 PART_NUMBER='D97712-004',
 LOCATION='C3N17',
 ROOM='SB_DECOUPLING',
 CDS_LIB='dev_discrete',
 CDS_PART_NAME='CAP_A_0402V-1.0UF,6.3V,10%,X6SA',
 VOLTAGE='6.3V',
 PRIM_FILE='./archive_libs/discrete/cap_a/chips/chips.prt';

PART_NAME
 C3N18 'CAP_A_0402V-1.0UF,6.3V,10%,X6SA':
 ROOM='SB_DECOUPLING';

SECTION_NUMBER 1
 '@BASEBOARD_FAB2_LIB.BASEBOARD_FAB2(SCH_1):PAGE132_I42@DEV_DISCRETE.CAP_A(CHIPS)':
 C_PATH='@baseboard_fab2_lib.baseboard_fab2(sch_1):page132_i42@dev_discrete.cap_~
a(chips)',
 P_PATH='@baseboard_fab2_lib.baseboard_fab2(sch_1):page132_i42@dev_discrete.cap_~
a(chips)',
 PATH='I42',
 DRAWING='@BASEBOARD_FAB2_LIB.BASEBOARD_FAB2(SCH_1):PAGE132',
 TOLERANCE='10%',
 MATERIAL='X6S',
 BOM_COST='SB',
 PHYS_PAGE='132',
 XY='(-2225,4050)',
 ROT='0',
 VER='1',
 VALUE='1.0UF',
 PACK_TYPE='0402V',
 PART_NUMBER='D97712-004',
 LOCATION='C3N18',
 ROOM='SB_DECOUPLING',
 CDS_LIB='dev_discrete',
 CDS_PART_NAME='CAP_A_0402V-1.0UF,6.3V,10%,X6SA',
 VOLTAGE='6.3V',
 PRIM_FILE='./archive_libs/discrete/cap_a/chips/chips.prt';

PART_NAME
 C3N19 'CAP_A_0402V-1.0UF,6.3V,10%,X6SA':
 ROOM='SB_DECOUPLING';

SECTION_NUMBER 1
 '@BASEBOARD_FAB2_LIB.BASEBOARD_FAB2(SCH_1):PAGE132_I31@DEV_DISCRETE.CAP_A(CHIPS)':
 C_PATH='@baseboard_fab2_lib.baseboard_fab2(sch_1):page132_i31@dev_discrete.cap_~
a(chips)',
 P_PATH='@baseboard_fab2_lib.baseboard_fab2(sch_1):page132_i31@dev_discrete.cap_~
a(chips)',
 PATH='I31',
 DRAWING='@BASEBOARD_FAB2_LIB.BASEBOARD_FAB2(SCH_1):PAGE132',
 TOLERANCE='10%',
 MATERIAL='X6S',
 BOM_COST='SB',
 PHYS_PAGE='132',
 XY='(-1475,4050)',
 ROT='0',
 VER='1',
 VALUE='1.0UF',
 PACK_TYPE='0402V',
 PART_NUMBER='D97712-004',
 LOCATION='C3N19',
 ROOM='SB_DECOUPLING',
 CDS_LIB='dev_discrete',
 CDS_PART_NAME='CAP_A_0402V-1.0UF,6.3V,10%,X6SA',
 VOLTAGE='6.3V',
 PRIM_FILE='./archive_libs/discrete/cap_a/chips/chips.prt';

PART_NAME
 C3N20 'CAP_A_0402V-1.0UF,6.3V,10%,X6SA':
 ROOM='SB_DECOUPLING';

SECTION_NUMBER 1
 '@BASEBOARD_FAB2_LIB.BASEBOARD_FAB2(SCH_1):PAGE132_I51@DEV_DISCRETE.CAP_A(CHIPS)':
 C_PATH='@baseboard_fab2_lib.baseboard_fab2(sch_1):page132_i51@dev_discrete.cap_~
a(chips)',
 P_PATH='@baseboard_fab2_lib.baseboard_fab2(sch_1):page132_i51@dev_discrete.cap_~
a(chips)',
 PATH='I51',
 DRAWING='@BASEBOARD_FAB2_LIB.BASEBOARD_FAB2(SCH_1):PAGE132',
 TOLERANCE='10%',
 MATERIAL='X6S',
 BOM_COST='SB',
 PHYS_PAGE='132',
 XY='(-3375,3025)',
 ROT='0',
 VER='1',
 VALUE='1.0UF',
 PACK_TYPE='0402V',
 PART_NUMBER='D97712-004',
 LOCATION='C3N20',
 ROOM='SB_DECOUPLING',
 CDS_LIB='dev_discrete',
 CDS_PART_NAME='CAP_A_0402V-1.0UF,6.3V,10%,X6SA',
 VOLTAGE='6.3V',
 PRIM_FILE='./archive_libs/discrete/cap_a/chips/chips.prt';

PART_NAME
 C3N21 'CAP_A_0402V-1.0UF,6.3V,10%,X6SA':
 ROOM='SB_DECOUPLING';

SECTION_NUMBER 1
 '@BASEBOARD_FAB2_LIB.BASEBOARD_FAB2(SCH_1):PAGE130_I49@DEV_DISCRETE.CAP_A(CHIPS)':
 C_PATH='@baseboard_fab2_lib.baseboard_fab2(sch_1):page130_i49@dev_discrete.cap_~
a(chips)',
 P_PATH='@baseboard_fab2_lib.baseboard_fab2(sch_1):page130_i49@dev_discrete.cap_~
a(chips)',
 PATH='I49',
 DRAWING='@BASEBOARD_FAB2_LIB.BASEBOARD_FAB2(SCH_1):PAGE130',
 TOLERANCE='10%',
 MATERIAL='X6S',
 BOM_COST='SB',
 PHYS_PAGE='130',
 XY='(-3975,1475)',
 ROT='0',
 VER='1',
 VALUE='1.0UF',
 PACK_TYPE='0402V',
 PART_NUMBER='D97712-004',
 LOCATION='C3N21',
 ROOM='SB_DECOUPLING',
 CDS_LIB='dev_discrete',
 CDS_PART_NAME='CAP_A_0402V-1.0UF,6.3V,10%,X6SA',
 VOLTAGE='6.3V',
 PRIM_FILE='./archive_libs/discrete/cap_a/chips/chips.prt';

PART_NAME
 C3N22 'CAP_A_0402V-1.0UF,6.3V,10%,X6SA':
 ROOM='SB_DECOUPLING';

SECTION_NUMBER 1
 '@BASEBOARD_FAB2_LIB.BASEBOARD_FAB2(SCH_1):PAGE130_I53@DEV_DISCRETE.CAP_A(CHIPS)':
 C_PATH='@baseboard_fab2_lib.baseboard_fab2(sch_1):page130_i53@dev_discrete.cap_~
a(chips)',
 P_PATH='@baseboard_fab2_lib.baseboard_fab2(sch_1):page130_i53@dev_discrete.cap_~
a(chips)',
 PATH='I53',
 DRAWING='@BASEBOARD_FAB2_LIB.BASEBOARD_FAB2(SCH_1):PAGE130',
 TOLERANCE='10%',
 MATERIAL='X6S',
 BOM_COST='SB',
 PHYS_PAGE='130',
 XY='(-5200,1475)',
 ROT='0',
 VER='1',
 VALUE='1.0UF',
 PACK_TYPE='0402V',
 PART_NUMBER='D97712-004',
 LOCATION='C3N22',
 ROOM='SB_DECOUPLING',
 CDS_LIB='dev_discrete',
 CDS_PART_NAME='CAP_A_0402V-1.0UF,6.3V,10%,X6SA',
 VOLTAGE='6.3V',
 PRIM_FILE='./archive_libs/discrete/cap_a/chips/chips.prt';

PART_NAME
 C3N23 'CAP_A_0402V-1.0UF,6.3V,10%,X6SA':
 ROOM='SB_DECOUPLING';

SECTION_NUMBER 1
 '@BASEBOARD_FAB2_LIB.BASEBOARD_FAB2(SCH_1):PAGE130_I42@DEV_DISCRETE.CAP_A(CHIPS)':
 C_PATH='@baseboard_fab2_lib.baseboard_fab2(sch_1):page130_i42@dev_discrete.cap_~
a(chips)',
 P_PATH='@baseboard_fab2_lib.baseboard_fab2(sch_1):page130_i42@dev_discrete.cap_~
a(chips)',
 PATH='I42',
 DRAWING='@BASEBOARD_FAB2_LIB.BASEBOARD_FAB2(SCH_1):PAGE130',
 TOLERANCE='10%',
 MATERIAL='X6S',
 BOM_COST='SB',
 PHYS_PAGE='130',
 XY='(-4600,3925)',
 ROT='0',
 VER='1',
 VALUE='1.0UF',
 PACK_TYPE='0402V',
 PART_NUMBER='D97712-004',
 LOCATION='C3N23',
 ROOM='SB_DECOUPLING',
 CDS_LIB='dev_discrete',
 CDS_PART_NAME='CAP_A_0402V-1.0UF,6.3V,10%,X6SA',
 VOLTAGE='6.3V',
 PRIM_FILE='./archive_libs/discrete/cap_a/chips/chips.prt';

PART_NAME
 C3N24 'CAP_A_0603V-22.0UF,4V,20%,X6S,A':
 ROOM='SB_DECOUPLING';

SECTION_NUMBER 1
 '@BASEBOARD_FAB2_LIB.BASEBOARD_FAB2(SCH_1):PAGE132_I16@DEV_DISCRETE.CAP_A(CHIPS)':
 C_PATH='@baseboard_fab2_lib.baseboard_fab2(sch_1):page132_i16@dev_discrete.cap_~
a(chips)',
 P_PATH='@baseboard_fab2_lib.baseboard_fab2(sch_1):page132_i16@dev_discrete.cap_~
a(chips)',
 PATH='I16',
 DRAWING='@BASEBOARD_FAB2_LIB.BASEBOARD_FAB2(SCH_1):PAGE132',
 TOLERANCE='20%',
 MATERIAL='X6S',
 BOM_COST='SB',
 PHYS_PAGE='132',
 XY='(1850,2525)',
 ROT='0',
 VER='1',
 VALUE='22.0UF',
 PACK_TYPE='0603V',
 PART_NUMBER='E15431-004',
 LOCATION='C3N24',
 ROOM='SB_DECOUPLING',
 CDS_LIB='dev_discrete',
 CDS_PART_NAME='CAP_A_0603V-22.0UF,4V,20%,X6S,A',
 VOLTAGE='4V',
 PRIM_FILE='./archive_libs/discrete/cap_a/chips/chips.prt';

PART_NAME
 C3N25 'CAP_A_0402V-1.0UF,6.3V,10%,X6SA':
 ROOM='SB_DECOUPLING';

SECTION_NUMBER 1
 '@BASEBOARD_FAB2_LIB.BASEBOARD_FAB2(SCH_1):PAGE130_I50@DEV_DISCRETE.CAP_A(CHIPS)':
 C_PATH='@baseboard_fab2_lib.baseboard_fab2(sch_1):page130_i50@dev_discrete.cap_~
a(chips)',
 P_PATH='@baseboard_fab2_lib.baseboard_fab2(sch_1):page130_i50@dev_discrete.cap_~
a(chips)',
 PATH='I50',
 DRAWING='@BASEBOARD_FAB2_LIB.BASEBOARD_FAB2(SCH_1):PAGE130',
 TOLERANCE='10%',
 MATERIAL='X6S',
 BOM_COST='SB',
 PHYS_PAGE='130',
 XY='(-4350,1475)',
 ROT='0',
 VER='1',
 VALUE='1.0UF',
 PACK_TYPE='0402V',
 PART_NUMBER='D97712-004',
 LOCATION='C3N25',
 ROOM='SB_DECOUPLING',
 CDS_LIB='dev_discrete',
 CDS_PART_NAME='CAP_A_0402V-1.0UF,6.3V,10%,X6SA',
 VOLTAGE='6.3V',
 PRIM_FILE='./archive_libs/discrete/cap_a/chips/chips.prt';

PART_NAME
 C3N26 'CAPP_3018-470UF,2.5V,20%,ALUM,A':
 GROUP='PWR_BULK_CAP',
 ROOM='PVCCIO_CPU0';

SECTION_NUMBER 1
 '@BASEBOARD_FAB2_LIB.BASEBOARD_FAB2(SCH_1):PAGE212_I145@MSTR_DISCRETE.CAPP(CHIPS)':
 C_PATH='@baseboard_fab2_lib.baseboard_fab2(sch_1):page212_i145@mstr_discrete.ca~
pp(chips)',
 P_PATH='@baseboard_fab2_lib.baseboard_fab2(sch_1):page212_i145@mstr_discrete.ca~
pp(chips)',
 PATH='I145',
 DRAWING='@BASEBOARD_FAB2_LIB.BASEBOARD_FAB2(SCH_1):PAGE212',
 TOLERANCE='20%',
 MATERIAL='ALUM',
 BOM_COST='PROC_VRD_PVCCIO_CPU0',
 PHYS_PAGE='212',
 XY='(1400,1300)',
 ROT='2',
 VER='1',
 VALUE='470UF',
 PACK_TYPE='3018',
 PART_NUMBER='699013-049',
 LOCATION='C3N26',
 ROOM='PVCCIO_CPU0',
 GROUP='PWR_BULK_CAP',
 CDS_LIB='mstr_discrete',
 CDS_PART_NAME='CAPP_3018-470UF,2.5V,20%,ALUM,A',
 VOLTAGE='2.5V',
 PRIM_FILE='./archive_libs/mstr_discrete/capp/chips/chips.prt';

PART_NAME
 C3N27 'CAP_A_0603V-22.0UF,4V,20%,X6S,A':
 ROOM='SB_DECOUPLING';

SECTION_NUMBER 1
 '@BASEBOARD_FAB2_LIB.BASEBOARD_FAB2(SCH_1):PAGE132_I8@DEV_DISCRETE.CAP_A(CHIPS)':
 C_PATH='@baseboard_fab2_lib.baseboard_fab2(sch_1):page132_i8@dev_discrete.cap_a~
(chips)',
 P_PATH='@baseboard_fab2_lib.baseboard_fab2(sch_1):page132_i8@dev_discrete.cap_a~
(chips)',
 PATH='I8',
 DRAWING='@BASEBOARD_FAB2_LIB.BASEBOARD_FAB2(SCH_1):PAGE132',
 TOLERANCE='20%',
 MATERIAL='X6S',
 BOM_COST='SB',
 PHYS_PAGE='132',
 XY='(2600,2525)',
 ROT='0',
 VER='1',
 VALUE='22.0UF',
 PACK_TYPE='0603V',
 PART_NUMBER='E15431-004',
 LOCATION='C3N27',
 ROOM='SB_DECOUPLING',
 CDS_LIB='dev_discrete',
 CDS_PART_NAME='CAP_A_0603V-22.0UF,4V,20%,X6S,A',
 VOLTAGE='4V',
 PRIM_FILE='./archive_libs/discrete/cap_a/chips/chips.prt';

PART_NAME
 C3N28 'CAP_A_0603V-22.0UF,4V,20%,X6S,A':
 ROOM='SB_DECOUPLING';

SECTION_NUMBER 1
 '@BASEBOARD_FAB2_LIB.BASEBOARD_FAB2(SCH_1):PAGE132_I17@DEV_DISCRETE.CAP_A(CHIPS)':
 C_PATH='@baseboard_fab2_lib.baseboard_fab2(sch_1):page132_i17@dev_discrete.cap_~
a(chips)',
 P_PATH='@baseboard_fab2_lib.baseboard_fab2(sch_1):page132_i17@dev_discrete.cap_~
a(chips)',
 PATH='I17',
 DRAWING='@BASEBOARD_FAB2_LIB.BASEBOARD_FAB2(SCH_1):PAGE132',
 TOLERANCE='20%',
 MATERIAL='X6S',
 BOM_COST='SB',
 PHYS_PAGE='132',
 XY='(1475,2525)',
 ROT='0',
 VER='1',
 VALUE='22.0UF',
 PACK_TYPE='0603V',
 PART_NUMBER='E15431-004',
 LOCATION='C3N28',
 ROOM='SB_DECOUPLING',
 CDS_LIB='dev_discrete',
 CDS_PART_NAME='CAP_A_0603V-22.0UF,4V,20%,X6S,A',
 VOLTAGE='4V',
 PRIM_FILE='./archive_libs/discrete/cap_a/chips/chips.prt';

PART_NAME
 C3N29 'CAP_A_0402V-0.1UF,16V,10%,X7R,A':
 ROOM='SB_DECOUPLING';

SECTION_NUMBER 1
 '@BASEBOARD_FAB2_LIB.BASEBOARD_FAB2(SCH_1):PAGE130_I16@DEV_DISCRETE.CAP_A(CHIPS)':
 C_PATH='@baseboard_fab2_lib.baseboard_fab2(sch_1):page130_i16@dev_discrete.cap_~
a(chips)',
 P_PATH='@baseboard_fab2_lib.baseboard_fab2(sch_1):page130_i16@dev_discrete.cap_~
a(chips)',
 PATH='I16',
 DRAWING='@BASEBOARD_FAB2_LIB.BASEBOARD_FAB2(SCH_1):PAGE130',
 TOLERANCE='10%',
 MATERIAL='X7R',
 BOM_COST='SB',
 PHYS_PAGE='130',
 XY='(0,2025)',
 ROT='2',
 VER='1',
 VALUE='0.1UF',
 PACK_TYPE='0402V',
 PART_NUMBER='A36096-030',
 LOCATION='C3N29',
 ROOM='SB_DECOUPLING',
 CDS_LIB='dev_discrete',
 CDS_PART_NAME='CAP_A_0402V-0.1UF,16V,10%,X7R,A',
 VOLTAGE='16V',
 PRIM_FILE='./archive_libs/discrete/cap_a/chips/chips.prt';

PART_NAME
 C3N30 'CAP_A_0603V-22.0UF,4V,20%,X6S,A':
 ROOM='SB_DECOUPLING';

SECTION_NUMBER 1
 '@BASEBOARD_FAB2_LIB.BASEBOARD_FAB2(SCH_1):PAGE132_I9@DEV_DISCRETE.CAP_A(CHIPS)':
 C_PATH='@baseboard_fab2_lib.baseboard_fab2(sch_1):page132_i9@dev_discrete.cap_a~
(chips)',
 P_PATH='@baseboard_fab2_lib.baseboard_fab2(sch_1):page132_i9@dev_discrete.cap_a~
(chips)',
 PATH='I9',
 DRAWING='@BASEBOARD_FAB2_LIB.BASEBOARD_FAB2(SCH_1):PAGE132',
 TOLERANCE='20%',
 MATERIAL='X6S',
 BOM_COST='SB',
 PHYS_PAGE='132',
 XY='(2225,2525)',
 ROT='0',
 VER='1',
 VALUE='22.0UF',
 PACK_TYPE='0603V',
 PART_NUMBER='E15431-004',
 LOCATION='C3N30',
 ROOM='SB_DECOUPLING',
 CDS_LIB='dev_discrete',
 CDS_PART_NAME='CAP_A_0603V-22.0UF,4V,20%,X6S,A',
 VOLTAGE='4V',
 PRIM_FILE='./archive_libs/discrete/cap_a/chips/chips.prt';

PART_NAME
 C3N31 'CAP_A_0603V-22.0UF,4V,20%,X6S,A':
 ROOM='SB_DECOUPLING';

SECTION_NUMBER 1
 '@BASEBOARD_FAB2_LIB.BASEBOARD_FAB2(SCH_1):PAGE132_I20@DEV_DISCRETE.CAP_A(CHIPS)':
 C_PATH='@baseboard_fab2_lib.baseboard_fab2(sch_1):page132_i20@dev_discrete.cap_~
a(chips)',
 P_PATH='@baseboard_fab2_lib.baseboard_fab2(sch_1):page132_i20@dev_discrete.cap_~
a(chips)',
 PATH='I20',
 DRAWING='@BASEBOARD_FAB2_LIB.BASEBOARD_FAB2(SCH_1):PAGE132',
 TOLERANCE='20%',
 MATERIAL='X6S',
 BOM_COST='SB',
 PHYS_PAGE='132',
 XY='(1100,2525)',
 ROT='0',
 VER='1',
 VALUE='22.0UF',
 PACK_TYPE='0603V',
 PART_NUMBER='E15431-004',
 LOCATION='C3N31',
 ROOM='SB_DECOUPLING',
 CDS_LIB='dev_discrete',
 CDS_PART_NAME='CAP_A_0603V-22.0UF,4V,20%,X6S,A',
 VOLTAGE='4V',
 PRIM_FILE='./archive_libs/discrete/cap_a/chips/chips.prt';

PART_NAME
 C3N32 'CAP_A_0402V-1.0UF,6.3V,10%,X6SA':
 ROOM='SB';

SECTION_NUMBER 1
 '@BASEBOARD_FAB2_LIB.BASEBOARD_FAB2(SCH_1):PAGE137_I20@DEV_DISCRETE.CAP_A(CHIPS)':
 C_PATH='@baseboard_fab2_lib.baseboard_fab2(sch_1):page137_i20@dev_discrete.cap_~
a(chips)',
 P_PATH='@baseboard_fab2_lib.baseboard_fab2(sch_1):page137_i20@dev_discrete.cap_~
a(chips)',
 PATH='I20',
 DRAWING='@BASEBOARD_FAB2_LIB.BASEBOARD_FAB2(SCH_1):PAGE137',
 TOLERANCE='10%',
 SEC_TYPE='0402V',
 MATERIAL='X6S',
 BOM_COST='SB',
 PHYS_PAGE='137',
 XY='(-300,1450)',
 ROT='0',
 VER='1',
 VALUE='1.0UF',
 PACK_TYPE='0402V',
 PART_NUMBER='D97712-004',
 LOCATION='C3N32',
 ROOM='SB',
 SEC='1',
 CDS_LIB='dev_discrete',
 CDS_PART_NAME='CAP_A_0402V-1.0UF,6.3V,10%,X6SA',
 VOLTAGE='6.3V',
 PRIM_FILE='./archive_libs/discrete/cap_a/chips/chips.prt';

PART_NAME
 C3N33 'CAP_0805-10UF,16V,10%,X6S,C953A':
 ROOM='PVCCIO_CPU0';

SECTION_NUMBER 1
 '@BASEBOARD_FAB2_LIB.BASEBOARD_FAB2(SCH_1):PAGE212_I41@MSTR_DISCRETE.CAP(CHIPS)':
 C_PATH='@baseboard_fab2_lib.baseboard_fab2(sch_1):page212_i41@mstr_discrete.cap~
(chips)',
 P_PATH='@baseboard_fab2_lib.baseboard_fab2(sch_1):page212_i41@mstr_discrete.cap~
(chips)',
 PATH='I41',
 DRAWING='@BASEBOARD_FAB2_LIB.BASEBOARD_FAB2(SCH_1):PAGE212',
 TOLERANCE='10%',
 SEC_TYPE='0805',
 MATERIAL='X6S',
 PHYS_PAGE='212',
 XY='(-2475,4225)',
 ROT='0',
 VER='1',
 VALUE='10UF',
 PACK_TYPE='0805',
 PART_NUMBER='C95333-007',
 LOCATION='C3N33',
 ROOM='PVCCIO_CPU0',
 SEC='1',
 CDS_LIB='mstr_discrete',
 CDS_PART_NAME='CAP_0805-10UF,16V,10%,X6S,C953A',
 VOLTAGE='16V',
 PRIM_FILE='./archive_libs/mstr_discrete/cap/chips/chips.prt';

PART_NAME
 C3N34 'CAP_0805-10UF,16V,10%,X6S,C953A':
 ROOM='PVCCIO_CPU0';

SECTION_NUMBER 1
 '@BASEBOARD_FAB2_LIB.BASEBOARD_FAB2(SCH_1):PAGE212_I43@MSTR_DISCRETE.CAP(CHIPS)':
 C_PATH='@baseboard_fab2_lib.baseboard_fab2(sch_1):page212_i43@mstr_discrete.cap~
(chips)',
 P_PATH='@baseboard_fab2_lib.baseboard_fab2(sch_1):page212_i43@mstr_discrete.cap~
(chips)',
 PATH='I43',
 DRAWING='@BASEBOARD_FAB2_LIB.BASEBOARD_FAB2(SCH_1):PAGE212',
 TOLERANCE='10%',
 SEC_TYPE='0805',
 MATERIAL='X6S',
 PHYS_PAGE='212',
 XY='(-2725,4225)',
 ROT='0',
 VER='1',
 VALUE='10UF',
 PACK_TYPE='0805',
 PART_NUMBER='C95333-007',
 LOCATION='C3N34',
 ROOM='PVCCIO_CPU0',
 SEC='1',
 CDS_LIB='mstr_discrete',
 CDS_PART_NAME='CAP_0805-10UF,16V,10%,X6S,C953A',
 VOLTAGE='16V',
 PRIM_FILE='./archive_libs/mstr_discrete/cap/chips/chips.prt';

PART_NAME
 C3N35 'CAPP_3018-470UF,2.5V,20%,ALUM,A':
 GROUP='PWR_BULK_CAP',
 ROOM='PVCCIO_CPU0';

SECTION_NUMBER 1
 '@BASEBOARD_FAB2_LIB.BASEBOARD_FAB2(SCH_1):PAGE212_I18@MSTR_DISCRETE.CAPP(CHIPS)':
 C_PATH='@baseboard_fab2_lib.baseboard_fab2(sch_1):page212_i18@mstr_discrete.cap~
p(chips)',
 P_PATH='@baseboard_fab2_lib.baseboard_fab2(sch_1):page212_i18@mstr_discrete.cap~
p(chips)',
 PATH='I18',
 DRAWING='@BASEBOARD_FAB2_LIB.BASEBOARD_FAB2(SCH_1):PAGE212',
 TOLERANCE='20%',
 MATERIAL='ALUM',
 BOM_COST='PROC_VRD_PVCCIO_CPU0',
 PHYS_PAGE='212',
 XY='(850,1300)',
 ROT='2',
 VER='1',
 VALUE='470UF',
 PACK_TYPE='3018',
 PART_NUMBER='699013-049',
 LOCATION='C3N35',
 ROOM='PVCCIO_CPU0',
 GROUP='PWR_BULK_CAP',
 CDS_LIB='mstr_discrete',
 CDS_PART_NAME='CAPP_3018-470UF,2.5V,20%,ALUM,A',
 VOLTAGE='2.5V',
 PRIM_FILE='./archive_libs/mstr_discrete/capp/chips/chips.prt';

PART_NAME
 C3N36 'CAP_0805-10UF,16V,10%,X6S,C953A':
 ROOM='PVCCIO_CPU0';

SECTION_NUMBER 1
 '@BASEBOARD_FAB2_LIB.BASEBOARD_FAB2(SCH_1):PAGE212_I40@MSTR_DISCRETE.CAP(CHIPS)':
 C_PATH='@baseboard_fab2_lib.baseboard_fab2(sch_1):page212_i40@mstr_discrete.cap~
(chips)',
 P_PATH='@baseboard_fab2_lib.baseboard_fab2(sch_1):page212_i40@mstr_discrete.cap~
(chips)',
 PATH='I40',
 DRAWING='@BASEBOARD_FAB2_LIB.BASEBOARD_FAB2(SCH_1):PAGE212',
 TOLERANCE='10%',
 SEC_TYPE='0805',
 MATERIAL='X6S',
 PHYS_PAGE='212',
 XY='(-2250,4225)',
 ROT='0',
 VER='1',
 VALUE='10UF',
 PACK_TYPE='0805',
 PART_NUMBER='C95333-007',
 LOCATION='C3N36',
 ROOM='PVCCIO_CPU0',
 SEC='1',
 CDS_LIB='mstr_discrete',
 CDS_PART_NAME='CAP_0805-10UF,16V,10%,X6S,C953A',
 VOLTAGE='16V',
 PRIM_FILE='./archive_libs/mstr_discrete/cap/chips/chips.prt';

PART_NAME
 C3N38 'CAPP_3018-470UF,2.5V,20%,ALUM,A':
 GROUP='PWR_BULK_CAP',
 ROOM='PVCCIO_CPU0';

SECTION_NUMBER 1
 '@BASEBOARD_FAB2_LIB.BASEBOARD_FAB2(SCH_1):PAGE212_I146@MSTR_DISCRETE.CAPP(CHIPS)':
 C_PATH='@baseboard_fab2_lib.baseboard_fab2(sch_1):page212_i146@mstr_discrete.ca~
pp(chips)',
 P_PATH='@baseboard_fab2_lib.baseboard_fab2(sch_1):page212_i146@mstr_discrete.ca~
pp(chips)',
 PATH='I146',
 DRAWING='@BASEBOARD_FAB2_LIB.BASEBOARD_FAB2(SCH_1):PAGE212',
 TOLERANCE='20%',
 MATERIAL='ALUM',
 BOM_COST='PROC_VRD_PVCCIO_CPU0',
 PHYS_PAGE='212',
 XY='(1950,1300)',
 ROT='2',
 VER='1',
 VALUE='470UF',
 PACK_TYPE='3018',
 PART_NUMBER='699013-049',
 LOCATION='C3N38',
 ROOM='PVCCIO_CPU0',
 GROUP='PWR_BULK_CAP',
 CDS_LIB='mstr_discrete',
 CDS_PART_NAME='CAPP_3018-470UF,2.5V,20%,ALUM,A',
 VOLTAGE='2.5V',
 PRIM_FILE='./archive_libs/mstr_discrete/capp/chips/chips.prt';

PART_NAME
 C3N39 'CAP_0402LF-220PF,50V,10%,X7R,AA':
 ROOM='PVCCIO_CPU0';

SECTION_NUMBER 1
 '@BASEBOARD_FAB2_LIB.BASEBOARD_FAB2(SCH_1):PAGE211_I83@MSTR_DISCRETE.CAP(CHIPS)':
 C_PATH='@baseboard_fab2_lib.baseboard_fab2(sch_1):page211_i83@mstr_discrete.cap~
(chips)',
 P_PATH='@baseboard_fab2_lib.baseboard_fab2(sch_1):page211_i83@mstr_discrete.cap~
(chips)',
 PATH='I83',
 DRAWING='@BASEBOARD_FAB2_LIB.BASEBOARD_FAB2(SCH_1):PAGE211',
 TOLERANCE='10%',
 SEC_TYPE='0402LF',
 MATERIAL='X7R',
 PHYS_PAGE='211',
 XY='(-2400,1850)',
 ROT='0',
 VER='1',
 VALUE='220PF',
 PACK_TYPE='0402LF',
 PART_NUMBER='A36096-050',
 LOCATION='C3N39',
 ROOM='PVCCIO_CPU0',
 SEC='1',
 CDS_LIB='mstr_discrete',
 CDS_PART_NAME='CAP_0402LF-220PF,50V,10%,X7R,AA',
 VOLTAGE='50V',
 PRIM_FILE='./archive_libs/mstr_discrete/cap/chips/chips.prt';

PART_NAME
 C3N40 'CAP_A_0402V-1.0UF,6.3V,10%,X6SA':
 GROUP='PWR_MCP_CAP',
 ROOM='P0V95_MCP_CPU0';

SECTION_NUMBER 1
 '@BASEBOARD_FAB2_LIB.BASEBOARD_FAB2(SCH_1):PAGE194_I86@DEV_DISCRETE.CAP_A(CHIPS)':
 C_PATH='@baseboard_fab2_lib.baseboard_fab2(sch_1):page194_i86@dev_discrete.cap_~
a(chips)',
 P_PATH='@baseboard_fab2_lib.baseboard_fab2(sch_1):page194_i86@dev_discrete.cap_~
a(chips)',
 PATH='I86',
 DRAWING='@BASEBOARD_FAB2_LIB.BASEBOARD_FAB2(SCH_1):PAGE194',
 TOLERANCE='10%',
 SEC_TYPE='0402V',
 MATERIAL='X6S',
 PHYS_PAGE='194',
 XY='(-1100,3100)',
 ROT='0',
 VER='1',
 VALUE='1.0UF',
 PACK_TYPE='0402V',
 PART_NUMBER='D97712-004',
 LOCATION='C3N40',
 ROOM='P0V95_MCP_CPU0',
 GROUP='PWR_MCP_CAP',
 SEC='1',
 CDS_LIB='dev_discrete',
 CDS_PART_NAME='CAP_A_0402V-1.0UF,6.3V,10%,X6SA',
 VOLTAGE='6.3V',
 PRIM_FILE='./archive_libs/discrete/cap_a/chips/chips.prt';

PART_NAME
 C3P1 'CAP_A_0402V-0.1UF,16V,10%,EMPTA':
 ROOM='PVCCIO_CPU0';

SECTION_NUMBER 1
 '@BASEBOARD_FAB2_LIB.BASEBOARD_FAB2(SCH_1):PAGE212_I60@DEV_DISCRETE.CAP_A(CHIPS)':
 C_PATH='@baseboard_fab2_lib.baseboard_fab2(sch_1):page212_i60@dev_discrete.cap_~
a(chips)',
 P_PATH='@baseboard_fab2_lib.baseboard_fab2(sch_1):page212_i60@dev_discrete.cap_~
a(chips)',
 PATH='I60',
 DRAWING='@BASEBOARD_FAB2_LIB.BASEBOARD_FAB2(SCH_1):PAGE212',
 TOLERANCE='10%',
 SEC_TYPE='0402V',
 MATERIAL='EMPTY',
 BOM_COST='PROC_VRD_PVCCIO_CPU0',
 PHYS_PAGE='212',
 XY='(-1925,1675)',
 ROT='0',
 VER='1',
 VALUE='0.1UF',
 PACK_TYPE='0402V',
 PART_NUMBER='A36096-030',
 LOCATION='C3P1',
 ROOM='PVCCIO_CPU0',
 SEC='1',
 CDS_LIB='dev_discrete',
 CDS_PART_NAME='CAP_A_0402V-0.1UF,16V,10%,EMPTA',
 VOLTAGE='16V',
 PRIM_FILE='./archive_libs/discrete/cap_a/chips/chips.prt';

PART_NAME
 C3P2 'CAP_A_0402V-0.1UF,16V,10%,X7R,A':
 ROOM='CPU_FANS';

SECTION_NUMBER 1
 '@BASEBOARD_FAB2_LIB.BASEBOARD_FAB2(SCH_1):PAGE211_I103@DEV_DISCRETE.CAP_A(CHIPS)':
 C_PATH='@baseboard_fab2_lib.baseboard_fab2(sch_1):page211_i103@dev_discrete.cap~
_a(chips)',
 P_PATH='@baseboard_fab2_lib.baseboard_fab2(sch_1):page211_i103@dev_discrete.cap~
_a(chips)',
 PATH='I103',
 DRAWING='@BASEBOARD_FAB2_LIB.BASEBOARD_FAB2(SCH_1):PAGE211',
 TOLERANCE='10%',
 SEC_TYPE='0402V',
 MATERIAL='X7R',
 BOM_COST='SM_THERM',
 PHYS_PAGE='211',
 XY='(-2850,4300)',
 ROT='0',
 VER='1',
 VALUE='0.1UF',
 PACK_TYPE='0402V',
 PART_NUMBER='A36096-030',
 LOCATION='C3P2',
 ROOM='CPU_FANS',
 SEC='1',
 CDS_LIB='dev_discrete',
 CDS_PART_NAME='CAP_A_0402V-0.1UF,16V,10%,X7R,A',
 VOLTAGE='16V',
 PRIM_FILE='./archive_libs/discrete/cap_a/chips/chips.prt';

PART_NAME
 C3P3 'CAP_A_0402V-1.0UF,6.3V,10%,X6SA':
 ROOM='PVCCIO_CPU0';

SECTION_NUMBER 1
 '@BASEBOARD_FAB2_LIB.BASEBOARD_FAB2(SCH_1):PAGE211_I20@DEV_DISCRETE.CAP_A(CHIPS)':
 C_PATH='@baseboard_fab2_lib.baseboard_fab2(sch_1):page211_i20@dev_discrete.cap_~
a(chips)',
 P_PATH='@baseboard_fab2_lib.baseboard_fab2(sch_1):page211_i20@dev_discrete.cap_~
a(chips)',
 PATH='I20',
 DRAWING='@BASEBOARD_FAB2_LIB.BASEBOARD_FAB2(SCH_1):PAGE211',
 TOLERANCE='10%',
 SEC_TYPE='0402V',
 MATERIAL='X6S',
 PHYS_PAGE='211',
 XY='(75,4175)',
 ROT='0',
 VER='1',
 VALUE='1.0UF',
 PACK_TYPE='0402V',
 PART_NUMBER='D97712-004',
 LOCATION='C3P3',
 ROOM='PVCCIO_CPU0',
 SEC='1',
 CDS_LIB='dev_discrete',
 CDS_PART_NAME='CAP_A_0402V-1.0UF,6.3V,10%,X6SA',
 VOLTAGE='6.3V',
 PRIM_FILE='./archive_libs/discrete/cap_a/chips/chips.prt';

PART_NAME
 C3P4 'CAP_A_0402V-1.0UF,6.3V,10%,X6SA':
 ROOM='PVCCIO_CPU0';

SECTION_NUMBER 1
 '@BASEBOARD_FAB2_LIB.BASEBOARD_FAB2(SCH_1):PAGE211_I11@DEV_DISCRETE.CAP_A(CHIPS)':
 C_PATH='@baseboard_fab2_lib.baseboard_fab2(sch_1):page211_i11@dev_discrete.cap_~
a(chips)',
 P_PATH='@baseboard_fab2_lib.baseboard_fab2(sch_1):page211_i11@dev_discrete.cap_~
a(chips)',
 PATH='I11',
 DRAWING='@BASEBOARD_FAB2_LIB.BASEBOARD_FAB2(SCH_1):PAGE211',
 TOLERANCE='10%',
 SEC_TYPE='0402V',
 MATERIAL='X6S',
 PHYS_PAGE='211',
 XY='(2475,1425)',
 ROT='0',
 VER='1',
 VALUE='1.0UF',
 PACK_TYPE='0402V',
 PART_NUMBER='D97712-004',
 LOCATION='C3P4',
 ROOM='PVCCIO_CPU0',
 SEC='1',
 CDS_LIB='dev_discrete',
 CDS_PART_NAME='CAP_A_0402V-1.0UF,6.3V,10%,X6SA',
 VOLTAGE='6.3V',
 PRIM_FILE='./archive_libs/discrete/cap_a/chips/chips.prt';

PART_NAME
 C3P5 'CAP_A_0402V-0.1UF,16V,10%,X7R,A':
 ROOM='PVCCIO_CPU0';

SECTION_NUMBER 1
 '@BASEBOARD_FAB2_LIB.BASEBOARD_FAB2(SCH_1):PAGE211_I13@DEV_DISCRETE.CAP_A(CHIPS)':
 C_PATH='@baseboard_fab2_lib.baseboard_fab2(sch_1):page211_i13@dev_discrete.cap_~
a(chips)',
 P_PATH='@baseboard_fab2_lib.baseboard_fab2(sch_1):page211_i13@dev_discrete.cap_~
a(chips)',
 PATH='I13',
 DRAWING='@BASEBOARD_FAB2_LIB.BASEBOARD_FAB2(SCH_1):PAGE211',
 TOLERANCE='10%',
 SEC_TYPE='0402V',
 MATERIAL='X7R',
 PHYS_PAGE='211',
 XY='(2075,1425)',
 ROT='0',
 VER='1',
 VALUE='0.1UF',
 PACK_TYPE='0402V',
 PART_NUMBER='A36096-030',
 LOCATION='C3P5',
 ROOM='PVCCIO_CPU0',
 SEC='1',
 CDS_LIB='dev_discrete',
 CDS_PART_NAME='CAP_A_0402V-0.1UF,16V,10%,X7R,A',
 VOLTAGE='16V',
 PRIM_FILE='./archive_libs/discrete/cap_a/chips/chips.prt';

PART_NAME
 C3P6 'CAP_0402LF-1000PF,50V,10%,X7R,A':
 ROOM='PVCCIO_CPU0_VR';

SECTION_NUMBER 1
 '@BASEBOARD_FAB2_LIB.BASEBOARD_FAB2(SCH_1):PAGE211_I71@MSTR_DISCRETE.CAP(CHIPS)':
 C_PATH='@baseboard_fab2_lib.baseboard_fab2(sch_1):page211_i71@mstr_discrete.cap~
(chips)',
 P_PATH='@baseboard_fab2_lib.baseboard_fab2(sch_1):page211_i71@mstr_discrete.cap~
(chips)',
 PATH='I71',
 DRAWING='@BASEBOARD_FAB2_LIB.BASEBOARD_FAB2(SCH_1):PAGE211',
 TOLERANCE='10%',
 SEC_TYPE='0402LF',
 MATERIAL='X7R',
 PHYS_PAGE='211',
 XY='(1650,2750)',
 ROT='0',
 VER='1',
 VALUE='1000PF',
 PACK_TYPE='0402LF',
 PART_NUMBER='A36096-046',
 LOCATION='C3P6',
 ROOM='PVCCIO_CPU0_VR',
 SEC='1',
 CDS_LIB='mstr_discrete',
 CDS_PART_NAME='CAP_0402LF-1000PF,50V,10%,X7R,A',
 VOLTAGE='50V',
 PRIM_FILE='./archive_libs/mstr_discrete/cap/chips/chips.prt';

PART_NAME
 C3P7 'CAP_A_0402V-0.1UF,16V,10%,X7R,A':
 ROOM='PVCCIO_CPU0';

SECTION_NUMBER 1
 '@BASEBOARD_FAB2_LIB.BASEBOARD_FAB2(SCH_1):PAGE211_I22@DEV_DISCRETE.CAP_A(CHIPS)':
 C_PATH='@baseboard_fab2_lib.baseboard_fab2(sch_1):page211_i22@dev_discrete.cap_~
a(chips)',
 P_PATH='@baseboard_fab2_lib.baseboard_fab2(sch_1):page211_i22@dev_discrete.cap_~
a(chips)',
 PATH='I22',
 DRAWING='@BASEBOARD_FAB2_LIB.BASEBOARD_FAB2(SCH_1):PAGE211',
 TOLERANCE='10%',
 SEC_TYPE='0402V',
 MATERIAL='X7R',
 PHYS_PAGE='211',
 XY='(-325,4175)',
 ROT='0',
 VER='1',
 VALUE='0.1UF',
 PACK_TYPE='0402V',
 PART_NUMBER='A36096-030',
 LOCATION='C3P7',
 ROOM='PVCCIO_CPU0',
 SEC='1',
 CDS_LIB='dev_discrete',
 CDS_PART_NAME='CAP_A_0402V-0.1UF,16V,10%,X7R,A',
 VOLTAGE='16V',
 PRIM_FILE='./archive_libs/discrete/cap_a/chips/chips.prt';

PART_NAME
 C3P10 'CAP_0402-0.22UF,16V,10%,X7R,A3A':
 GROUP='PCIE_RISER';

SECTION_NUMBER 1
 '@BASEBOARD_FAB2_LIB.BASEBOARD_FAB2(SCH_1):PAGE107_I482@MSTR_DISCRETE.CAP(CHIPS)':
 C_PATH='@baseboard_fab2_lib.baseboard_fab2(sch_1):page107_i482@mstr_discrete.ca~
p(chips)',
 P_PATH='@baseboard_fab2_lib.baseboard_fab2(sch_1):page107_i482@mstr_discrete.ca~
p(chips)',
 PATH='I482',
 DRAWING='@BASEBOARD_FAB2_LIB.BASEBOARD_FAB2(SCH_1):PAGE107',
 TOLERANCE='10%',
 MATERIAL='X7R',
 PHYS_PAGE='107',
 XY='(-4250,2975)',
 ROT='0',
 VER='1',
 VALUE='0.22UF',
 PACK_TYPE='0402',
 PART_NUMBER='A36096-155',
 LOCATION='C3P10',
 GROUP='PCIE_RISER',
 CDS_LIB='mstr_discrete',
 CDS_PART_NAME='CAP_0402-0.22UF,16V,10%,X7R,A3A',
 VOLTAGE='16V',
 PRIM_FILE='./archive_libs/mstr_discrete/cap/chips/chips.prt';

PART_NAME
 C3P11 'CAP_0402-0.22UF,16V,10%,X7R,A3A':
 GROUP='PCIE_UPLINK';

SECTION_NUMBER 1
 '@BASEBOARD_FAB2_LIB.BASEBOARD_FAB2(SCH_1):PAGE107_I212@MSTR_DISCRETE.CAP(CHIPS)':
 C_PATH='@baseboard_fab2_lib.baseboard_fab2(sch_1):page107_i212@mstr_discrete.ca~
p(chips)',
 P_PATH='@baseboard_fab2_lib.baseboard_fab2(sch_1):page107_i212@mstr_discrete.ca~
p(chips)',
 PATH='I212',
 DRAWING='@BASEBOARD_FAB2_LIB.BASEBOARD_FAB2(SCH_1):PAGE107',
 TOLERANCE='10%',
 MATERIAL='X7R',
 PHYS_PAGE='107',
 XY='(-5475,875)',
 ROT='2',
 VER='1',
 VALUE='0.22UF',
 PACK_TYPE='0402',
 PART_NUMBER='A36096-155',
 LOCATION='C3P11',
 GROUP='PCIE_UPLINK',
 CDS_LIB='mstr_discrete',
 CDS_PART_NAME='CAP_0402-0.22UF,16V,10%,X7R,A3A',
 VOLTAGE='16V',
 PRIM_FILE='./archive_libs/mstr_discrete/cap/chips/chips.prt';

PART_NAME
 C3P12 'CAP_0402-0.22UF,16V,10%,X7R,A3A':
 GROUP='PCIE_RISER';

SECTION_NUMBER 1
 '@BASEBOARD_FAB2_LIB.BASEBOARD_FAB2(SCH_1):PAGE107_I481@MSTR_DISCRETE.CAP(CHIPS)':
 C_PATH='@baseboard_fab2_lib.baseboard_fab2(sch_1):page107_i481@mstr_discrete.ca~
p(chips)',
 P_PATH='@baseboard_fab2_lib.baseboard_fab2(sch_1):page107_i481@mstr_discrete.ca~
p(chips)',
 PATH='I481',
 DRAWING='@BASEBOARD_FAB2_LIB.BASEBOARD_FAB2(SCH_1):PAGE107',
 TOLERANCE='10%',
 MATERIAL='X7R',
 PHYS_PAGE='107',
 XY='(-4300,3975)',
 ROT='0',
 VER='1',
 VALUE='0.22UF',
 PACK_TYPE='0402',
 PART_NUMBER='A36096-155',
 LOCATION='C3P12',
 GROUP='PCIE_RISER',
 CDS_LIB='mstr_discrete',
 CDS_PART_NAME='CAP_0402-0.22UF,16V,10%,X7R,A3A',
 VOLTAGE='16V',
 PRIM_FILE='./archive_libs/mstr_discrete/cap/chips/chips.prt';

PART_NAME
 C3P13 'CAP_0402-0.22UF,16V,10%,X7R,A3A':
 GROUP='PCIE_UPLINK';

SECTION_NUMBER 1
 '@BASEBOARD_FAB2_LIB.BASEBOARD_FAB2(SCH_1):PAGE107_I207@MSTR_DISCRETE.CAP(CHIPS)':
 C_PATH='@baseboard_fab2_lib.baseboard_fab2(sch_1):page107_i207@mstr_discrete.ca~
p(chips)',
 P_PATH='@baseboard_fab2_lib.baseboard_fab2(sch_1):page107_i207@mstr_discrete.ca~
p(chips)',
 PATH='I207',
 DRAWING='@BASEBOARD_FAB2_LIB.BASEBOARD_FAB2(SCH_1):PAGE107',
 TOLERANCE='10%',
 MATERIAL='X7R',
 PHYS_PAGE='107',
 XY='(-5525,1875)',
 ROT='2',
 VER='1',
 VALUE='0.22UF',
 PACK_TYPE='0402',
 PART_NUMBER='A36096-155',
 LOCATION='C3P13',
 GROUP='PCIE_UPLINK',
 CDS_LIB='mstr_discrete',
 CDS_PART_NAME='CAP_0402-0.22UF,16V,10%,X7R,A3A',
 VOLTAGE='16V',
 PRIM_FILE='./archive_libs/mstr_discrete/cap/chips/chips.prt';

PART_NAME
 C3P14 'CAP_0402-0.22UF,16V,10%,X7R,A3A':
 GROUP='PCIE_RISER';

SECTION_NUMBER 1
 '@BASEBOARD_FAB2_LIB.BASEBOARD_FAB2(SCH_1):PAGE107_I483@MSTR_DISCRETE.CAP(CHIPS)':
 C_PATH='@baseboard_fab2_lib.baseboard_fab2(sch_1):page107_i483@mstr_discrete.ca~
p(chips)',
 P_PATH='@baseboard_fab2_lib.baseboard_fab2(sch_1):page107_i483@mstr_discrete.ca~
p(chips)',
 PATH='I483',
 DRAWING='@BASEBOARD_FAB2_LIB.BASEBOARD_FAB2(SCH_1):PAGE107',
 TOLERANCE='10%',
 MATERIAL='X7R',
 PHYS_PAGE='107',
 XY='(-4450,2675)',
 ROT='0',
 VER='1',
 VALUE='0.22UF',
 PACK_TYPE='0402',
 PART_NUMBER='A36096-155',
 LOCATION='C3P14',
 GROUP='PCIE_RISER',
 CDS_LIB='mstr_discrete',
 CDS_PART_NAME='CAP_0402-0.22UF,16V,10%,X7R,A3A',
 VOLTAGE='16V',
 PRIM_FILE='./archive_libs/mstr_discrete/cap/chips/chips.prt';

PART_NAME
 C3P15 'CAP_0402-0.22UF,16V,10%,X7R,A3A':
 GROUP='PCIE_UPLINK';

SECTION_NUMBER 1
 '@BASEBOARD_FAB2_LIB.BASEBOARD_FAB2(SCH_1):PAGE107_I226@MSTR_DISCRETE.CAP(CHIPS)':
 C_PATH='@baseboard_fab2_lib.baseboard_fab2(sch_1):page107_i226@mstr_discrete.ca~
p(chips)',
 P_PATH='@baseboard_fab2_lib.baseboard_fab2(sch_1):page107_i226@mstr_discrete.ca~
p(chips)',
 PATH='I226',
 DRAWING='@BASEBOARD_FAB2_LIB.BASEBOARD_FAB2(SCH_1):PAGE107',
 TOLERANCE='10%',
 MATERIAL='X7R',
 PHYS_PAGE='107',
 XY='(-5675,575)',
 ROT='2',
 VER='1',
 VALUE='0.22UF',
 PACK_TYPE='0402',
 PART_NUMBER='A36096-155',
 LOCATION='C3P15',
 GROUP='PCIE_UPLINK',
 CDS_LIB='mstr_discrete',
 CDS_PART_NAME='CAP_0402-0.22UF,16V,10%,X7R,A3A',
 VOLTAGE='16V',
 PRIM_FILE='./archive_libs/mstr_discrete/cap/chips/chips.prt';

PART_NAME
 C3P16 'CAP_0402-0.22UF,16V,10%,X7R,A3A':
 GROUP='PCIE_RISER';

SECTION_NUMBER 1
 '@BASEBOARD_FAB2_LIB.BASEBOARD_FAB2(SCH_1):PAGE107_I476@MSTR_DISCRETE.CAP(CHIPS)':
 C_PATH='@baseboard_fab2_lib.baseboard_fab2(sch_1):page107_i476@mstr_discrete.ca~
p(chips)',
 P_PATH='@baseboard_fab2_lib.baseboard_fab2(sch_1):page107_i476@mstr_discrete.ca~
p(chips)',
 PATH='I476',
 DRAWING='@BASEBOARD_FAB2_LIB.BASEBOARD_FAB2(SCH_1):PAGE107',
 TOLERANCE='10%',
 MATERIAL='X7R',
 PHYS_PAGE='107',
 XY='(-4500,3700)',
 ROT='0',
 VER='1',
 VALUE='0.22UF',
 PACK_TYPE='0402',
 PART_NUMBER='A36096-155',
 LOCATION='C3P16',
 GROUP='PCIE_RISER',
 CDS_LIB='mstr_discrete',
 CDS_PART_NAME='CAP_0402-0.22UF,16V,10%,X7R,A3A',
 VOLTAGE='16V',
 PRIM_FILE='./archive_libs/mstr_discrete/cap/chips/chips.prt';

PART_NAME
 C3P17 'CAP_0402-0.22UF,16V,10%,X7R,A3A':
 GROUP='PCIE_UPLINK';

SECTION_NUMBER 1
 '@BASEBOARD_FAB2_LIB.BASEBOARD_FAB2(SCH_1):PAGE107_I208@MSTR_DISCRETE.CAP(CHIPS)':
 C_PATH='@baseboard_fab2_lib.baseboard_fab2(sch_1):page107_i208@mstr_discrete.ca~
p(chips)',
 P_PATH='@baseboard_fab2_lib.baseboard_fab2(sch_1):page107_i208@mstr_discrete.ca~
p(chips)',
 PATH='I208',
 DRAWING='@BASEBOARD_FAB2_LIB.BASEBOARD_FAB2(SCH_1):PAGE107',
 TOLERANCE='10%',
 MATERIAL='X7R',
 PHYS_PAGE='107',
 XY='(-5725,1575)',
 ROT='2',
 VER='1',
 VALUE='0.22UF',
 PACK_TYPE='0402',
 PART_NUMBER='A36096-155',
 LOCATION='C3P17',
 GROUP='PCIE_UPLINK',
 CDS_LIB='mstr_discrete',
 CDS_PART_NAME='CAP_0402-0.22UF,16V,10%,X7R,A3A',
 VOLTAGE='16V',
 PRIM_FILE='./archive_libs/mstr_discrete/cap/chips/chips.prt';

PART_NAME
 C3P18 'CAP_0402-0.22UF,16V,10%,X7R,A3A':
 GROUP='PCIE_UPLINK';

SECTION_NUMBER 1
 '@BASEBOARD_FAB2_LIB.BASEBOARD_FAB2(SCH_1):PAGE107_I219@MSTR_DISCRETE.CAP(CHIPS)':
 C_PATH='@baseboard_fab2_lib.baseboard_fab2(sch_1):page107_i219@mstr_discrete.ca~
p(chips)',
 P_PATH='@baseboard_fab2_lib.baseboard_fab2(sch_1):page107_i219@mstr_discrete.ca~
p(chips)',
 PATH='I219',
 DRAWING='@BASEBOARD_FAB2_LIB.BASEBOARD_FAB2(SCH_1):PAGE107',
 TOLERANCE='10%',
 MATERIAL='X7R',
 PHYS_PAGE='107',
 XY='(-5875,875)',
 ROT='2',
 VER='1',
 VALUE='0.22UF',
 PACK_TYPE='0402',
 PART_NUMBER='A36096-155',
 LOCATION='C3P18',
 GROUP='PCIE_UPLINK',
 CDS_LIB='mstr_discrete',
 CDS_PART_NAME='CAP_0402-0.22UF,16V,10%,X7R,A3A',
 VOLTAGE='16V',
 PRIM_FILE='./archive_libs/mstr_discrete/cap/chips/chips.prt';

PART_NAME
 C3P19 'CAP_0402-0.22UF,16V,10%,X7R,A3A':
 GROUP='PCIE_RISER';

SECTION_NUMBER 1
 '@BASEBOARD_FAB2_LIB.BASEBOARD_FAB2(SCH_1):PAGE107_I485@MSTR_DISCRETE.CAP(CHIPS)':
 C_PATH='@baseboard_fab2_lib.baseboard_fab2(sch_1):page107_i485@mstr_discrete.ca~
p(chips)',
 P_PATH='@baseboard_fab2_lib.baseboard_fab2(sch_1):page107_i485@mstr_discrete.ca~
p(chips)',
 PATH='I485',
 DRAWING='@BASEBOARD_FAB2_LIB.BASEBOARD_FAB2(SCH_1):PAGE107',
 TOLERANCE='10%',
 MATERIAL='X7R',
 PHYS_PAGE='107',
 XY='(-4650,2975)',
 ROT='0',
 VER='1',
 VALUE='0.22UF',
 PACK_TYPE='0402',
 PART_NUMBER='A36096-155',
 LOCATION='C3P19',
 GROUP='PCIE_RISER',
 CDS_LIB='mstr_discrete',
 CDS_PART_NAME='CAP_0402-0.22UF,16V,10%,X7R,A3A',
 VOLTAGE='16V',
 PRIM_FILE='./archive_libs/mstr_discrete/cap/chips/chips.prt';

PART_NAME
 C3P20 'CAP_0402-0.22UF,16V,10%,X7R,A3A':
 GROUP='PCIE_UPLINK';

SECTION_NUMBER 1
 '@BASEBOARD_FAB2_LIB.BASEBOARD_FAB2(SCH_1):PAGE107_I215@MSTR_DISCRETE.CAP(CHIPS)':
 C_PATH='@baseboard_fab2_lib.baseboard_fab2(sch_1):page107_i215@mstr_discrete.ca~
p(chips)',
 P_PATH='@baseboard_fab2_lib.baseboard_fab2(sch_1):page107_i215@mstr_discrete.ca~
p(chips)',
 PATH='I215',
 DRAWING='@BASEBOARD_FAB2_LIB.BASEBOARD_FAB2(SCH_1):PAGE107',
 TOLERANCE='10%',
 MATERIAL='X7R',
 PHYS_PAGE='107',
 XY='(-5925,1900)',
 ROT='2',
 VER='1',
 VALUE='0.22UF',
 PACK_TYPE='0402',
 PART_NUMBER='A36096-155',
 LOCATION='C3P20',
 GROUP='PCIE_UPLINK',
 CDS_LIB='mstr_discrete',
 CDS_PART_NAME='CAP_0402-0.22UF,16V,10%,X7R,A3A',
 VOLTAGE='16V',
 PRIM_FILE='./archive_libs/mstr_discrete/cap/chips/chips.prt';

PART_NAME
 C3P21 'CAP_0402-0.22UF,16V,10%,X7R,A3A':
 GROUP='PCIE_RISER';

SECTION_NUMBER 1
 '@BASEBOARD_FAB2_LIB.BASEBOARD_FAB2(SCH_1):PAGE107_I480@MSTR_DISCRETE.CAP(CHIPS)':
 C_PATH='@baseboard_fab2_lib.baseboard_fab2(sch_1):page107_i480@mstr_discrete.ca~
p(chips)',
 P_PATH='@baseboard_fab2_lib.baseboard_fab2(sch_1):page107_i480@mstr_discrete.ca~
p(chips)',
 PATH='I480',
 DRAWING='@BASEBOARD_FAB2_LIB.BASEBOARD_FAB2(SCH_1):PAGE107',
 TOLERANCE='10%',
 MATERIAL='X7R',
 PHYS_PAGE='107',
 XY='(-4700,3975)',
 ROT='0',
 VER='1',
 VALUE='0.22UF',
 PACK_TYPE='0402',
 PART_NUMBER='A36096-155',
 LOCATION='C3P21',
 GROUP='PCIE_RISER',
 CDS_LIB='mstr_discrete',
 CDS_PART_NAME='CAP_0402-0.22UF,16V,10%,X7R,A3A',
 VOLTAGE='16V',
 PRIM_FILE='./archive_libs/mstr_discrete/cap/chips/chips.prt';

PART_NAME
 C3P22 'CAP_0402-0.22UF,16V,10%,X7R,A3A':
 GROUP='PCIE_RISER';

SECTION_NUMBER 1
 '@BASEBOARD_FAB2_LIB.BASEBOARD_FAB2(SCH_1):PAGE107_I484@MSTR_DISCRETE.CAP(CHIPS)':
 C_PATH='@baseboard_fab2_lib.baseboard_fab2(sch_1):page107_i484@mstr_discrete.ca~
p(chips)',
 P_PATH='@baseboard_fab2_lib.baseboard_fab2(sch_1):page107_i484@mstr_discrete.ca~
p(chips)',
 PATH='I484',
 DRAWING='@BASEBOARD_FAB2_LIB.BASEBOARD_FAB2(SCH_1):PAGE107',
 TOLERANCE='10%',
 MATERIAL='X7R',
 PHYS_PAGE='107',
 XY='(-4850,2675)',
 ROT='0',
 VER='1',
 VALUE='0.22UF',
 PACK_TYPE='0402',
 PART_NUMBER='A36096-155',
 LOCATION='C3P22',
 GROUP='PCIE_RISER',
 CDS_LIB='mstr_discrete',
 CDS_PART_NAME='CAP_0402-0.22UF,16V,10%,X7R,A3A',
 VOLTAGE='16V',
 PRIM_FILE='./archive_libs/mstr_discrete/cap/chips/chips.prt';

PART_NAME
 C3P23 'CAP_0402-0.22UF,16V,10%,X7R,A3A':
 GROUP='PCIE_UPLINK';

SECTION_NUMBER 1
 '@BASEBOARD_FAB2_LIB.BASEBOARD_FAB2(SCH_1):PAGE107_I229@MSTR_DISCRETE.CAP(CHIPS)':
 C_PATH='@baseboard_fab2_lib.baseboard_fab2(sch_1):page107_i229@mstr_discrete.ca~
p(chips)',
 P_PATH='@baseboard_fab2_lib.baseboard_fab2(sch_1):page107_i229@mstr_discrete.ca~
p(chips)',
 PATH='I229',
 DRAWING='@BASEBOARD_FAB2_LIB.BASEBOARD_FAB2(SCH_1):PAGE107',
 TOLERANCE='10%',
 MATERIAL='X7R',
 PHYS_PAGE='107',
 XY='(-6075,575)',
 ROT='2',
 VER='1',
 VALUE='0.22UF',
 PACK_TYPE='0402',
 PART_NUMBER='A36096-155',
 LOCATION='C3P23',
 GROUP='PCIE_UPLINK',
 CDS_LIB='mstr_discrete',
 CDS_PART_NAME='CAP_0402-0.22UF,16V,10%,X7R,A3A',
 VOLTAGE='16V',
 PRIM_FILE='./archive_libs/mstr_discrete/cap/chips/chips.prt';

PART_NAME
 C3P24 'CAP_0402-0.22UF,16V,10%,X7R,A3A':
 GROUP='PCIE_RISER';

SECTION_NUMBER 1
 '@BASEBOARD_FAB2_LIB.BASEBOARD_FAB2(SCH_1):PAGE107_I479@MSTR_DISCRETE.CAP(CHIPS)':
 C_PATH='@baseboard_fab2_lib.baseboard_fab2(sch_1):page107_i479@mstr_discrete.ca~
p(chips)',
 P_PATH='@baseboard_fab2_lib.baseboard_fab2(sch_1):page107_i479@mstr_discrete.ca~
p(chips)',
 PATH='I479',
 DRAWING='@BASEBOARD_FAB2_LIB.BASEBOARD_FAB2(SCH_1):PAGE107',
 TOLERANCE='10%',
 MATERIAL='X7R',
 PHYS_PAGE='107',
 XY='(-4900,3675)',
 ROT='0',
 VER='1',
 VALUE='0.22UF',
 PACK_TYPE='0402',
 PART_NUMBER='A36096-155',
 LOCATION='C3P24',
 GROUP='PCIE_RISER',
 CDS_LIB='mstr_discrete',
 CDS_PART_NAME='CAP_0402-0.22UF,16V,10%,X7R,A3A',
 VOLTAGE='16V',
 PRIM_FILE='./archive_libs/mstr_discrete/cap/chips/chips.prt';

PART_NAME
 C3P25 'CAP_0402-0.22UF,16V,10%,X7R,A3A':
 GROUP='PCIE_UPLINK';

SECTION_NUMBER 1
 '@BASEBOARD_FAB2_LIB.BASEBOARD_FAB2(SCH_1):PAGE107_I216@MSTR_DISCRETE.CAP(CHIPS)':
 C_PATH='@baseboard_fab2_lib.baseboard_fab2(sch_1):page107_i216@mstr_discrete.ca~
p(chips)',
 P_PATH='@baseboard_fab2_lib.baseboard_fab2(sch_1):page107_i216@mstr_discrete.ca~
p(chips)',
 PATH='I216',
 DRAWING='@BASEBOARD_FAB2_LIB.BASEBOARD_FAB2(SCH_1):PAGE107',
 TOLERANCE='10%',
 MATERIAL='X7R',
 PHYS_PAGE='107',
 XY='(-6125,1575)',
 ROT='2',
 VER='1',
 VALUE='0.22UF',
 PACK_TYPE='0402',
 PART_NUMBER='A36096-155',
 LOCATION='C3P25',
 GROUP='PCIE_UPLINK',
 CDS_LIB='mstr_discrete',
 CDS_PART_NAME='CAP_0402-0.22UF,16V,10%,X7R,A3A',
 VOLTAGE='16V',
 PRIM_FILE='./archive_libs/mstr_discrete/cap/chips/chips.prt';

PART_NAME
 C3P26 'CAP_0402-0.22UF,16V,10%,X7R,A3A':
 GROUP='PCIE_RISER';

SECTION_NUMBER 1
 '@BASEBOARD_FAB2_LIB.BASEBOARD_FAB2(SCH_1):PAGE107_I487@MSTR_DISCRETE.CAP(CHIPS)':
 C_PATH='@baseboard_fab2_lib.baseboard_fab2(sch_1):page107_i487@mstr_discrete.ca~
p(chips)',
 P_PATH='@baseboard_fab2_lib.baseboard_fab2(sch_1):page107_i487@mstr_discrete.ca~
p(chips)',
 PATH='I487',
 DRAWING='@BASEBOARD_FAB2_LIB.BASEBOARD_FAB2(SCH_1):PAGE107',
 TOLERANCE='10%',
 MATERIAL='X7R',
 PHYS_PAGE='107',
 XY='(-5050,2975)',
 ROT='0',
 VER='1',
 VALUE='0.22UF',
 PACK_TYPE='0402',
 PART_NUMBER='A36096-155',
 LOCATION='C3P26',
 GROUP='PCIE_RISER',
 CDS_LIB='mstr_discrete',
 CDS_PART_NAME='CAP_0402-0.22UF,16V,10%,X7R,A3A',
 VOLTAGE='16V',
 PRIM_FILE='./archive_libs/mstr_discrete/cap/chips/chips.prt';

PART_NAME
 C3P27 'CAP_0402-0.22UF,16V,10%,X7R,A3A':
 GROUP='PCIE_UPLINK';

SECTION_NUMBER 1
 '@BASEBOARD_FAB2_LIB.BASEBOARD_FAB2(SCH_1):PAGE107_I223@MSTR_DISCRETE.CAP(CHIPS)':
 C_PATH='@baseboard_fab2_lib.baseboard_fab2(sch_1):page107_i223@mstr_discrete.ca~
p(chips)',
 P_PATH='@baseboard_fab2_lib.baseboard_fab2(sch_1):page107_i223@mstr_discrete.ca~
p(chips)',
 PATH='I223',
 DRAWING='@BASEBOARD_FAB2_LIB.BASEBOARD_FAB2(SCH_1):PAGE107',
 TOLERANCE='10%',
 MATERIAL='X7R',
 PHYS_PAGE='107',
 XY='(-6275,875)',
 ROT='2',
 VER='1',
 VALUE='0.22UF',
 PACK_TYPE='0402',
 PART_NUMBER='A36096-155',
 LOCATION='C3P27',
 GROUP='PCIE_UPLINK',
 CDS_LIB='mstr_discrete',
 CDS_PART_NAME='CAP_0402-0.22UF,16V,10%,X7R,A3A',
 VOLTAGE='16V',
 PRIM_FILE='./archive_libs/mstr_discrete/cap/chips/chips.prt';

PART_NAME
 C3P28 'CAP_0402-0.22UF,16V,10%,X7R,A3A':
 GROUP='PCIE_UPLINK';

SECTION_NUMBER 1
 '@BASEBOARD_FAB2_LIB.BASEBOARD_FAB2(SCH_1):PAGE107_I232@MSTR_DISCRETE.CAP(CHIPS)':
 C_PATH='@baseboard_fab2_lib.baseboard_fab2(sch_1):page107_i232@mstr_discrete.ca~
p(chips)',
 P_PATH='@baseboard_fab2_lib.baseboard_fab2(sch_1):page107_i232@mstr_discrete.ca~
p(chips)',
 PATH='I232',
 DRAWING='@BASEBOARD_FAB2_LIB.BASEBOARD_FAB2(SCH_1):PAGE107',
 TOLERANCE='10%',
 MATERIAL='X7R',
 PHYS_PAGE='107',
 XY='(-6325,1875)',
 ROT='2',
 VER='1',
 VALUE='0.22UF',
 PACK_TYPE='0402',
 PART_NUMBER='A36096-155',
 LOCATION='C3P28',
 GROUP='PCIE_UPLINK',
 CDS_LIB='mstr_discrete',
 CDS_PART_NAME='CAP_0402-0.22UF,16V,10%,X7R,A3A',
 VOLTAGE='16V',
 PRIM_FILE='./archive_libs/mstr_discrete/cap/chips/chips.prt';

PART_NAME
 C3P29 'CAP_0402-0.22UF,16V,10%,X7R,A3A':
 GROUP='PCIE_RISER';

SECTION_NUMBER 1
 '@BASEBOARD_FAB2_LIB.BASEBOARD_FAB2(SCH_1):PAGE107_I478@MSTR_DISCRETE.CAP(CHIPS)':
 C_PATH='@baseboard_fab2_lib.baseboard_fab2(sch_1):page107_i478@mstr_discrete.ca~
p(chips)',
 P_PATH='@baseboard_fab2_lib.baseboard_fab2(sch_1):page107_i478@mstr_discrete.ca~
p(chips)',
 PATH='I478',
 DRAWING='@BASEBOARD_FAB2_LIB.BASEBOARD_FAB2(SCH_1):PAGE107',
 TOLERANCE='10%',
 MATERIAL='X7R',
 PHYS_PAGE='107',
 XY='(-5100,3975)',
 ROT='0',
 VER='1',
 VALUE='0.22UF',
 PACK_TYPE='0402',
 PART_NUMBER='A36096-155',
 LOCATION='C3P29',
 GROUP='PCIE_RISER',
 CDS_LIB='mstr_discrete',
 CDS_PART_NAME='CAP_0402-0.22UF,16V,10%,X7R,A3A',
 VOLTAGE='16V',
 PRIM_FILE='./archive_libs/mstr_discrete/cap/chips/chips.prt';

PART_NAME
 C3P30 'CAP_0402-0.22UF,16V,10%,X7R,A3A':
 GROUP='PCIE_UPLINK';

SECTION_NUMBER 1
 '@BASEBOARD_FAB2_LIB.BASEBOARD_FAB2(SCH_1):PAGE107_I245@MSTR_DISCRETE.CAP(CHIPS)':
 C_PATH='@baseboard_fab2_lib.baseboard_fab2(sch_1):page107_i245@mstr_discrete.ca~
p(chips)',
 P_PATH='@baseboard_fab2_lib.baseboard_fab2(sch_1):page107_i245@mstr_discrete.ca~
p(chips)',
 PATH='I245',
 DRAWING='@BASEBOARD_FAB2_LIB.BASEBOARD_FAB2(SCH_1):PAGE107',
 TOLERANCE='10%',
 MATERIAL='X7R',
 PHYS_PAGE='107',
 XY='(-6475,575)',
 ROT='2',
 VER='1',
 VALUE='0.22UF',
 PACK_TYPE='0402',
 PART_NUMBER='A36096-155',
 LOCATION='C3P30',
 GROUP='PCIE_UPLINK',
 CDS_LIB='mstr_discrete',
 CDS_PART_NAME='CAP_0402-0.22UF,16V,10%,X7R,A3A',
 VOLTAGE='16V',
 PRIM_FILE='./archive_libs/mstr_discrete/cap/chips/chips.prt';

PART_NAME
 C3P31 'CAP_0402-0.22UF,16V,10%,X7R,A3A':
 GROUP='PCIE_RISER';

SECTION_NUMBER 1
 '@BASEBOARD_FAB2_LIB.BASEBOARD_FAB2(SCH_1):PAGE107_I488@MSTR_DISCRETE.CAP(CHIPS)':
 C_PATH='@baseboard_fab2_lib.baseboard_fab2(sch_1):page107_i488@mstr_discrete.ca~
p(chips)',
 P_PATH='@baseboard_fab2_lib.baseboard_fab2(sch_1):page107_i488@mstr_discrete.ca~
p(chips)',
 PATH='I488',
 DRAWING='@BASEBOARD_FAB2_LIB.BASEBOARD_FAB2(SCH_1):PAGE107',
 TOLERANCE='10%',
 MATERIAL='X7R',
 PHYS_PAGE='107',
 XY='(-5250,2675)',
 ROT='0',
 VER='1',
 VALUE='0.22UF',
 PACK_TYPE='0402',
 PART_NUMBER='A36096-155',
 LOCATION='C3P31',
 GROUP='PCIE_RISER',
 CDS_LIB='mstr_discrete',
 CDS_PART_NAME='CAP_0402-0.22UF,16V,10%,X7R,A3A',
 VOLTAGE='16V',
 PRIM_FILE='./archive_libs/mstr_discrete/cap/chips/chips.prt';

PART_NAME
 C3P32 'CAP_0402-0.22UF,16V,10%,X7R,A3A':
 GROUP='PCIE_UPLINK';

SECTION_NUMBER 1
 '@BASEBOARD_FAB2_LIB.BASEBOARD_FAB2(SCH_1):PAGE107_I234@MSTR_DISCRETE.CAP(CHIPS)':
 C_PATH='@baseboard_fab2_lib.baseboard_fab2(sch_1):page107_i234@mstr_discrete.ca~
p(chips)',
 P_PATH='@baseboard_fab2_lib.baseboard_fab2(sch_1):page107_i234@mstr_discrete.ca~
p(chips)',
 PATH='I234',
 DRAWING='@BASEBOARD_FAB2_LIB.BASEBOARD_FAB2(SCH_1):PAGE107',
 TOLERANCE='10%',
 MATERIAL='X7R',
 PHYS_PAGE='107',
 XY='(-6525,1575)',
 ROT='2',
 VER='1',
 VALUE='0.22UF',
 PACK_TYPE='0402',
 PART_NUMBER='A36096-155',
 LOCATION='C3P32',
 GROUP='PCIE_UPLINK',
 CDS_LIB='mstr_discrete',
 CDS_PART_NAME='CAP_0402-0.22UF,16V,10%,X7R,A3A',
 VOLTAGE='16V',
 PRIM_FILE='./archive_libs/mstr_discrete/cap/chips/chips.prt';

PART_NAME
 C3P33 'CAP_0402-0.22UF,16V,10%,X7R,A3A':
 GROUP='PCIE_RISER';

SECTION_NUMBER 1
 '@BASEBOARD_FAB2_LIB.BASEBOARD_FAB2(SCH_1):PAGE107_I477@MSTR_DISCRETE.CAP(CHIPS)':
 C_PATH='@baseboard_fab2_lib.baseboard_fab2(sch_1):page107_i477@mstr_discrete.ca~
p(chips)',
 P_PATH='@baseboard_fab2_lib.baseboard_fab2(sch_1):page107_i477@mstr_discrete.ca~
p(chips)',
 PATH='I477',
 DRAWING='@BASEBOARD_FAB2_LIB.BASEBOARD_FAB2(SCH_1):PAGE107',
 TOLERANCE='10%',
 MATERIAL='X7R',
 PHYS_PAGE='107',
 XY='(-5300,3675)',
 ROT='0',
 VER='1',
 VALUE='0.22UF',
 PACK_TYPE='0402',
 PART_NUMBER='A36096-155',
 LOCATION='C3P33',
 GROUP='PCIE_RISER',
 CDS_LIB='mstr_discrete',
 CDS_PART_NAME='CAP_0402-0.22UF,16V,10%,X7R,A3A',
 VOLTAGE='16V',
 PRIM_FILE='./archive_libs/mstr_discrete/cap/chips/chips.prt';

PART_NAME
 C3P34 'CAP_0402-0.22UF,16V,10%,X7R,A3A':
 GROUP='PCIE_RISER';

SECTION_NUMBER 1
 '@BASEBOARD_FAB2_LIB.BASEBOARD_FAB2(SCH_1):PAGE107_I489@MSTR_DISCRETE.CAP(CHIPS)':
 C_PATH='@baseboard_fab2_lib.baseboard_fab2(sch_1):page107_i489@mstr_discrete.ca~
p(chips)',
 P_PATH='@baseboard_fab2_lib.baseboard_fab2(sch_1):page107_i489@mstr_discrete.ca~
p(chips)',
 PATH='I489',
 DRAWING='@BASEBOARD_FAB2_LIB.BASEBOARD_FAB2(SCH_1):PAGE107',
 TOLERANCE='10%',
 MATERIAL='X7R',
 PHYS_PAGE='107',
 XY='(-5450,2975)',
 ROT='0',
 VER='1',
 VALUE='0.22UF',
 PACK_TYPE='0402',
 PART_NUMBER='A36096-155',
 LOCATION='C3P34',
 GROUP='PCIE_RISER',
 CDS_LIB='mstr_discrete',
 CDS_PART_NAME='CAP_0402-0.22UF,16V,10%,X7R,A3A',
 VOLTAGE='16V',
 PRIM_FILE='./archive_libs/mstr_discrete/cap/chips/chips.prt';

PART_NAME
 C3P35 'CAP_0402-0.22UF,16V,10%,X7R,A3A':
 GROUP='PCIE_UPLINK';

SECTION_NUMBER 1
 '@BASEBOARD_FAB2_LIB.BASEBOARD_FAB2(SCH_1):PAGE107_I240@MSTR_DISCRETE.CAP(CHIPS)':
 C_PATH='@baseboard_fab2_lib.baseboard_fab2(sch_1):page107_i240@mstr_discrete.ca~
p(chips)',
 P_PATH='@baseboard_fab2_lib.baseboard_fab2(sch_1):page107_i240@mstr_discrete.ca~
p(chips)',
 PATH='I240',
 DRAWING='@BASEBOARD_FAB2_LIB.BASEBOARD_FAB2(SCH_1):PAGE107',
 TOLERANCE='10%',
 MATERIAL='X7R',
 PHYS_PAGE='107',
 XY='(-6675,875)',
 ROT='2',
 VER='1',
 VALUE='0.22UF',
 PACK_TYPE='0402',
 PART_NUMBER='A36096-155',
 LOCATION='C3P35',
 GROUP='PCIE_UPLINK',
 CDS_LIB='mstr_discrete',
 CDS_PART_NAME='CAP_0402-0.22UF,16V,10%,X7R,A3A',
 VOLTAGE='16V',
 PRIM_FILE='./archive_libs/mstr_discrete/cap/chips/chips.prt';

PART_NAME
 C3P36 'CAP_0402-0.22UF,16V,10%,X7R,A3A':
 GROUP='PCIE_RISER';

SECTION_NUMBER 1
 '@BASEBOARD_FAB2_LIB.BASEBOARD_FAB2(SCH_1):PAGE107_I475@MSTR_DISCRETE.CAP(CHIPS)':
 C_PATH='@baseboard_fab2_lib.baseboard_fab2(sch_1):page107_i475@mstr_discrete.ca~
p(chips)',
 P_PATH='@baseboard_fab2_lib.baseboard_fab2(sch_1):page107_i475@mstr_discrete.ca~
p(chips)',
 PATH='I475',
 DRAWING='@BASEBOARD_FAB2_LIB.BASEBOARD_FAB2(SCH_1):PAGE107',
 TOLERANCE='10%',
 MATERIAL='X7R',
 PHYS_PAGE='107',
 XY='(-5500,3975)',
 ROT='0',
 VER='1',
 VALUE='0.22UF',
 PACK_TYPE='0402',
 PART_NUMBER='A36096-155',
 LOCATION='C3P36',
 GROUP='PCIE_RISER',
 CDS_LIB='mstr_discrete',
 CDS_PART_NAME='CAP_0402-0.22UF,16V,10%,X7R,A3A',
 VOLTAGE='16V',
 PRIM_FILE='./archive_libs/mstr_discrete/cap/chips/chips.prt';

PART_NAME
 C3P37 'CAP_0402-0.22UF,16V,10%,X7R,A3A':
 GROUP='PCIE_UPLINK';

SECTION_NUMBER 1
 '@BASEBOARD_FAB2_LIB.BASEBOARD_FAB2(SCH_1):PAGE107_I235@MSTR_DISCRETE.CAP(CHIPS)':
 C_PATH='@baseboard_fab2_lib.baseboard_fab2(sch_1):page107_i235@mstr_discrete.ca~
p(chips)',
 P_PATH='@baseboard_fab2_lib.baseboard_fab2(sch_1):page107_i235@mstr_discrete.ca~
p(chips)',
 PATH='I235',
 DRAWING='@BASEBOARD_FAB2_LIB.BASEBOARD_FAB2(SCH_1):PAGE107',
 TOLERANCE='10%',
 MATERIAL='X7R',
 PHYS_PAGE='107',
 XY='(-6725,1875)',
 ROT='2',
 VER='1',
 VALUE='0.22UF',
 PACK_TYPE='0402',
 PART_NUMBER='A36096-155',
 LOCATION='C3P37',
 GROUP='PCIE_UPLINK',
 CDS_LIB='mstr_discrete',
 CDS_PART_NAME='CAP_0402-0.22UF,16V,10%,X7R,A3A',
 VOLTAGE='16V',
 PRIM_FILE='./archive_libs/mstr_discrete/cap/chips/chips.prt';

PART_NAME
 C3P38 'CAP_0402-0.22UF,16V,10%,X7R,A3A':
 GROUP='PCIE_RISER';

SECTION_NUMBER 1
 '@BASEBOARD_FAB2_LIB.BASEBOARD_FAB2(SCH_1):PAGE107_I486@MSTR_DISCRETE.CAP(CHIPS)':
 C_PATH='@baseboard_fab2_lib.baseboard_fab2(sch_1):page107_i486@mstr_discrete.ca~
p(chips)',
 P_PATH='@baseboard_fab2_lib.baseboard_fab2(sch_1):page107_i486@mstr_discrete.ca~
p(chips)',
 PATH='I486',
 DRAWING='@BASEBOARD_FAB2_LIB.BASEBOARD_FAB2(SCH_1):PAGE107',
 TOLERANCE='10%',
 MATERIAL='X7R',
 PHYS_PAGE='107',
 XY='(-5650,2675)',
 ROT='0',
 VER='1',
 VALUE='0.22UF',
 PACK_TYPE='0402',
 PART_NUMBER='A36096-155',
 LOCATION='C3P38',
 GROUP='PCIE_RISER',
 CDS_LIB='mstr_discrete',
 CDS_PART_NAME='CAP_0402-0.22UF,16V,10%,X7R,A3A',
 VOLTAGE='16V',
 PRIM_FILE='./archive_libs/mstr_discrete/cap/chips/chips.prt';

PART_NAME
 C3P39 'CAP_0402-0.22UF,16V,10%,X7R,A3A':
 GROUP='PCIE_UPLINK';

SECTION_NUMBER 1
 '@BASEBOARD_FAB2_LIB.BASEBOARD_FAB2(SCH_1):PAGE107_I248@MSTR_DISCRETE.CAP(CHIPS)':
 C_PATH='@baseboard_fab2_lib.baseboard_fab2(sch_1):page107_i248@mstr_discrete.ca~
p(chips)',
 P_PATH='@baseboard_fab2_lib.baseboard_fab2(sch_1):page107_i248@mstr_discrete.ca~
p(chips)',
 PATH='I248',
 DRAWING='@BASEBOARD_FAB2_LIB.BASEBOARD_FAB2(SCH_1):PAGE107',
 TOLERANCE='10%',
 MATERIAL='X7R',
 PHYS_PAGE='107',
 XY='(-6875,575)',
 ROT='2',
 VER='1',
 VALUE='0.22UF',
 PACK_TYPE='0402',
 PART_NUMBER='A36096-155',
 LOCATION='C3P39',
 GROUP='PCIE_UPLINK',
 CDS_LIB='mstr_discrete',
 CDS_PART_NAME='CAP_0402-0.22UF,16V,10%,X7R,A3A',
 VOLTAGE='16V',
 PRIM_FILE='./archive_libs/mstr_discrete/cap/chips/chips.prt';

PART_NAME
 C3P40 'CAP_0402-0.22UF,16V,10%,X7R,A3A':
 GROUP='PCIE_UPLINK';

SECTION_NUMBER 1
 '@BASEBOARD_FAB2_LIB.BASEBOARD_FAB2(SCH_1):PAGE107_I241@MSTR_DISCRETE.CAP(CHIPS)':
 C_PATH='@baseboard_fab2_lib.baseboard_fab2(sch_1):page107_i241@mstr_discrete.ca~
p(chips)',
 P_PATH='@baseboard_fab2_lib.baseboard_fab2(sch_1):page107_i241@mstr_discrete.ca~
p(chips)',
 PATH='I241',
 DRAWING='@BASEBOARD_FAB2_LIB.BASEBOARD_FAB2(SCH_1):PAGE107',
 TOLERANCE='10%',
 MATERIAL='X7R',
 PHYS_PAGE='107',
 XY='(-6925,1575)',
 ROT='2',
 VER='1',
 VALUE='0.22UF',
 PACK_TYPE='0402',
 PART_NUMBER='A36096-155',
 LOCATION='C3P40',
 GROUP='PCIE_UPLINK',
 CDS_LIB='mstr_discrete',
 CDS_PART_NAME='CAP_0402-0.22UF,16V,10%,X7R,A3A',
 VOLTAGE='16V',
 PRIM_FILE='./archive_libs/mstr_discrete/cap/chips/chips.prt';

PART_NAME
 C3P41 'CAP_0402-0.22UF,16V,10%,X7R,A3A':
 GROUP='PCIE_RISER';

SECTION_NUMBER 1
 '@BASEBOARD_FAB2_LIB.BASEBOARD_FAB2(SCH_1):PAGE107_I474@MSTR_DISCRETE.CAP(CHIPS)':
 C_PATH='@baseboard_fab2_lib.baseboard_fab2(sch_1):page107_i474@mstr_discrete.ca~
p(chips)',
 P_PATH='@baseboard_fab2_lib.baseboard_fab2(sch_1):page107_i474@mstr_discrete.ca~
p(chips)',
 PATH='I474',
 DRAWING='@BASEBOARD_FAB2_LIB.BASEBOARD_FAB2(SCH_1):PAGE107',
 TOLERANCE='10%',
 MATERIAL='X7R',
 PHYS_PAGE='107',
 XY='(-5700,3675)',
 ROT='0',
 VER='1',
 VALUE='0.22UF',
 PACK_TYPE='0402',
 PART_NUMBER='A36096-155',
 LOCATION='C3P41',
 GROUP='PCIE_RISER',
 CDS_LIB='mstr_discrete',
 CDS_PART_NAME='CAP_0402-0.22UF,16V,10%,X7R,A3A',
 VOLTAGE='16V',
 PRIM_FILE='./archive_libs/mstr_discrete/cap/chips/chips.prt';

PART_NAME
 C3P42 'CAP_A_0402V-1.0UF,6.3V,10%,X6SA':
 ROOM='PROC_RSTS_PGOODS';

SECTION_NUMBER 1
 '@BASEBOARD_FAB2_LIB.BASEBOARD_FAB2(SCH_1):PAGE96_I73@DEV_DISCRETE.CAP_A(CHIPS)':
 C_PATH='@baseboard_fab2_lib.baseboard_fab2(sch_1):page96_i73@dev_discrete.cap_a~
(chips)',
 P_PATH='@baseboard_fab2_lib.baseboard_fab2(sch_1):page96_i73@dev_discrete.cap_a~
(chips)',
 PATH='I73',
 DRAWING='@BASEBOARD_FAB2_LIB.BASEBOARD_FAB2(SCH_1):PAGE96',
 TOLERANCE='10%',
 SEC_TYPE='0402V',
 MATERIAL='X6S',
 BOM_COST='PROC_SIDEBAND',
 PHYS_PAGE='96',
 XY='(-1650,4650)',
 ROT='0',
 VER='1',
 VALUE='1.0UF',
 PACK_TYPE='0402V',
 PART_NUMBER='D97712-004',
 LOCATION='C3P42',
 ROOM='PROC_RSTS_PGOODS',
 SEC='1',
 CDS_LIB='dev_discrete',
 CDS_PART_NAME='CAP_A_0402V-1.0UF,6.3V,10%,X6SA',
 VOLTAGE='6.3V',
 PRIM_FILE='./archive_libs/discrete/cap_a/chips/chips.prt';

PART_NAME
 C3P43 'CAP_A_0402V-0.1UF,16V,10%,X7R,A':
 ROOM='CPLD',
 SIGNAL_MODEL='DEFAULT_CAPACITOR_100000pF_2_1';

SECTION_NUMBER 1
 '@BASEBOARD_FAB2_LIB.BASEBOARD_FAB2(SCH_1):PAGE192_I6@DEV_DISCRETE.CAP_A(CHIPS)':
 C_PATH='@baseboard_fab2_lib.baseboard_fab2(sch_1):page192_i6@dev_discrete.cap_a~
(chips)',
 P_PATH='@baseboard_fab2_lib.baseboard_fab2(sch_1):page192_i6@dev_discrete.cap_a~
(chips)',
 PATH='I6',
 DRAWING='@BASEBOARD_FAB2_LIB.BASEBOARD_FAB2(SCH_1):PAGE192',
 TOLERANCE='10%',
 MATERIAL='X7R',
 BOM_COST='CPLD',
 PHYS_PAGE='192',
 XY='(-2650,1975)',
 ROT='0',
 VER='1',
 VALUE='0.1UF',
 PACK_TYPE='0402V',
 PART_NUMBER='A36096-030',
 LOCATION='C3P43',
 SIGNAL_MODEL='DEFAULT_CAPACITOR_100000pF_2_1',
 ROOM='CPLD',
 CDS_LIB='dev_discrete',
 CDS_PART_NAME='CAP_A_0402V-0.1UF,16V,10%,X7R,A',
 VOLTAGE='16V',
 PRIM_FILE='./archive_libs/discrete/cap_a/chips/chips.prt';

PART_NAME
 C3P44 'CAP_A_0402V-0.1UF,16V,10%,X7R,A':
 ROOM='CPLD',
 SIGNAL_MODEL='DEFAULT_CAPACITOR_100000pF_2_1';

SECTION_NUMBER 1
 '@BASEBOARD_FAB2_LIB.BASEBOARD_FAB2(SCH_1):PAGE192_I23@DEV_DISCRETE.CAP_A(CHIPS)':
 C_PATH='@baseboard_fab2_lib.baseboard_fab2(sch_1):page192_i23@dev_discrete.cap_~
a(chips)',
 P_PATH='@baseboard_fab2_lib.baseboard_fab2(sch_1):page192_i23@dev_discrete.cap_~
a(chips)',
 PATH='I23',
 DRAWING='@BASEBOARD_FAB2_LIB.BASEBOARD_FAB2(SCH_1):PAGE192',
 TOLERANCE='10%',
 MATERIAL='X7R',
 BOM_COST='CPLD',
 PHYS_PAGE='192',
 XY='(-6450,1975)',
 ROT='0',
 VER='1',
 VALUE='0.1UF',
 PACK_TYPE='0402V',
 PART_NUMBER='A36096-030',
 LOCATION='C3P44',
 SIGNAL_MODEL='DEFAULT_CAPACITOR_100000pF_2_1',
 ROOM='CPLD',
 CDS_LIB='dev_discrete',
 CDS_PART_NAME='CAP_A_0402V-0.1UF,16V,10%,X7R,A',
 VOLTAGE='16V',
 PRIM_FILE='./archive_libs/discrete/cap_a/chips/chips.prt';

PART_NAME
 C3P45 'CAP_0402-0.047UF,25V,10%,X7R,AA':
 ROOM='V_SUPER';

SECTION_NUMBER 1
 '@BASEBOARD_FAB2_LIB.BASEBOARD_FAB2(SCH_1):PAGE196_I60@MSTR_DISCRETE.CAP(CHIPS)':
 C_PATH='@baseboard_fab2_lib.baseboard_fab2(sch_1):page196_i60@mstr_discrete.cap~
(chips)',
 P_PATH='@baseboard_fab2_lib.baseboard_fab2(sch_1):page196_i60@mstr_discrete.cap~
(chips)',
 PATH='I60',
 DRAWING='@BASEBOARD_FAB2_LIB.BASEBOARD_FAB2(SCH_1):PAGE196',
 TOLERANCE='10%',
 SEC_TYPE='0402',
 MATERIAL='X7R',
 PHYS_PAGE='196',
 XY='(1225,4050)',
 ROT='0',
 VER='1',
 VALUE='0.047UF',
 PACK_TYPE='0402',
 PART_NUMBER='A36096-090',
 LOCATION='C3P45',
 ROOM='V_SUPER',
 SEC='1',
 CDS_LIB='mstr_discrete',
 CDS_PART_NAME='CAP_0402-0.047UF,25V,10%,X7R,AA',
 VOLTAGE='25V',
 PRIM_FILE='./archive_libs/mstr_discrete/cap/chips/chips.prt';

PART_NAME
 C3P46 'CAP_A_0402V-0.1UF,16V,10%,X7R,A':
 ROOM='V_SUPER';

SECTION_NUMBER 1
 '@BASEBOARD_FAB2_LIB.BASEBOARD_FAB2(SCH_1):PAGE196_I72@DEV_DISCRETE.CAP_A(CHIPS)':
 C_PATH='@baseboard_fab2_lib.baseboard_fab2(sch_1):page196_i72@dev_discrete.cap_~
a(chips)',
 P_PATH='@baseboard_fab2_lib.baseboard_fab2(sch_1):page196_i72@dev_discrete.cap_~
a(chips)',
 PATH='I72',
 DRAWING='@BASEBOARD_FAB2_LIB.BASEBOARD_FAB2(SCH_1):PAGE196',
 TOLERANCE='10%',
 SEC_TYPE='0402V',
 MATERIAL='X7R',
 PHYS_PAGE='196',
 XY='(275,3950)',
 ROT='0',
 VER='1',
 VALUE='0.1UF',
 PACK_TYPE='0402V',
 PART_NUMBER='A36096-030',
 LOCATION='C3P46',
 ROOM='V_SUPER',
 SEC='1',
 CDS_LIB='dev_discrete',
 CDS_PART_NAME='CAP_A_0402V-0.1UF,16V,10%,X7R,A',
 VOLTAGE='16V',
 PRIM_FILE='./archive_libs/discrete/cap_a/chips/chips.prt';

PART_NAME
 C3P47 'CAP_A_0402V-0.1UF,16V,10%,X7R,A':
 ROOM='CPLD',
 SIGNAL_MODEL='DEFAULT_CAPACITOR_100000pF_2_1';

SECTION_NUMBER 1
 '@BASEBOARD_FAB2_LIB.BASEBOARD_FAB2(SCH_1):PAGE192_I12@DEV_DISCRETE.CAP_A(CHIPS)':
 C_PATH='@baseboard_fab2_lib.baseboard_fab2(sch_1):page192_i12@dev_discrete.cap_~
a(chips)',
 P_PATH='@baseboard_fab2_lib.baseboard_fab2(sch_1):page192_i12@dev_discrete.cap_~
a(chips)',
 PATH='I12',
 DRAWING='@BASEBOARD_FAB2_LIB.BASEBOARD_FAB2(SCH_1):PAGE192',
 TOLERANCE='10%',
 MATERIAL='X7R',
 BOM_COST='CPLD',
 PHYS_PAGE='192',
 XY='(-4200,1300)',
 ROT='0',
 VER='1',
 VALUE='0.1UF',
 PACK_TYPE='0402V',
 PART_NUMBER='A36096-030',
 LOCATION='C3P47',
 SIGNAL_MODEL='DEFAULT_CAPACITOR_100000pF_2_1',
 ROOM='CPLD',
 CDS_LIB='dev_discrete',
 CDS_PART_NAME='CAP_A_0402V-0.1UF,16V,10%,X7R,A',
 VOLTAGE='16V',
 PRIM_FILE='./archive_libs/discrete/cap_a/chips/chips.prt';

PART_NAME
 C3P48 'CAP_A_0402V-0.1UF,16V,10%,X7R,A':
 ROOM='CPLD',
 SIGNAL_MODEL='DEFAULT_CAPACITOR_100000pF_2_1';

SECTION_NUMBER 1
 '@BASEBOARD_FAB2_LIB.BASEBOARD_FAB2(SCH_1):PAGE192_I25@DEV_DISCRETE.CAP_A(CHIPS)':
 C_PATH='@baseboard_fab2_lib.baseboard_fab2(sch_1):page192_i25@dev_discrete.cap_~
a(chips)',
 P_PATH='@baseboard_fab2_lib.baseboard_fab2(sch_1):page192_i25@dev_discrete.cap_~
a(chips)',
 PATH='I25',
 DRAWING='@BASEBOARD_FAB2_LIB.BASEBOARD_FAB2(SCH_1):PAGE192',
 TOLERANCE='10%',
 SEC_TYPE='0402V',
 MATERIAL='X7R',
 BOM_COST='CPLD',
 PHYS_PAGE='192',
 XY='(-6925,1975)',
 ROT='0',
 VER='1',
 VALUE='0.1UF',
 PACK_TYPE='0402V',
 PART_NUMBER='A36096-030',
 LOCATION='C3P48',
 SIGNAL_MODEL='DEFAULT_CAPACITOR_100000pF_2_1',
 ROOM='CPLD',
 SEC='1',
 CDS_LIB='dev_discrete',
 CDS_PART_NAME='CAP_A_0402V-0.1UF,16V,10%,X7R,A',
 VOLTAGE='16V',
 PRIM_FILE='./archive_libs/discrete/cap_a/chips/chips.prt';

PART_NAME
 C3P49 'CAP_A_0402V-0.1UF,16V,10%,X7R,A':
 ROOM='PROC_SIDEBAND';

SECTION_NUMBER 1
 '@BASEBOARD_FAB2_LIB.BASEBOARD_FAB2(SCH_1):PAGE92_I37@DEV_DISCRETE.CAP_A(CHIPS)':
 C_PATH='@baseboard_fab2_lib.baseboard_fab2(sch_1):page92_i37@dev_discrete.cap_a~
(chips)',
 P_PATH='@baseboard_fab2_lib.baseboard_fab2(sch_1):page92_i37@dev_discrete.cap_a~
(chips)',
 PATH='I37',
 DRAWING='@BASEBOARD_FAB2_LIB.BASEBOARD_FAB2(SCH_1):PAGE92',
 TOLERANCE='10%',
 SEC_TYPE='0402V',
 MATERIAL='X7R',
 BOM_COST='PROC_SIDEBAND',
 PHYS_PAGE='92',
 XY='(-400,4800)',
 ROT='0',
 VER='1',
 VALUE='0.1UF',
 PACK_TYPE='0402V',
 PART_NUMBER='A36096-030',
 LOCATION='C3P49',
 ROOM='PROC_SIDEBAND',
 SEC='1',
 CDS_LIB='dev_discrete',
 CDS_PART_NAME='CAP_A_0402V-0.1UF,16V,10%,X7R,A',
 VOLTAGE='16V',
 PRIM_FILE='./archive_libs/discrete/cap_a/chips/chips.prt';

PART_NAME
 C3P50 'CAP_0402-1.0UF,16V,10%,X6S,D97A':
 ROOM='PROC_SIDEBAND';

SECTION_NUMBER 1
 '@BASEBOARD_FAB2_LIB.BASEBOARD_FAB2(SCH_1):PAGE92_I84@MSTR_DISCRETE.CAP(CHIPS)':
 C_PATH='@baseboard_fab2_lib.baseboard_fab2(sch_1):page92_i84@mstr_discrete.cap(~
chips)',
 P_PATH='@baseboard_fab2_lib.baseboard_fab2(sch_1):page92_i84@mstr_discrete.cap(~
chips)',
 PATH='I84',
 DRAWING='@BASEBOARD_FAB2_LIB.BASEBOARD_FAB2(SCH_1):PAGE92',
 TOLERANCE='10%',
 SEC_TYPE='0402',
 MATERIAL='X6S',
 BOM_COST='PROC',
 PHYS_PAGE='92',
 XY='(-1025,4725)',
 ROT='0',
 VER='1',
 VALUE='1.0UF',
 PACK_TYPE='0402',
 PART_NUMBER='D97712-011',
 LOCATION='C3P50',
 ROOM='PROC_SIDEBAND',
 SEC='1',
 CDS_LIB='mstr_discrete',
 CDS_PART_NAME='CAP_0402-1.0UF,16V,10%,X6S,D97A',
 VOLTAGE='16V',
 PRIM_FILE='./archive_libs/mstr_discrete/cap/chips/chips.prt';

PART_NAME
 C3P51 'CAP_A_0402V-0.1UF,16V,10%,X7R,A':
 ROOM='CPLD',
 SIGNAL_MODEL='DEFAULT_CAPACITOR_100000pF_2_1';

SECTION_NUMBER 1
 '@BASEBOARD_FAB2_LIB.BASEBOARD_FAB2(SCH_1):PAGE192_I11@DEV_DISCRETE.CAP_A(CHIPS)':
 C_PATH='@baseboard_fab2_lib.baseboard_fab2(sch_1):page192_i11@dev_discrete.cap_~
a(chips)',
 P_PATH='@baseboard_fab2_lib.baseboard_fab2(sch_1):page192_i11@dev_discrete.cap_~
a(chips)',
 PATH='I11',
 DRAWING='@BASEBOARD_FAB2_LIB.BASEBOARD_FAB2(SCH_1):PAGE192',
 TOLERANCE='10%',
 MATERIAL='X7R',
 BOM_COST='CPLD',
 PHYS_PAGE='192',
 XY='(-3700,1300)',
 ROT='0',
 VER='1',
 VALUE='0.1UF',
 PACK_TYPE='0402V',
 PART_NUMBER='A36096-030',
 LOCATION='C3P51',
 SIGNAL_MODEL='DEFAULT_CAPACITOR_100000pF_2_1',
 ROOM='CPLD',
 CDS_LIB='dev_discrete',
 CDS_PART_NAME='CAP_A_0402V-0.1UF,16V,10%,X7R,A',
 VOLTAGE='16V',
 PRIM_FILE='./archive_libs/discrete/cap_a/chips/chips.prt';

PART_NAME
 C3P52 'CAP_A_0402V-0.1UF,16V,10%,X7R,A':
 ROOM='CPLD',
 SIGNAL_MODEL='DEFAULT_CAPACITOR_100000pF_2_1';

SECTION_NUMBER 1
 '@BASEBOARD_FAB2_LIB.BASEBOARD_FAB2(SCH_1):PAGE192_I17@DEV_DISCRETE.CAP_A(CHIPS)':
 C_PATH='@baseboard_fab2_lib.baseboard_fab2(sch_1):page192_i17@dev_discrete.cap_~
a(chips)',
 P_PATH='@baseboard_fab2_lib.baseboard_fab2(sch_1):page192_i17@dev_discrete.cap_~
a(chips)',
 PATH='I17',
 DRAWING='@BASEBOARD_FAB2_LIB.BASEBOARD_FAB2(SCH_1):PAGE192',
 TOLERANCE='10%',
 MATERIAL='X7R',
 BOM_COST='CPLD',
 PHYS_PAGE='192',
 XY='(-4725,1300)',
 ROT='0',
 VER='1',
 VALUE='0.1UF',
 PACK_TYPE='0402V',
 PART_NUMBER='A36096-030',
 LOCATION='C3P52',
 SIGNAL_MODEL='DEFAULT_CAPACITOR_100000pF_2_1',
 ROOM='CPLD',
 CDS_LIB='dev_discrete',
 CDS_PART_NAME='CAP_A_0402V-0.1UF,16V,10%,X7R,A',
 VOLTAGE='16V',
 PRIM_FILE='./archive_libs/discrete/cap_a/chips/chips.prt';

PART_NAME
 C3R1 'CAP_A_0402V-0.1UF,16V,10%,X7R,A':
 ROOM='CPLD',
 SIGNAL_MODEL='DEFAULT_CAPACITOR_100000pF_2_1';

SECTION_NUMBER 1
 '@BASEBOARD_FAB2_LIB.BASEBOARD_FAB2(SCH_1):PAGE192_I4@DEV_DISCRETE.CAP_A(CHIPS)':
 C_PATH='@baseboard_fab2_lib.baseboard_fab2(sch_1):page192_i4@dev_discrete.cap_a~
(chips)',
 P_PATH='@baseboard_fab2_lib.baseboard_fab2(sch_1):page192_i4@dev_discrete.cap_a~
(chips)',
 PATH='I4',
 DRAWING='@BASEBOARD_FAB2_LIB.BASEBOARD_FAB2(SCH_1):PAGE192',
 TOLERANCE='10%',
 MATERIAL='X7R',
 BOM_COST='CPLD',
 PHYS_PAGE='192',
 XY='(-2175,1975)',
 ROT='0',
 VER='1',
 VALUE='0.1UF',
 PACK_TYPE='0402V',
 PART_NUMBER='A36096-030',
 LOCATION='C3R1',
 SIGNAL_MODEL='DEFAULT_CAPACITOR_100000pF_2_1',
 ROOM='CPLD',
 CDS_LIB='dev_discrete',
 CDS_PART_NAME='CAP_A_0402V-0.1UF,16V,10%,X7R,A',
 VOLTAGE='16V',
 PRIM_FILE='./archive_libs/discrete/cap_a/chips/chips.prt';

PART_NAME
 C3R2 'CAP_A_0402V-0.1UF,16V,10%,X7R,A':
 ROOM='CPLD',
 SIGNAL_MODEL='DEFAULT_CAPACITOR_100000pF_2_1';

SECTION_NUMBER 1
 '@BASEBOARD_FAB2_LIB.BASEBOARD_FAB2(SCH_1):PAGE192_I10@DEV_DISCRETE.CAP_A(CHIPS)':
 C_PATH='@baseboard_fab2_lib.baseboard_fab2(sch_1):page192_i10@dev_discrete.cap_~
a(chips)',
 P_PATH='@baseboard_fab2_lib.baseboard_fab2(sch_1):page192_i10@dev_discrete.cap_~
a(chips)',
 PATH='I10',
 DRAWING='@BASEBOARD_FAB2_LIB.BASEBOARD_FAB2(SCH_1):PAGE192',
 TOLERANCE='10%',
 MATERIAL='X7R',
 BOM_COST='CPLD',
 PHYS_PAGE='192',
 XY='(-4075,1975)',
 ROT='0',
 VER='1',
 VALUE='0.1UF',
 PACK_TYPE='0402V',
 PART_NUMBER='A36096-030',
 LOCATION='C3R2',
 SIGNAL_MODEL='DEFAULT_CAPACITOR_100000pF_2_1',
 ROOM='CPLD',
 CDS_LIB='dev_discrete',
 CDS_PART_NAME='CAP_A_0402V-0.1UF,16V,10%,X7R,A',
 VOLTAGE='16V',
 PRIM_FILE='./archive_libs/discrete/cap_a/chips/chips.prt';

PART_NAME
 C3R3 'CAP_A_0402V-0.1UF,16V,10%,X7R,A':
 ROOM='CPLD',
 SIGNAL_MODEL='DEFAULT_CAPACITOR_100000pF_2_1';

SECTION_NUMBER 1
 '@BASEBOARD_FAB2_LIB.BASEBOARD_FAB2(SCH_1):PAGE192_I7@DEV_DISCRETE.CAP_A(CHIPS)':
 C_PATH='@baseboard_fab2_lib.baseboard_fab2(sch_1):page192_i7@dev_discrete.cap_a~
(chips)',
 P_PATH='@baseboard_fab2_lib.baseboard_fab2(sch_1):page192_i7@dev_discrete.cap_a~
(chips)',
 PATH='I7',
 DRAWING='@BASEBOARD_FAB2_LIB.BASEBOARD_FAB2(SCH_1):PAGE192',
 TOLERANCE='10%',
 MATERIAL='X7R',
 BOM_COST='CPLD',
 PHYS_PAGE='192',
 XY='(-3125,1975)',
 ROT='0',
 VER='1',
 VALUE='0.1UF',
 PACK_TYPE='0402V',
 PART_NUMBER='A36096-030',
 LOCATION='C3R3',
 SIGNAL_MODEL='DEFAULT_CAPACITOR_100000pF_2_1',
 ROOM='CPLD',
 CDS_LIB='dev_discrete',
 CDS_PART_NAME='CAP_A_0402V-0.1UF,16V,10%,X7R,A',
 VOLTAGE='16V',
 PRIM_FILE='./archive_libs/discrete/cap_a/chips/chips.prt';

PART_NAME
 C3R4 'CAPP_3018-470UF,2.5V,20%,ALUM,A':
 GROUP='PWR_MCP_CAP',
 ROOM='PVMCP_MCP_CPU0_VR';

SECTION_NUMBER 1
 '@BASEBOARD_FAB2_LIB.BASEBOARD_FAB2(SCH_1):PAGE194_I31@MSTR_DISCRETE.CAPP(CHIPS)':
 C_PATH='@baseboard_fab2_lib.baseboard_fab2(sch_1):page194_i31@mstr_discrete.cap~
p(chips)',
 P_PATH='@baseboard_fab2_lib.baseboard_fab2(sch_1):page194_i31@mstr_discrete.cap~
p(chips)',
 PATH='I31',
 DRAWING='@BASEBOARD_FAB2_LIB.BASEBOARD_FAB2(SCH_1):PAGE194',
 TOLERANCE='20%',
 MATERIAL='ALUM',
 BOM_COST='PVMCP_MCP_CPU0_VR',
 PHYS_PAGE='194',
 XY='(-1900,2500)',
 ROT='0',
 VER='1',
 VALUE='470UF',
 PACK_TYPE='3018',
 PART_NUMBER='699013-049',
 LOCATION='C3R4',
 ROOM='PVMCP_MCP_CPU0_VR',
 GROUP='PWR_MCP_CAP',
 CDS_LIB='mstr_discrete',
 CDS_PART_NAME='CAPP_3018-470UF,2.5V,20%,ALUM,A',
 VOLTAGE='2.5V',
 PRIM_FILE='./archive_libs/mstr_discrete/capp/chips/chips.prt';

PART_NAME
 C3T1 'CAP_A_0603V-47UF,4V,20%,X5R,60A':
 GROUP='PWR_MCP_CAP';

SECTION_NUMBER 1
 '@BASEBOARD_FAB2_LIB.BASEBOARD_FAB2(SCH_1):PAGE194_I149@DEV_DISCRETE.CAP_A(CHIPS)':
 C_PATH='@baseboard_fab2_lib.baseboard_fab2(sch_1):page194_i149@dev_discrete.cap~
_a(chips)',
 P_PATH='@baseboard_fab2_lib.baseboard_fab2(sch_1):page194_i149@dev_discrete.cap~
_a(chips)',
 PATH='I149',
 DRAWING='@BASEBOARD_FAB2_LIB.BASEBOARD_FAB2(SCH_1):PAGE194',
 TOLERANCE='20%',
 SEC_TYPE='0603V',
 MATERIAL='X5R',
 PHYS_PAGE='194',
 XY='(-1600,1850)',
 ROT='0',
 VER='1',
 VALUE='47UF',
 PACK_TYPE='0603V',
 PART_NUMBER='602433-106',
 LOCATION='C3T1',
 GROUP='PWR_MCP_CAP',
 SEC='1',
 CDS_LIB='dev_discrete',
 CDS_PART_NAME='CAP_A_0603V-47UF,4V,20%,X5R,60A',
 VOLTAGE='4V',
 PRIM_FILE='./archive_libs/discrete/cap_a/chips/chips.prt';

PART_NAME
 C3T2 'CAP_A_0603V-47UF,4V,20%,X5R,60A':
 GROUP='PWR_MCP_CAP';

SECTION_NUMBER 1
 '@BASEBOARD_FAB2_LIB.BASEBOARD_FAB2(SCH_1):PAGE194_I150@DEV_DISCRETE.CAP_A(CHIPS)':
 C_PATH='@baseboard_fab2_lib.baseboard_fab2(sch_1):page194_i150@dev_discrete.cap~
_a(chips)',
 P_PATH='@baseboard_fab2_lib.baseboard_fab2(sch_1):page194_i150@dev_discrete.cap~
_a(chips)',
 PATH='I150',
 DRAWING='@BASEBOARD_FAB2_LIB.BASEBOARD_FAB2(SCH_1):PAGE194',
 TOLERANCE='20%',
 SEC_TYPE='0603V',
 MATERIAL='X5R',
 PHYS_PAGE='194',
 XY='(-1900,1850)',
 ROT='0',
 VER='1',
 VALUE='47UF',
 PACK_TYPE='0603V',
 PART_NUMBER='602433-106',
 LOCATION='C3T2',
 GROUP='PWR_MCP_CAP',
 SEC='1',
 CDS_LIB='dev_discrete',
 CDS_PART_NAME='CAP_A_0603V-47UF,4V,20%,X5R,60A',
 VOLTAGE='4V',
 PRIM_FILE='./archive_libs/discrete/cap_a/chips/chips.prt';

PART_NAME
 C3T3 'CAPP_3018-68UF,16V,20%,TANT,72A':;

SECTION_NUMBER 1
 '@BASEBOARD_FAB2_LIB.BASEBOARD_FAB2(SCH_1):PAGE195_I113@MSTR_DISCRETE.CAPP(CHIPS)':
 C_PATH='@baseboard_fab2_lib.baseboard_fab2(sch_1):page195_i113@mstr_discrete.ca~
pp(chips)',
 P_PATH='@baseboard_fab2_lib.baseboard_fab2(sch_1):page195_i113@mstr_discrete.ca~
pp(chips)',
 PATH='I113',
 DRAWING='@BASEBOARD_FAB2_LIB.BASEBOARD_FAB2(SCH_1):PAGE195',
 TOLERANCE='20%',
 SEC_TYPE='3018',
 MATERIAL='TANT',
 PHYS_PAGE='195',
 XY='(-7675,1950)',
 ROT='0',
 VER='1',
 VALUE='68UF',
 PACK_TYPE='3018',
 PART_NUMBER='724613-112',
 LOCATION='C3T3',
 SEC='1',
 CDS_LIB='mstr_discrete',
 CDS_PART_NAME='CAPP_3018-68UF,16V,20%,TANT,72A',
 VOLTAGE='16V',
 PRIM_FILE='./archive_libs/mstr_discrete/capp/chips/chips.prt';

PART_NAME
 C3T4 'CAP_A_0402V-1.0UF,6.3V,10%,X6SA':
 GROUP='NI_BIOS_ROM2',
 ROOM='SB_SPI',
 NO_XNET_CONNECTION='1';

SECTION_NUMBER 1
 '@BASEBOARD_FAB2_LIB.BASEBOARD_FAB2(SCH_1):PAGE153_I138@DEV_DISCRETE.CAP_A(CHIPS)':
 C_PATH='@baseboard_fab2_lib.baseboard_fab2(sch_1):page153_i138@dev_discrete.cap~
_a(chips)',
 P_PATH='@baseboard_fab2_lib.baseboard_fab2(sch_1):page153_i138@dev_discrete.cap~
_a(chips)',
 PATH='I138',
 DRAWING='@BASEBOARD_FAB2_LIB.BASEBOARD_FAB2(SCH_1):PAGE153',
 TOLERANCE='10%',
 SEC_TYPE='0402V',
 MATERIAL='X6S',
 BOM_COST='MIO_BIOS_MEM',
 NO_XNET_CONNECTION='1',
 PHYS_PAGE='153',
 XY='(-3925,2400)',
 ROT='0',
 VER='1',
 VALUE='1.0UF',
 PACK_TYPE='0402V',
 PART_NUMBER='D97712-004',
 LOCATION='C3T4',
 ROOM='SB_SPI',
 GROUP='NI_BIOS_ROM2',
 SEC='1',
 CDS_LIB='dev_discrete',
 CDS_PART_NAME='CAP_A_0402V-1.0UF,6.3V,10%,X6SA',
 VOLTAGE='6.3V',
 PRIM_FILE='./archive_libs/discrete/cap_a/chips/chips.prt';

PART_NAME
 C3T5 'CAP_A_0402V-0.01UF,25V,10%,X7RA':
 GROUP='NI_BIOS_ROM2',
 ROOM='SB_SPI',
 NO_XNET_CONNECTION='1';

SECTION_NUMBER 1
 '@BASEBOARD_FAB2_LIB.BASEBOARD_FAB2(SCH_1):PAGE153_I136@DEV_DISCRETE.CAP_A(CHIPS)':
 C_PATH='@baseboard_fab2_lib.baseboard_fab2(sch_1):page153_i136@dev_discrete.cap~
_a(chips)',
 P_PATH='@baseboard_fab2_lib.baseboard_fab2(sch_1):page153_i136@dev_discrete.cap~
_a(chips)',
 PATH='I136',
 DRAWING='@BASEBOARD_FAB2_LIB.BASEBOARD_FAB2(SCH_1):PAGE153',
 TOLERANCE='10%',
 SEC_TYPE='0402V',
 MATERIAL='X7R',
 BOM_COST='MIO_BIOS_MEM',
 NO_XNET_CONNECTION='1',
 PHYS_PAGE='153',
 XY='(-3625,2400)',
 ROT='0',
 VER='1',
 VALUE='0.01UF',
 PACK_TYPE='0402V',
 PART_NUMBER='A36096-045',
 LOCATION='C3T5',
 ROOM='SB_SPI',
 GROUP='NI_BIOS_ROM2',
 SEC='1',
 CDS_LIB='dev_discrete',
 CDS_PART_NAME='CAP_A_0402V-0.01UF,25V,10%,X7RA',
 VOLTAGE='25V',
 PRIM_FILE='./archive_libs/discrete/cap_a/chips/chips.prt';

PART_NAME
 C3T6 'CAPP_3018-68UF,16V,20%,TANT,72A':;

SECTION_NUMBER 1
 '@BASEBOARD_FAB2_LIB.BASEBOARD_FAB2(SCH_1):PAGE195_I98@MSTR_DISCRETE.CAPP(CHIPS)':
 C_PATH='@baseboard_fab2_lib.baseboard_fab2(sch_1):page195_i98@mstr_discrete.cap~
p(chips)',
 P_PATH='@baseboard_fab2_lib.baseboard_fab2(sch_1):page195_i98@mstr_discrete.cap~
p(chips)',
 PATH='I98',
 DRAWING='@BASEBOARD_FAB2_LIB.BASEBOARD_FAB2(SCH_1):PAGE195',
 TOLERANCE='20%',
 SEC_TYPE='3018',
 MATERIAL='TANT',
 PHYS_PAGE='195',
 XY='(-5300,750)',
 ROT='0',
 VER='1',
 VALUE='68UF',
 PACK_TYPE='3018',
 PART_NUMBER='724613-112',
 LOCATION='C3T6',
 SEC='1',
 CDS_LIB='mstr_discrete',
 CDS_PART_NAME='CAPP_3018-68UF,16V,20%,TANT,72A',
 VOLTAGE='16V',
 PRIM_FILE='./archive_libs/mstr_discrete/capp/chips/chips.prt';

PART_NAME
 C3T7 'CAP_0805-47UF,4V,20%,X6S,C9533A':
 GROUP='PWR_MLCC_CAP',
 ROOM='PVPP_KLM_VR',
 REUSE_ID='33';

SECTION_NUMBER 1
 '@BASEBOARD_FAB2_LIB.BASEBOARD_FAB2(SCH_1):PAGE231_I184@MSTR_DISCRETE.CAP(CHIPS)':
 C_PATH='@baseboard_fab2_lib.baseboard_fab2(sch_1):page231_i184@mstr_discrete.ca~
p(chips)',
 P_PATH='@baseboard_fab2_lib.baseboard_fab2(sch_1):page231_i184@mstr_discrete.ca~
p(chips)',
 PATH='I184',
 DRAWING='@BASEBOARD_FAB2_LIB.BASEBOARD_FAB2(SCH_1):PAGE231',
 TOLERANCE='20%',
 MATERIAL='X6S',
 BOM_COST='PVPP_KLM_VR',
 PHYS_PAGE='231',
 REUSE_ID='33',
 XY='(-775,3900)',
 ROT='0',
 VER='1',
 VALUE='47UF',
 PACK_TYPE='0805',
 PART_NUMBER='C95333-006',
 LOCATION='C3T7',
 ROOM='PVPP_KLM_VR',
 GROUP='PWR_MLCC_CAP',
 CDS_LIB='mstr_discrete',
 CDS_PART_NAME='CAP_0805-47UF,4V,20%,X6S,C9533A',
 VOLTAGE='4V',
 PRIM_FILE='./archive_libs/mstr_discrete/cap/chips/chips.prt';

PART_NAME
 C3T8 'CAP_0805-10UF,16V,10%,X6S,C953A':;

SECTION_NUMBER 1
 '@BASEBOARD_FAB2_LIB.BASEBOARD_FAB2(SCH_1):PAGE231_I210@MSTR_DISCRETE.CAP(CHIPS)':
 C_PATH='@baseboard_fab2_lib.baseboard_fab2(sch_1):page231_i210@mstr_discrete.ca~
p(chips)',
 P_PATH='@baseboard_fab2_lib.baseboard_fab2(sch_1):page231_i210@mstr_discrete.ca~
p(chips)',
 PATH='I210',
 DRAWING='@BASEBOARD_FAB2_LIB.BASEBOARD_FAB2(SCH_1):PAGE231',
 TOLERANCE='10%',
 SEC_TYPE='0805',
 MATERIAL='X6S',
 PHYS_PAGE='231',
 XY='(-5825,4375)',
 ROT='0',
 VER='1',
 VALUE='10UF',
 PACK_TYPE='0805',
 PART_NUMBER='C95333-007',
 LOCATION='C3T8',
 SEC='1',
 CDS_LIB='mstr_discrete',
 CDS_PART_NAME='CAP_0805-10UF,16V,10%,X6S,C953A',
 VOLTAGE='16V',
 PRIM_FILE='./archive_libs/mstr_discrete/cap/chips/chips.prt';

PART_NAME
 C3T9 'CAP_0805-47UF,4V,20%,X6S,C9533A':
 GROUP='PWR_MLCC_CAP',
 ROOM='PVPP_KLM_VR',
 REUSE_ID='33';

SECTION_NUMBER 1
 '@BASEBOARD_FAB2_LIB.BASEBOARD_FAB2(SCH_1):PAGE231_I186@MSTR_DISCRETE.CAP(CHIPS)':
 C_PATH='@baseboard_fab2_lib.baseboard_fab2(sch_1):page231_i186@mstr_discrete.ca~
p(chips)',
 P_PATH='@baseboard_fab2_lib.baseboard_fab2(sch_1):page231_i186@mstr_discrete.ca~
p(chips)',
 PATH='I186',
 DRAWING='@BASEBOARD_FAB2_LIB.BASEBOARD_FAB2(SCH_1):PAGE231',
 TOLERANCE='20%',
 MATERIAL='X6S',
 BOM_COST='PVPP_KLM_VR',
 PHYS_PAGE='231',
 REUSE_ID='33',
 XY='(-475,3925)',
 ROT='0',
 VER='1',
 VALUE='47UF',
 PACK_TYPE='0805',
 PART_NUMBER='C95333-006',
 LOCATION='C3T9',
 ROOM='PVPP_KLM_VR',
 GROUP='PWR_MLCC_CAP',
 CDS_LIB='mstr_discrete',
 CDS_PART_NAME='CAP_0805-47UF,4V,20%,X6S,C9533A',
 VOLTAGE='4V',
 PRIM_FILE='./archive_libs/mstr_discrete/cap/chips/chips.prt';

PART_NAME
 C3T10 'CAP_0402-1.0UF,16V,10%,X6S,D97A':
 ROOM='PVPP_KLM_VR',
 REUSE_ID='1';

SECTION_NUMBER 1
 '@BASEBOARD_FAB2_LIB.BASEBOARD_FAB2(SCH_1):PAGE231_I161@MSTR_DISCRETE.CAP(CHIPS)':
 C_PATH='@baseboard_fab2_lib.baseboard_fab2(sch_1):page231_i161@mstr_discrete.ca~
p(chips)',
 P_PATH='@baseboard_fab2_lib.baseboard_fab2(sch_1):page231_i161@mstr_discrete.ca~
p(chips)',
 PATH='I161',
 DRAWING='@BASEBOARD_FAB2_LIB.BASEBOARD_FAB2(SCH_1):PAGE231',
 FIN='VR_1P2',
 TOLERANCE='10%',
 MATERIAL='X6S',
 BOM_COST='PVPP_KLM_VR',
 PHYS_PAGE='231',
 REUSE_ID='1',
 XY='(-4700,4400)',
 ROT='0',
 VER='1',
 VALUE='1.0UF',
 PACK_TYPE='0402',
 PART_NUMBER='D97712-011',
 LOCATION='C3T10',
 ROOM='PVPP_KLM_VR',
 CDS_LIB='mstr_discrete',
 CDS_PART_NAME='CAP_0402-1.0UF,16V,10%,X6S,D97A',
 VOLTAGE='16V',
 PRIM_FILE='./archive_libs/mstr_discrete/cap/chips/chips.prt';

PART_NAME
 C3T11 'CAP_0603-4.7UF,6.3V,10%,X6S,E1A':
 ROOM='PVPP_KLM_VR',
 REUSE_ID='26';

SECTION_NUMBER 1
 '@BASEBOARD_FAB2_LIB.BASEBOARD_FAB2(SCH_1):PAGE231_I202@MSTR_DISCRETE.CAP(CHIPS)':
 C_PATH='@baseboard_fab2_lib.baseboard_fab2(sch_1):page231_i202@mstr_discrete.ca~
p(chips)',
 P_PATH='@baseboard_fab2_lib.baseboard_fab2(sch_1):page231_i202@mstr_discrete.ca~
p(chips)',
 PATH='I202',
 DRAWING='@BASEBOARD_FAB2_LIB.BASEBOARD_FAB2(SCH_1):PAGE231',
 CONFIG='078.47521.08BD',
 TOLERANCE='10%',
 SEC_TYPE='0603',
 MATERIAL='X6S',
 BOM_COST='PVPP_KLM_VR',
 PHYS_PAGE='231',
 REUSE_ID='26',
 XY='(-5375,2625)',
 ROT='0',
 VER='1',
 VALUE='4.7UF',
 PACK_TYPE='0603',
 PART_NUMBER='E15431-003',
 LOCATION='C3T11',
 ROOM='PVPP_KLM_VR',
 SEC='1',
 CDS_LIB='mstr_discrete',
 CDS_PART_NAME='CAP_0603-4.7UF,6.3V,10%,X6S,E1A',
 VOLTAGE='6.3V',
 PRIM_FILE='./archive_libs/mstr_discrete/cap/chips/chips.prt';

PART_NAME
 C3T12 'CAP_0805-10UF,16V,10%,X6S,C953A':;

SECTION_NUMBER 1
 '@BASEBOARD_FAB2_LIB.BASEBOARD_FAB2(SCH_1):PAGE231_I215@MSTR_DISCRETE.CAP(CHIPS)':
 C_PATH='@baseboard_fab2_lib.baseboard_fab2(sch_1):page231_i215@mstr_discrete.ca~
p(chips)',
 P_PATH='@baseboard_fab2_lib.baseboard_fab2(sch_1):page231_i215@mstr_discrete.ca~
p(chips)',
 PATH='I215',
 DRAWING='@BASEBOARD_FAB2_LIB.BASEBOARD_FAB2(SCH_1):PAGE231',
 TOLERANCE='10%',
 SEC_TYPE='0805',
 MATERIAL='X6S',
 PHYS_PAGE='231',
 XY='(-5075,4375)',
 ROT='0',
 VER='1',
 VALUE='10UF',
 PACK_TYPE='0805',
 PART_NUMBER='C95333-007',
 LOCATION='C3T12',
 SEC='1',
 CDS_LIB='mstr_discrete',
 CDS_PART_NAME='CAP_0805-10UF,16V,10%,X6S,C953A',
 VOLTAGE='16V',
 PRIM_FILE='./archive_libs/mstr_discrete/cap/chips/chips.prt';

PART_NAME
 C3T13 'CAPP_3018-68UF,16V,20%,TANT,72A':;

SECTION_NUMBER 1
 '@BASEBOARD_FAB2_LIB.BASEBOARD_FAB2(SCH_1):PAGE195_I104@MSTR_DISCRETE.CAPP(CHIPS)':
 C_PATH='@baseboard_fab2_lib.baseboard_fab2(sch_1):page195_i104@mstr_discrete.ca~
pp(chips)',
 P_PATH='@baseboard_fab2_lib.baseboard_fab2(sch_1):page195_i104@mstr_discrete.ca~
pp(chips)',
 PATH='I104',
 DRAWING='@BASEBOARD_FAB2_LIB.BASEBOARD_FAB2(SCH_1):PAGE195',
 TOLERANCE='20%',
 SEC_TYPE='3018',
 MATERIAL='TANT',
 PHYS_PAGE='195',
 XY='(-5725,1950)',
 ROT='0',
 VER='1',
 VALUE='68UF',
 PACK_TYPE='3018',
 PART_NUMBER='724613-112',
 LOCATION='C3T13',
 SEC='1',
 CDS_LIB='mstr_discrete',
 CDS_PART_NAME='CAPP_3018-68UF,16V,20%,TANT,72A',
 VOLTAGE='16V',
 PRIM_FILE='./archive_libs/mstr_discrete/capp/chips/chips.prt';

PART_NAME
 C3T14 'CAP_0805-10UF,16V,10%,X6S,C953A':;

SECTION_NUMBER 1
 '@BASEBOARD_FAB2_LIB.BASEBOARD_FAB2(SCH_1):PAGE231_I211@MSTR_DISCRETE.CAP(CHIPS)':
 C_PATH='@baseboard_fab2_lib.baseboard_fab2(sch_1):page231_i211@mstr_discrete.ca~
p(chips)',
 P_PATH='@baseboard_fab2_lib.baseboard_fab2(sch_1):page231_i211@mstr_discrete.ca~
p(chips)',
 PATH='I211',
 DRAWING='@BASEBOARD_FAB2_LIB.BASEBOARD_FAB2(SCH_1):PAGE231',
 TOLERANCE='10%',
 SEC_TYPE='0805',
 MATERIAL='X6S',
 PHYS_PAGE='231',
 XY='(-5425,4375)',
 ROT='0',
 VER='1',
 VALUE='10UF',
 PACK_TYPE='0805',
 PART_NUMBER='C95333-007',
 LOCATION='C3T14',
 SEC='1',
 CDS_LIB='mstr_discrete',
 CDS_PART_NAME='CAP_0805-10UF,16V,10%,X6S,C953A',
 VOLTAGE='16V',
 PRIM_FILE='./archive_libs/mstr_discrete/cap/chips/chips.prt';

PART_NAME
 C3T15 'CAPP_3018-68UF,16V,20%,TANT,72A':;

SECTION_NUMBER 1
 '@BASEBOARD_FAB2_LIB.BASEBOARD_FAB2(SCH_1):PAGE195_I106@MSTR_DISCRETE.CAPP(CHIPS)':
 C_PATH='@baseboard_fab2_lib.baseboard_fab2(sch_1):page195_i106@mstr_discrete.ca~
pp(chips)',
 P_PATH='@baseboard_fab2_lib.baseboard_fab2(sch_1):page195_i106@mstr_discrete.ca~
pp(chips)',
 PATH='I106',
 DRAWING='@BASEBOARD_FAB2_LIB.BASEBOARD_FAB2(SCH_1):PAGE195',
 TOLERANCE='20%',
 SEC_TYPE='3018',
 MATERIAL='TANT',
 PHYS_PAGE='195',
 XY='(-5275,1925)',
 ROT='0',
 VER='1',
 VALUE='68UF',
 PACK_TYPE='3018',
 PART_NUMBER='724613-112',
 LOCATION='C3T15',
 SEC='1',
 CDS_LIB='mstr_discrete',
 CDS_PART_NAME='CAPP_3018-68UF,16V,20%,TANT,72A',
 VOLTAGE='16V',
 PRIM_FILE='./archive_libs/mstr_discrete/capp/chips/chips.prt';

PART_NAME
 C3U1 'CAPP_3018-470UF,2.5V,20%,ALUM,A':
 GROUP='PWR_BULK_CAP',
 ROOM='VDDQ_ABC_PWR_VR';

SECTION_NUMBER 1
 '@BASEBOARD_FAB2_LIB.BASEBOARD_FAB2(SCH_1):PAGE217_I76@MSTR_DISCRETE.CAPP(CHIPS)':
 C_PATH='@baseboard_fab2_lib.baseboard_fab2(sch_1):page217_i76@mstr_discrete.cap~
p(chips)',
 P_PATH='@baseboard_fab2_lib.baseboard_fab2(sch_1):page217_i76@mstr_discrete.cap~
p(chips)',
 PATH='I76',
 DRAWING='@BASEBOARD_FAB2_LIB.BASEBOARD_FAB2(SCH_1):PAGE217',
 TOLERANCE='20%',
 SEC_TYPE='3018',
 MATERIAL='ALUM',
 PHYS_PAGE='217',
 XY='(3650,-400)',
 ROT='0',
 VER='1',
 VALUE='470UF',
 PACK_TYPE='3018',
 PART_NUMBER='699013-049',
 LOCATION='C3U1',
 ROOM='VDDQ_ABC_PWR_VR',
 GROUP='PWR_BULK_CAP',
 SEC='1',
 CDS_LIB='mstr_discrete',
 CDS_PART_NAME='CAPP_3018-470UF,2.5V,20%,ALUM,A',
 VOLTAGE='2.5V',
 PRIM_FILE='./archive_libs/mstr_discrete/capp/chips/chips.prt';

PART_NAME
 C3U2 'CAP_0805-10UF,16V,10%,X6S,C953A':
 ROOM='VDDQ_ABC_PWR_VR';

SECTION_NUMBER 1
 '@BASEBOARD_FAB2_LIB.BASEBOARD_FAB2(SCH_1):PAGE216_I45@MSTR_DISCRETE.CAP(CHIPS)':
 C_PATH='@baseboard_fab2_lib.baseboard_fab2(sch_1):page216_i45@mstr_discrete.cap~
(chips)',
 P_PATH='@baseboard_fab2_lib.baseboard_fab2(sch_1):page216_i45@mstr_discrete.cap~
(chips)',
 PATH='I45',
 DRAWING='@BASEBOARD_FAB2_LIB.BASEBOARD_FAB2(SCH_1):PAGE216',
 TOLERANCE='10%',
 SEC_TYPE='0805',
 MATERIAL='X6S',
 PHYS_PAGE='216',
 XY='(-2050,2525)',
 ROT='0',
 VER='1',
 VALUE='10UF',
 PACK_TYPE='0805',
 PART_NUMBER='C95333-007',
 LOCATION='C3U2',
 ROOM='VDDQ_ABC_PWR_VR',
 SEC='1',
 CDS_LIB='mstr_discrete',
 CDS_PART_NAME='CAP_0805-10UF,16V,10%,X6S,C953A',
 VOLTAGE='16V',
 PRIM_FILE='./archive_libs/mstr_discrete/cap/chips/chips.prt';

PART_NAME
 C3U3 'CAP_0805-10UF,16V,10%,X6S,C953A':
 ROOM='VDDQ_ABC_PWR_VR';

SECTION_NUMBER 1
 '@BASEBOARD_FAB2_LIB.BASEBOARD_FAB2(SCH_1):PAGE216_I46@MSTR_DISCRETE.CAP(CHIPS)':
 C_PATH='@baseboard_fab2_lib.baseboard_fab2(sch_1):page216_i46@mstr_discrete.cap~
(chips)',
 P_PATH='@baseboard_fab2_lib.baseboard_fab2(sch_1):page216_i46@mstr_discrete.cap~
(chips)',
 PATH='I46',
 DRAWING='@BASEBOARD_FAB2_LIB.BASEBOARD_FAB2(SCH_1):PAGE216',
 TOLERANCE='10%',
 SEC_TYPE='0805',
 MATERIAL='X6S',
 PHYS_PAGE='216',
 XY='(-1775,2525)',
 ROT='0',
 VER='1',
 VALUE='10UF',
 PACK_TYPE='0805',
 PART_NUMBER='C95333-007',
 LOCATION='C3U3',
 ROOM='VDDQ_ABC_PWR_VR',
 SEC='1',
 CDS_LIB='mstr_discrete',
 CDS_PART_NAME='CAP_0805-10UF,16V,10%,X6S,C953A',
 VOLTAGE='16V',
 PRIM_FILE='./archive_libs/mstr_discrete/cap/chips/chips.prt';

PART_NAME
 C3U4 'CAP_0805-10UF,16V,10%,X6S,C953A':
 ROOM='VDDQ_ABC_PWR_VR';

SECTION_NUMBER 1
 '@BASEBOARD_FAB2_LIB.BASEBOARD_FAB2(SCH_1):PAGE216_I47@MSTR_DISCRETE.CAP(CHIPS)':
 C_PATH='@baseboard_fab2_lib.baseboard_fab2(sch_1):page216_i47@mstr_discrete.cap~
(chips)',
 P_PATH='@baseboard_fab2_lib.baseboard_fab2(sch_1):page216_i47@mstr_discrete.cap~
(chips)',
 PATH='I47',
 DRAWING='@BASEBOARD_FAB2_LIB.BASEBOARD_FAB2(SCH_1):PAGE216',
 TOLERANCE='10%',
 SEC_TYPE='0805',
 MATERIAL='X6S',
 PHYS_PAGE='216',
 XY='(-1525,2525)',
 ROT='0',
 VER='1',
 VALUE='10UF',
 PACK_TYPE='0805',
 PART_NUMBER='C95333-007',
 LOCATION='C3U4',
 ROOM='VDDQ_ABC_PWR_VR',
 SEC='1',
 CDS_LIB='mstr_discrete',
 CDS_PART_NAME='CAP_0805-10UF,16V,10%,X6S,C953A',
 VOLTAGE='16V',
 PRIM_FILE='./archive_libs/mstr_discrete/cap/chips/chips.prt';

PART_NAME
 C3U5 'CAPP_3018-470UF,2.5V,20%,ALUM,A':
 GROUP='PWR_BULK_CAP',
 ROOM='VDDQ_ABC_PWR_VR';

SECTION_NUMBER 1
 '@BASEBOARD_FAB2_LIB.BASEBOARD_FAB2(SCH_1):PAGE217_I77@MSTR_DISCRETE.CAPP(CHIPS)':
 C_PATH='@baseboard_fab2_lib.baseboard_fab2(sch_1):page217_i77@mstr_discrete.cap~
p(chips)',
 P_PATH='@baseboard_fab2_lib.baseboard_fab2(sch_1):page217_i77@mstr_discrete.cap~
p(chips)',
 PATH='I77',
 DRAWING='@BASEBOARD_FAB2_LIB.BASEBOARD_FAB2(SCH_1):PAGE217',
 TOLERANCE='20%',
 SEC_TYPE='3018',
 MATERIAL='ALUM',
 PHYS_PAGE='217',
 XY='(3950,-400)',
 ROT='0',
 VER='1',
 VALUE='470UF',
 PACK_TYPE='3018',
 PART_NUMBER='699013-049',
 LOCATION='C3U5',
 ROOM='VDDQ_ABC_PWR_VR',
 GROUP='PWR_BULK_CAP',
 SEC='1',
 CDS_LIB='mstr_discrete',
 CDS_PART_NAME='CAPP_3018-470UF,2.5V,20%,ALUM,A',
 VOLTAGE='2.5V',
 PRIM_FILE='./archive_libs/mstr_discrete/capp/chips/chips.prt';

PART_NAME
 C3U6 'CAP_0805-10UF,16V,10%,X6S,C953A':
 ROOM='VDDQ_ABC_PWR_VR';

SECTION_NUMBER 1
 '@BASEBOARD_FAB2_LIB.BASEBOARD_FAB2(SCH_1):PAGE216_I84@MSTR_DISCRETE.CAP(CHIPS)':
 C_PATH='@baseboard_fab2_lib.baseboard_fab2(sch_1):page216_i84@mstr_discrete.cap~
(chips)',
 P_PATH='@baseboard_fab2_lib.baseboard_fab2(sch_1):page216_i84@mstr_discrete.cap~
(chips)',
 PATH='I84',
 DRAWING='@BASEBOARD_FAB2_LIB.BASEBOARD_FAB2(SCH_1):PAGE216',
 TOLERANCE='10%',
 SEC_TYPE='0805',
 MATERIAL='X6S',
 PHYS_PAGE='216',
 XY='(-2050,175)',
 ROT='0',
 VER='1',
 VALUE='10UF',
 PACK_TYPE='0805',
 PART_NUMBER='C95333-007',
 LOCATION='C3U6',
 ROOM='VDDQ_ABC_PWR_VR',
 SEC='1',
 CDS_LIB='mstr_discrete',
 CDS_PART_NAME='CAP_0805-10UF,16V,10%,X6S,C953A',
 VOLTAGE='16V',
 PRIM_FILE='./archive_libs/mstr_discrete/cap/chips/chips.prt';

PART_NAME
 C3U7 'CAP_0805-10UF,16V,10%,X6S,C953A':
 ROOM='VDDQ_ABC_PWR_VR';

SECTION_NUMBER 1
 '@BASEBOARD_FAB2_LIB.BASEBOARD_FAB2(SCH_1):PAGE216_I81@MSTR_DISCRETE.CAP(CHIPS)':
 C_PATH='@baseboard_fab2_lib.baseboard_fab2(sch_1):page216_i81@mstr_discrete.cap~
(chips)',
 P_PATH='@baseboard_fab2_lib.baseboard_fab2(sch_1):page216_i81@mstr_discrete.cap~
(chips)',
 PATH='I81',
 DRAWING='@BASEBOARD_FAB2_LIB.BASEBOARD_FAB2(SCH_1):PAGE216',
 TOLERANCE='10%',
 SEC_TYPE='0805',
 MATERIAL='X6S',
 PHYS_PAGE='216',
 XY='(-1800,175)',
 ROT='0',
 VER='1',
 VALUE='10UF',
 PACK_TYPE='0805',
 PART_NUMBER='C95333-007',
 LOCATION='C3U7',
 ROOM='VDDQ_ABC_PWR_VR',
 SEC='1',
 CDS_LIB='mstr_discrete',
 CDS_PART_NAME='CAP_0805-10UF,16V,10%,X6S,C953A',
 VOLTAGE='16V',
 PRIM_FILE='./archive_libs/mstr_discrete/cap/chips/chips.prt';

PART_NAME
 C3U8 'CAPP_3018-470UF,2.5V,20%,ALUM,A':
 GROUP='PWR_BULK_CAP',
 ROOM='VDDQ_ABC_PWR_VR';

SECTION_NUMBER 1
 '@BASEBOARD_FAB2_LIB.BASEBOARD_FAB2(SCH_1):PAGE217_I78@MSTR_DISCRETE.CAPP(CHIPS)':
 C_PATH='@baseboard_fab2_lib.baseboard_fab2(sch_1):page217_i78@mstr_discrete.cap~
p(chips)',
 P_PATH='@baseboard_fab2_lib.baseboard_fab2(sch_1):page217_i78@mstr_discrete.cap~
p(chips)',
 PATH='I78',
 DRAWING='@BASEBOARD_FAB2_LIB.BASEBOARD_FAB2(SCH_1):PAGE217',
 TOLERANCE='20%',
 SEC_TYPE='3018',
 MATERIAL='ALUM',
 PHYS_PAGE='217',
 XY='(4250,-400)',
 ROT='0',
 VER='1',
 VALUE='470UF',
 PACK_TYPE='3018',
 PART_NUMBER='699013-049',
 LOCATION='C3U8',
 ROOM='VDDQ_ABC_PWR_VR',
 GROUP='PWR_BULK_CAP',
 SEC='1',
 CDS_LIB='mstr_discrete',
 CDS_PART_NAME='CAPP_3018-470UF,2.5V,20%,ALUM,A',
 VOLTAGE='2.5V',
 PRIM_FILE='./archive_libs/mstr_discrete/capp/chips/chips.prt';

PART_NAME
 C3U9 'CAP_0805-10UF,16V,10%,X6S,C953A':
 ROOM='VDDQ_ABC_PWR_VR';

SECTION_NUMBER 1
 '@BASEBOARD_FAB2_LIB.BASEBOARD_FAB2(SCH_1):PAGE216_I80@MSTR_DISCRETE.CAP(CHIPS)':
 C_PATH='@baseboard_fab2_lib.baseboard_fab2(sch_1):page216_i80@mstr_discrete.cap~
(chips)',
 P_PATH='@baseboard_fab2_lib.baseboard_fab2(sch_1):page216_i80@mstr_discrete.cap~
(chips)',
 PATH='I80',
 DRAWING='@BASEBOARD_FAB2_LIB.BASEBOARD_FAB2(SCH_1):PAGE216',
 TOLERANCE='10%',
 SEC_TYPE='0805',
 MATERIAL='X6S',
 PHYS_PAGE='216',
 XY='(-1550,175)',
 ROT='0',
 VER='1',
 VALUE='10UF',
 PACK_TYPE='0805',
 PART_NUMBER='C95333-007',
 LOCATION='C3U9',
 ROOM='VDDQ_ABC_PWR_VR',
 SEC='1',
 CDS_LIB='mstr_discrete',
 CDS_PART_NAME='CAP_0805-10UF,16V,10%,X6S,C953A',
 VOLTAGE='16V',
 PRIM_FILE='./archive_libs/mstr_discrete/cap/chips/chips.prt';

PART_NAME
 C3W1 'CAP_0402-1.0UF,6.3V,10%,EMPTY,A':;

SECTION_NUMBER 1
 '@BASEBOARD_FAB2_LIB.BASEBOARD_FAB2(SCH_1):PAGE114_I193@MSTR_DISCRETE.CAP(CHIPS)':
 C_PATH='@baseboard_fab2_lib.baseboard_fab2(sch_1):page114_i193@mstr_discrete.ca~
p(chips)',
 P_PATH='@baseboard_fab2_lib.baseboard_fab2(sch_1):page114_i193@mstr_discrete.ca~
p(chips)',
 PATH='I193',
 DRAWING='@BASEBOARD_FAB2_LIB.BASEBOARD_FAB2(SCH_1):PAGE114',
 TOLERANCE='10%',
 SEC_TYPE='0402',
 MATERIAL='EMPTY',
 PHYS_PAGE='114',
 XY='(-2850,2750)',
 ROT='0',
 VER='1',
 VALUE='1.0UF',
 PACK_TYPE='0402',
 PART_NUMBER='D97712-004',
 LOCATION='C3W1',
 SEC='1',
 CDS_LIB='mstr_discrete',
 CDS_PART_NAME='CAP_0402-1.0UF,6.3V,10%,EMPTY,A',
 VOLTAGE='6.3V',
 PRIM_FILE='./archive_libs/mstr_discrete/cap/chips/chips.prt';

PART_NAME
 C3W2 'CAP_A_0402V-0.1UF,16V,10%,X7R,A':
 ROOM='PROC_SIDEBAND';

SECTION_NUMBER 1
 '@BASEBOARD_FAB2_LIB.BASEBOARD_FAB2(SCH_1):PAGE249_I57@DEV_DISCRETE.CAP_A(CHIPS)':
 C_PATH='@baseboard_fab2_lib.baseboard_fab2(sch_1):page249_i57@dev_discrete.cap_~
a(chips)',
 P_PATH='@baseboard_fab2_lib.baseboard_fab2(sch_1):page249_i57@dev_discrete.cap_~
a(chips)',
 PATH='I57',
 DRAWING='@BASEBOARD_FAB2_LIB.BASEBOARD_FAB2(SCH_1):PAGE249',
 TOLERANCE='10%',
 SEC_TYPE='0402V',
 MATERIAL='X7R',
 BOM_COST='PROC_SIDEBAND',
 PHYS_PAGE='249',
 XY='(-5950,1950)',
 ROT='0',
 VER='1',
 VALUE='0.1UF',
 PACK_TYPE='0402V',
 PART_NUMBER='A36096-030',
 LOCATION='C3W2',
 ROOM='PROC_SIDEBAND',
 SEC='1',
 CDS_LIB='dev_discrete',
 CDS_PART_NAME='CAP_A_0402V-0.1UF,16V,10%,X7R,A',
 VOLTAGE='16V',
 PRIM_FILE='./archive_libs/discrete/cap_a/chips/chips.prt';

PART_NAME
 C3W3 'CAP_A_0603V-22.0UF,4V,20%,X6S,A':
 GROUP='PWR_MCP_CAP',
 ROOM='PVCCIN_CPU0_DECAP_VR';

SECTION_NUMBER 1
 '@BASEBOARD_FAB2_LIB.BASEBOARD_FAB2(SCH_1):PAGE76_I256@DEV_DISCRETE.CAP_A(CHIPS)':
 C_PATH='@baseboard_fab2_lib.baseboard_fab2(sch_1):page76_i256@dev_discrete.cap_~
a(chips)',
 P_PATH='@baseboard_fab2_lib.baseboard_fab2(sch_1):page76_i256@dev_discrete.cap_~
a(chips)',
 PATH='I256',
 DRAWING='@BASEBOARD_FAB2_LIB.BASEBOARD_FAB2(SCH_1):PAGE76',
 TOLERANCE='20%',
 SEC_TYPE='0603V',
 MATERIAL='X6S',
 BOM_COST='PROC_SOCKET',
 PHYS_PAGE='76',
 XY='(-1400,3050)',
 ROT='0',
 VER='1',
 VALUE='22.0UF',
 PACK_TYPE='0603V',
 PART_NUMBER='E15431-004',
 LOCATION='C3W3',
 ROOM='PVCCIN_CPU0_DECAP_VR',
 GROUP='PWR_MCP_CAP',
 SEC='1',
 CDS_LIB='dev_discrete',
 CDS_PART_NAME='CAP_A_0603V-22.0UF,4V,20%,X6S,A',
 VOLTAGE='4V',
 PRIM_FILE='./archive_libs/discrete/cap_a/chips/chips.prt';

PART_NAME
 C3W4 'CAP_A_0603V-22.0UF,4V,20%,X6S,A':
 GROUP='PWR_MCP_CAP',
 ROOM='PVCCIN_CPU0_DECAP_VR';

SECTION_NUMBER 1
 '@BASEBOARD_FAB2_LIB.BASEBOARD_FAB2(SCH_1):PAGE76_I254@DEV_DISCRETE.CAP_A(CHIPS)':
 C_PATH='@baseboard_fab2_lib.baseboard_fab2(sch_1):page76_i254@dev_discrete.cap_~
a(chips)',
 P_PATH='@baseboard_fab2_lib.baseboard_fab2(sch_1):page76_i254@dev_discrete.cap_~
a(chips)',
 PATH='I254',
 DRAWING='@BASEBOARD_FAB2_LIB.BASEBOARD_FAB2(SCH_1):PAGE76',
 TOLERANCE='20%',
 SEC_TYPE='0603V',
 MATERIAL='X6S',
 BOM_COST='PROC_SOCKET',
 PHYS_PAGE='76',
 XY='(-1100,3050)',
 ROT='0',
 VER='1',
 VALUE='22.0UF',
 PACK_TYPE='0603V',
 PART_NUMBER='E15431-004',
 LOCATION='C3W4',
 ROOM='PVCCIN_CPU0_DECAP_VR',
 GROUP='PWR_MCP_CAP',
 SEC='1',
 CDS_LIB='dev_discrete',
 CDS_PART_NAME='CAP_A_0603V-22.0UF,4V,20%,X6S,A',
 VOLTAGE='4V',
 PRIM_FILE='./archive_libs/discrete/cap_a/chips/chips.prt';

PART_NAME
 C4A1 'CAP_0805LF-22UF,4V,20%,X6S,C95A':
 GROUP='PWR_MLCC_CAP',
 ROOM='VTT_DEF_PWR_VR';

SECTION_NUMBER 1
 '@BASEBOARD_FAB2_LIB.BASEBOARD_FAB2(SCH_1):PAGE222_I28@MSTR_DISCRETE.CAP(CHIPS)':
 C_PATH='@baseboard_fab2_lib.baseboard_fab2(sch_1):page222_i28@mstr_discrete.cap~
(chips)',
 P_PATH='@baseboard_fab2_lib.baseboard_fab2(sch_1):page222_i28@mstr_discrete.cap~
(chips)',
 PATH='I28',
 DRAWING='@BASEBOARD_FAB2_LIB.BASEBOARD_FAB2(SCH_1):PAGE222',
 TOLERANCE='20%',
 SEC_TYPE='0805LF',
 MATERIAL='X6S',
 BOM_COST='MEM_VRD_VTT_DEF',
 PHYS_PAGE='222',
 XY='(3200,575)',
 ROT='0',
 VER='1',
 VALUE='22UF',
 PACK_TYPE='0805LF',
 PART_NUMBER='C95333-002',
 LOCATION='C4A1',
 ROOM='VTT_DEF_PWR_VR',
 GROUP='PWR_MLCC_CAP',
 SEC='1',
 CDS_LIB='mstr_discrete',
 CDS_PART_NAME='CAP_0805LF-22UF,4V,20%,X6S,C95A',
 VOLTAGE='4V',
 PRIM_FILE='./archive_libs/mstr_discrete/cap/chips/chips.prt';

PART_NAME
 C4A2 'CAP_0402LF-1000PF,50V,10%,EMPTA':
 ROOM='VTT_DEF_PWR_VR';

SECTION_NUMBER 1
 '@BASEBOARD_FAB2_LIB.BASEBOARD_FAB2(SCH_1):PAGE222_I2@MSTR_DISCRETE.CAP(CHIPS)':
 C_PATH='@baseboard_fab2_lib.baseboard_fab2(sch_1):page222_i2@mstr_discrete.cap(~
chips)',
 P_PATH='@baseboard_fab2_lib.baseboard_fab2(sch_1):page222_i2@mstr_discrete.cap(~
chips)',
 PATH='I2',
 DRAWING='@BASEBOARD_FAB2_LIB.BASEBOARD_FAB2(SCH_1):PAGE222',
 TOLERANCE='10%',
 SEC_TYPE='0402LF',
 MATERIAL='EMPTY',
 BOM_COST='MEM_VRD_VTT_DEF',
 PHYS_PAGE='222',
 XY='(-1150,-850)',
 ROT='2',
 VER='1',
 VALUE='1000PF',
 PACK_TYPE='0402LF',
 PART_NUMBER='A36096-046',
 LOCATION='C4A2',
 ROOM='VTT_DEF_PWR_VR',
 SEC='1',
 CDS_LIB='mstr_discrete',
 CDS_PART_NAME='CAP_0402LF-1000PF,50V,10%,EMPTA',
 VOLTAGE='50V',
 PRIM_FILE='./archive_libs/mstr_discrete/cap/chips/chips.prt';

PART_NAME
 C4A3 'CAP_0402LF-1000PF,50V,10%,X7R,A':
 ROOM='VTT_KLM_PWR_VR';

SECTION_NUMBER 1
 '@BASEBOARD_FAB2_LIB.BASEBOARD_FAB2(SCH_1):PAGE230_I23@MSTR_DISCRETE.CAP(CHIPS)':
 C_PATH='@baseboard_fab2_lib.baseboard_fab2(sch_1):page230_i23@mstr_discrete.cap~
(chips)',
 P_PATH='@baseboard_fab2_lib.baseboard_fab2(sch_1):page230_i23@mstr_discrete.cap~
(chips)',
 PATH='I23',
 DRAWING='@BASEBOARD_FAB2_LIB.BASEBOARD_FAB2(SCH_1):PAGE230',
 TOLERANCE='10%',
 SEC_TYPE='0402LF',
 MATERIAL='X7R',
 BOM_COST='MEM_VRD_VTT_KLM',
 PHYS_PAGE='230',
 XY='(2200,900)',
 ROT='2',
 VER='1',
 VALUE='1000PF',
 PACK_TYPE='0402LF',
 PART_NUMBER='A36096-046',
 LOCATION='C4A3',
 ROOM='VTT_KLM_PWR_VR',
 SEC='1',
 CDS_LIB='mstr_discrete',
 CDS_PART_NAME='CAP_0402LF-1000PF,50V,10%,X7R,A',
 VOLTAGE='50V',
 PRIM_FILE='./archive_libs/mstr_discrete/cap/chips/chips.prt';

PART_NAME
 C4A4 'CAP_0805-10UF,16V,10%,X7R,G106A':
 ROOM='PVDDQ_DEF_PWR_VR';

SECTION_NUMBER 1
 '@BASEBOARD_FAB2_LIB.BASEBOARD_FAB2(SCH_1):PAGE197_I81@MSTR_DISCRETE.CAP(CHIPS)':
 C_PATH='@baseboard_fab2_lib.baseboard_fab2(sch_1):page197_i81@mstr_discrete.cap~
(chips)',
 P_PATH='@baseboard_fab2_lib.baseboard_fab2(sch_1):page197_i81@mstr_discrete.cap~
(chips)',
 PATH='I81',
 DRAWING='@BASEBOARD_FAB2_LIB.BASEBOARD_FAB2(SCH_1):PAGE197',
 TOLERANCE='10%',
 MATERIAL='X7R',
 PHYS_PAGE='197',
 XY='(2175,3750)',
 ROT='0',
 VER='1',
 VALUE='10UF',
 PACK_TYPE='0805',
 PART_NUMBER='G10601-001',
 LOCATION='C4A4',
 ROOM='PVDDQ_DEF_PWR_VR',
 CDS_LIB='mstr_discrete',
 CDS_PART_NAME='CAP_0805-10UF,16V,10%,X7R,G106A',
 VOLTAGE='16V',
 PRIM_FILE='./archive_libs/mstr_discrete/cap/chips/chips.prt';

PART_NAME
 C4A5 'CAP_A_0402V-0.01UF,25V,10%,X7RA':
 ROOM='DDR4_CH_F1';

SECTION_NUMBER 1
 '@BASEBOARD_FAB2_LIB.BASEBOARD_FAB2(SCH_1):PAGE54_I179@DEV_DISCRETE.CAP_A(CHIPS)':
 C_PATH='@baseboard_fab2_lib.baseboard_fab2(sch_1):page54_i179@dev_discrete.cap_~
a(chips)',
 P_PATH='@baseboard_fab2_lib.baseboard_fab2(sch_1):page54_i179@dev_discrete.cap_~
a(chips)',
 PATH='I179',
 DRAWING='@BASEBOARD_FAB2_LIB.BASEBOARD_FAB2(SCH_1):PAGE54',
 TOLERANCE='10%',
 SEC_TYPE='0402V',
 MATERIAL='X7R',
 BOM_COST='MEM',
 PHYS_PAGE='54',
 XY='(-4600,1400)',
 ROT='2',
 VER='1',
 VALUE='0.01UF',
 PACK_TYPE='0402V',
 PART_NUMBER='A36096-045',
 LOCATION='C4A5',
 ROOM='DDR4_CH_F1',
 SEC='1',
 CDS_LIB='dev_discrete',
 CDS_PART_NAME='CAP_A_0402V-0.01UF,25V,10%,X7RA',
 VOLTAGE='25V',
 PRIM_FILE='./archive_libs/discrete/cap_a/chips/chips.prt';

PART_NAME
 C4A6 'CAP_0402LF-1000PF,50V,10%,EMPTA':
 ROOM='VTT_KLM_PWR_VR';

SECTION_NUMBER 1
 '@BASEBOARD_FAB2_LIB.BASEBOARD_FAB2(SCH_1):PAGE230_I2@MSTR_DISCRETE.CAP(CHIPS)':
 C_PATH='@baseboard_fab2_lib.baseboard_fab2(sch_1):page230_i2@mstr_discrete.cap(~
chips)',
 P_PATH='@baseboard_fab2_lib.baseboard_fab2(sch_1):page230_i2@mstr_discrete.cap(~
chips)',
 PATH='I2',
 DRAWING='@BASEBOARD_FAB2_LIB.BASEBOARD_FAB2(SCH_1):PAGE230',
 TOLERANCE='10%',
 SEC_TYPE='0402LF',
 MATERIAL='EMPTY',
 BOM_COST='MEM_VRD_VTT_KLM',
 PHYS_PAGE='230',
 XY='(-2025,-1125)',
 ROT='2',
 VER='1',
 VALUE='1000PF',
 PACK_TYPE='0402LF',
 PART_NUMBER='A36096-046',
 LOCATION='C4A6',
 ROOM='VTT_KLM_PWR_VR',
 SEC='1',
 CDS_LIB='mstr_discrete',
 CDS_PART_NAME='CAP_0402LF-1000PF,50V,10%,EMPTA',
 VOLTAGE='50V',
 PRIM_FILE='./archive_libs/mstr_discrete/cap/chips/chips.prt';

PART_NAME
 C4A7 'CAP_0603-4.7UF,6.3V,10%,X6S,E1A':
 ROOM='VTT_KLM_PWR_VR';

SECTION_NUMBER 1
 '@BASEBOARD_FAB2_LIB.BASEBOARD_FAB2(SCH_1):PAGE230_I10@MSTR_DISCRETE.CAP(CHIPS)':
 C_PATH='@baseboard_fab2_lib.baseboard_fab2(sch_1):page230_i10@mstr_discrete.cap~
(chips)',
 P_PATH='@baseboard_fab2_lib.baseboard_fab2(sch_1):page230_i10@mstr_discrete.cap~
(chips)',
 PATH='I10',
 DRAWING='@BASEBOARD_FAB2_LIB.BASEBOARD_FAB2(SCH_1):PAGE230',
 TOLERANCE='10%',
 SEC_TYPE='0603',
 MATERIAL='X6S',
 PHYS_PAGE='230',
 XY='(-1300,225)',
 ROT='0',
 VER='1',
 VALUE='4.7UF',
 PACK_TYPE='0603',
 PART_NUMBER='E15431-003',
 LOCATION='C4A7',
 ROOM='VTT_KLM_PWR_VR',
 SEC='1',
 CDS_LIB='mstr_discrete',
 CDS_PART_NAME='CAP_0603-4.7UF,6.3V,10%,X6S,E1A',
 VOLTAGE='6.3V',
 PRIM_FILE='./archive_libs/mstr_discrete/cap/chips/chips.prt';

PART_NAME
 C4A8 'CAP_0402-1.0UF,16V,10%,X6S,D97A':
 ROOM='VTT_KLM_PWR_VR';

SECTION_NUMBER 1
 '@BASEBOARD_FAB2_LIB.BASEBOARD_FAB2(SCH_1):PAGE230_I12@MSTR_DISCRETE.CAP(CHIPS)':
 C_PATH='@baseboard_fab2_lib.baseboard_fab2(sch_1):page230_i12@mstr_discrete.cap~
(chips)',
 P_PATH='@baseboard_fab2_lib.baseboard_fab2(sch_1):page230_i12@mstr_discrete.cap~
(chips)',
 PATH='I12',
 DRAWING='@BASEBOARD_FAB2_LIB.BASEBOARD_FAB2(SCH_1):PAGE230',
 TOLERANCE='10%',
 SEC_TYPE='0402',
 MATERIAL='X6S',
 BOM_COST='MEM_VRD_VTT_KLM',
 PHYS_PAGE='230',
 XY='(-1200,775)',
 ROT='0',
 VER='1',
 VALUE='1.0UF',
 PACK_TYPE='0402',
 PART_NUMBER='D97712-011',
 LOCATION='C4A8',
 ROOM='VTT_KLM_PWR_VR',
 SEC='1',
 CDS_LIB='mstr_discrete',
 CDS_PART_NAME='CAP_0402-1.0UF,16V,10%,X6S,D97A',
 VOLTAGE='16V',
 PRIM_FILE='./archive_libs/mstr_discrete/cap/chips/chips.prt';

PART_NAME
 C4A9 'CAP_0402-1.0UF,16V,10%,X6S,D97A':
 ROOM='VTT_DEF_PWR_VR';

SECTION_NUMBER 1
 '@BASEBOARD_FAB2_LIB.BASEBOARD_FAB2(SCH_1):PAGE222_I20@MSTR_DISCRETE.CAP(CHIPS)':
 C_PATH='@baseboard_fab2_lib.baseboard_fab2(sch_1):page222_i20@mstr_discrete.cap~
(chips)',
 P_PATH='@baseboard_fab2_lib.baseboard_fab2(sch_1):page222_i20@mstr_discrete.cap~
(chips)',
 PATH='I20',
 DRAWING='@BASEBOARD_FAB2_LIB.BASEBOARD_FAB2(SCH_1):PAGE222',
 TOLERANCE='10%',
 SEC_TYPE='0402',
 MATERIAL='X6S',
 BOM_COST='MEM_VRD_VTT_DEF',
 PHYS_PAGE='222',
 XY='(1625,400)',
 ROT='0',
 VER='1',
 VALUE='1.0UF',
 PACK_TYPE='0402',
 PART_NUMBER='D97712-011',
 LOCATION='C4A9',
 ROOM='VTT_DEF_PWR_VR',
 SEC='1',
 CDS_LIB='mstr_discrete',
 CDS_PART_NAME='CAP_0402-1.0UF,16V,10%,X6S,D97A',
 VOLTAGE='16V',
 PRIM_FILE='./archive_libs/mstr_discrete/cap/chips/chips.prt';

PART_NAME
 C4A10 'CAP_0402-1.0UF,16V,10%,X6S,D97A':
 ROOM='VTT_DEF_PWR_VR';

SECTION_NUMBER 1
 '@BASEBOARD_FAB2_LIB.BASEBOARD_FAB2(SCH_1):PAGE222_I12@MSTR_DISCRETE.CAP(CHIPS)':
 C_PATH='@baseboard_fab2_lib.baseboard_fab2(sch_1):page222_i12@mstr_discrete.cap~
(chips)',
 P_PATH='@baseboard_fab2_lib.baseboard_fab2(sch_1):page222_i12@mstr_discrete.cap~
(chips)',
 PATH='I12',
 DRAWING='@BASEBOARD_FAB2_LIB.BASEBOARD_FAB2(SCH_1):PAGE222',
 TOLERANCE='10%',
 SEC_TYPE='0402',
 MATERIAL='X6S',
 BOM_COST='MEM_VRD_VTT_DEF',
 PHYS_PAGE='222',
 XY='(-325,1050)',
 ROT='0',
 VER='1',
 VALUE='1.0UF',
 PACK_TYPE='0402',
 PART_NUMBER='D97712-011',
 LOCATION='C4A10',
 ROOM='VTT_DEF_PWR_VR',
 SEC='1',
 CDS_LIB='mstr_discrete',
 CDS_PART_NAME='CAP_0402-1.0UF,16V,10%,X6S,D97A',
 VOLTAGE='16V',
 PRIM_FILE='./archive_libs/mstr_discrete/cap/chips/chips.prt';

PART_NAME
 C4A11 'CAP_0603-4.7UF,6.3V,10%,X6S,E1A':
 ROOM='VTT_DEF_PWR_VR';

SECTION_NUMBER 1
 '@BASEBOARD_FAB2_LIB.BASEBOARD_FAB2(SCH_1):PAGE222_I9@MSTR_DISCRETE.CAP(CHIPS)':
 C_PATH='@baseboard_fab2_lib.baseboard_fab2(sch_1):page222_i9@mstr_discrete.cap(~
chips)',
 P_PATH='@baseboard_fab2_lib.baseboard_fab2(sch_1):page222_i9@mstr_discrete.cap(~
chips)',
 PATH='I9',
 DRAWING='@BASEBOARD_FAB2_LIB.BASEBOARD_FAB2(SCH_1):PAGE222',
 TOLERANCE='10%',
 SEC_TYPE='0603',
 MATERIAL='X6S',
 PHYS_PAGE='222',
 XY='(-675,525)',
 ROT='0',
 VER='1',
 VALUE='4.7UF',
 PACK_TYPE='0603',
 PART_NUMBER='E15431-003',
 LOCATION='C4A11',
 ROOM='VTT_DEF_PWR_VR',
 SEC='1',
 CDS_LIB='mstr_discrete',
 CDS_PART_NAME='CAP_0603-4.7UF,6.3V,10%,X6S,E1A',
 VOLTAGE='6.3V',
 PRIM_FILE='./archive_libs/mstr_discrete/cap/chips/chips.prt';

PART_NAME
 C4A12 'CAP_0402LF-1000PF,50V,10%,X7R,A':
 ROOM='VTT_DEF_PWR_VR';

SECTION_NUMBER 1
 '@BASEBOARD_FAB2_LIB.BASEBOARD_FAB2(SCH_1):PAGE222_I22@MSTR_DISCRETE.CAP(CHIPS)':
 C_PATH='@baseboard_fab2_lib.baseboard_fab2(sch_1):page222_i22@mstr_discrete.cap~
(chips)',
 P_PATH='@baseboard_fab2_lib.baseboard_fab2(sch_1):page222_i22@mstr_discrete.cap~
(chips)',
 PATH='I22',
 DRAWING='@BASEBOARD_FAB2_LIB.BASEBOARD_FAB2(SCH_1):PAGE222',
 TOLERANCE='10%',
 SEC_TYPE='0402LF',
 MATERIAL='X7R',
 BOM_COST='MEM_VRD_VTT_DEF',
 PHYS_PAGE='222',
 XY='(3075,1175)',
 ROT='0',
 VER='1',
 VALUE='1000PF',
 PACK_TYPE='0402LF',
 PART_NUMBER='A36096-046',
 LOCATION='C4A12',
 ROOM='VTT_DEF_PWR_VR',
 SEC='1',
 CDS_LIB='mstr_discrete',
 CDS_PART_NAME='CAP_0402LF-1000PF,50V,10%,X7R,A',
 VOLTAGE='50V',
 PRIM_FILE='./archive_libs/mstr_discrete/cap/chips/chips.prt';

PART_NAME
 C4A13 'CAP_0805LF-22UF,4V,20%,X6S,C95A':
 GROUP='PWR_MLCC_CAP',
 ROOM='VTT_KLM_PWR_VR';

SECTION_NUMBER 1
 '@BASEBOARD_FAB2_LIB.BASEBOARD_FAB2(SCH_1):PAGE230_I20@MSTR_DISCRETE.CAP(CHIPS)':
 C_PATH='@baseboard_fab2_lib.baseboard_fab2(sch_1):page230_i20@mstr_discrete.cap~
(chips)',
 P_PATH='@baseboard_fab2_lib.baseboard_fab2(sch_1):page230_i20@mstr_discrete.cap~
(chips)',
 PATH='I20',
 DRAWING='@BASEBOARD_FAB2_LIB.BASEBOARD_FAB2(SCH_1):PAGE230',
 TOLERANCE='20%',
 SEC_TYPE='0805LF',
 MATERIAL='X6S',
 BOM_COST='MEM_VRD_VTT_KLM',
 PHYS_PAGE='230',
 XY='(2325,300)',
 ROT='0',
 VER='1',
 VALUE='22UF',
 PACK_TYPE='0805LF',
 PART_NUMBER='C95333-002',
 LOCATION='C4A13',
 ROOM='VTT_KLM_PWR_VR',
 GROUP='PWR_MLCC_CAP',
 SEC='1',
 CDS_LIB='mstr_discrete',
 CDS_PART_NAME='CAP_0805LF-22UF,4V,20%,X6S,C95A',
 VOLTAGE='4V',
 PRIM_FILE='./archive_libs/mstr_discrete/cap/chips/chips.prt';

PART_NAME
 C4A14 'CAP_0402-1.0UF,16V,10%,X6S,D97A':
 ROOM='VTT_KLM_PWR_VR';

SECTION_NUMBER 1
 '@BASEBOARD_FAB2_LIB.BASEBOARD_FAB2(SCH_1):PAGE230_I36@MSTR_DISCRETE.CAP(CHIPS)':
 C_PATH='@baseboard_fab2_lib.baseboard_fab2(sch_1):page230_i36@mstr_discrete.cap~
(chips)',
 P_PATH='@baseboard_fab2_lib.baseboard_fab2(sch_1):page230_i36@mstr_discrete.cap~
(chips)',
 PATH='I36',
 DRAWING='@BASEBOARD_FAB2_LIB.BASEBOARD_FAB2(SCH_1):PAGE230',
 TOLERANCE='10%',
 SEC_TYPE='0402',
 MATERIAL='X6S',
 BOM_COST='MEM_VRD_VTT_KLM',
 PHYS_PAGE='230',
 XY='(675,125)',
 ROT='0',
 VER='1',
 VALUE='1.0UF',
 PACK_TYPE='0402',
 PART_NUMBER='D97712-011',
 LOCATION='C4A14',
 ROOM='VTT_KLM_PWR_VR',
 SEC='1',
 CDS_LIB='mstr_discrete',
 CDS_PART_NAME='CAP_0402-1.0UF,16V,10%,X6S,D97A',
 VOLTAGE='16V',
 PRIM_FILE='./archive_libs/mstr_discrete/cap/chips/chips.prt';

PART_NAME
 C4A15 'CAP_0603LF-10UF,4V,20%,X6S,E15A':
 ROOM='VTT_KLM_PWR_VR';

SECTION_NUMBER 1
 '@BASEBOARD_FAB2_LIB.BASEBOARD_FAB2(SCH_1):PAGE230_I17@MSTR_DISCRETE.CAP(CHIPS)':
 C_PATH='@baseboard_fab2_lib.baseboard_fab2(sch_1):page230_i17@mstr_discrete.cap~
(chips)',
 P_PATH='@baseboard_fab2_lib.baseboard_fab2(sch_1):page230_i17@mstr_discrete.cap~
(chips)',
 PATH='I17',
 DRAWING='@BASEBOARD_FAB2_LIB.BASEBOARD_FAB2(SCH_1):PAGE230',
 TOLERANCE='20%',
 SEC_TYPE='0603LF',
 MATERIAL='X6S',
 BOM_COST='MEM_VRD_VTT_KLM',
 PHYS_PAGE='230',
 XY='(-1200,1650)',
 ROT='0',
 VER='1',
 VALUE='10UF',
 PACK_TYPE='0603LF',
 PART_NUMBER='E15431-001',
 LOCATION='C4A15',
 ROOM='VTT_KLM_PWR_VR',
 SEC='1',
 CDS_LIB='mstr_discrete',
 CDS_PART_NAME='CAP_0603LF-10UF,4V,20%,X6S,E15A',
 VOLTAGE='4V',
 PRIM_FILE='./archive_libs/mstr_discrete/cap/chips/chips.prt';

PART_NAME
 C4A16 'CAP_0402LF-3300PF,50V,10%,EMPTA':
 ROOM='PVPP_KLM_VR',
 REUSE_ID='26';

SECTION_NUMBER 1
 '@BASEBOARD_FAB2_LIB.BASEBOARD_FAB2(SCH_1):PAGE234_I163@MSTR_DISCRETE.CAP(CHIPS)':
 C_PATH='@baseboard_fab2_lib.baseboard_fab2(sch_1):page234_i163@mstr_discrete.ca~
p(chips)',
 P_PATH='@baseboard_fab2_lib.baseboard_fab2(sch_1):page234_i163@mstr_discrete.ca~
p(chips)',
 PATH='I163',
 DRAWING='@BASEBOARD_FAB2_LIB.BASEBOARD_FAB2(SCH_1):PAGE234',
 TOLERANCE='10%',
 MATERIAL='EMPTY',
 BOM_COST='PVPP_KLM_VR',
 PHYS_PAGE='234',
 REUSE_ID='26',
 XY='(-2575,3600)',
 ROT='0',
 VER='1',
 VALUE='3300PF',
 PACK_TYPE='0402LF',
 PART_NUMBER='A36096-091',
 LOCATION='C4A16',
 ROOM='PVPP_KLM_VR',
 CDS_LIB='mstr_discrete',
 CDS_PART_NAME='CAP_0402LF-3300PF,50V,10%,EMPTA',
 VOLTAGE='50V',
 PRIM_FILE='./archive_libs/mstr_discrete/cap/chips/chips.prt';

PART_NAME
 C4A17 'CAP_0805-10UF,16V,10%,X7R,G106A':
 ROOM='PVDDQ_DEF_PWR_VR';

SECTION_NUMBER 1
 '@BASEBOARD_FAB2_LIB.BASEBOARD_FAB2(SCH_1):PAGE197_I88@MSTR_DISCRETE.CAP(CHIPS)':
 C_PATH='@baseboard_fab2_lib.baseboard_fab2(sch_1):page197_i88@mstr_discrete.cap~
(chips)',
 P_PATH='@baseboard_fab2_lib.baseboard_fab2(sch_1):page197_i88@mstr_discrete.cap~
(chips)',
 PATH='I88',
 DRAWING='@BASEBOARD_FAB2_LIB.BASEBOARD_FAB2(SCH_1):PAGE197',
 TOLERANCE='10%',
 MATERIAL='X7R',
 PHYS_PAGE='197',
 XY='(2175,4400)',
 ROT='0',
 VER='1',
 VALUE='10UF',
 PACK_TYPE='0805',
 PART_NUMBER='G10601-001',
 LOCATION='C4A17',
 ROOM='PVDDQ_DEF_PWR_VR',
 CDS_LIB='mstr_discrete',
 CDS_PART_NAME='CAP_0805-10UF,16V,10%,X7R,G106A',
 VOLTAGE='16V',
 PRIM_FILE='./archive_libs/mstr_discrete/cap/chips/chips.prt';

PART_NAME
 C4A18 'CAP_A_0402V-0.01UF,25V,10%,X7RA':
 ROOM='DDR4_CH_E';

SECTION_NUMBER 1
 '@BASEBOARD_FAB2_LIB.BASEBOARD_FAB2(SCH_1):PAGE52_I3@DEV_DISCRETE.CAP_A(CHIPS)':
 C_PATH='@baseboard_fab2_lib.baseboard_fab2(sch_1):page52_i3@dev_discrete.cap_a(~
chips)',
 P_PATH='@baseboard_fab2_lib.baseboard_fab2(sch_1):page52_i3@dev_discrete.cap_a(~
chips)',
 PATH='I3',
 DRAWING='@BASEBOARD_FAB2_LIB.BASEBOARD_FAB2(SCH_1):PAGE52',
 TOLERANCE='10%',
 SEC_TYPE='0402V',
 MATERIAL='X7R',
 BOM_COST='MEM',
 PHYS_PAGE='52',
 XY='(-3025,1150)',
 ROT='2',
 VER='1',
 VALUE='0.01UF',
 PACK_TYPE='0402V',
 PART_NUMBER='A36096-045',
 LOCATION='C4A18',
 ROOM='DDR4_CH_E',
 SEC='1',
 CDS_LIB='dev_discrete',
 CDS_PART_NAME='CAP_A_0402V-0.01UF,25V,10%,X7RA',
 VOLTAGE='25V',
 PRIM_FILE='./archive_libs/discrete/cap_a/chips/chips.prt';

PART_NAME
 C4A19 'CAP_0805-10UF,16V,10%,X6S,C953A':;

SECTION_NUMBER 1
 '@BASEBOARD_FAB2_LIB.BASEBOARD_FAB2(SCH_1):PAGE234_I205@MSTR_DISCRETE.CAP(CHIPS)':
 C_PATH='@baseboard_fab2_lib.baseboard_fab2(sch_1):page234_i205@mstr_discrete.ca~
p(chips)',
 P_PATH='@baseboard_fab2_lib.baseboard_fab2(sch_1):page234_i205@mstr_discrete.ca~
p(chips)',
 PATH='I205',
 DRAWING='@BASEBOARD_FAB2_LIB.BASEBOARD_FAB2(SCH_1):PAGE234',
 TOLERANCE='10%',
 SEC_TYPE='0805',
 MATERIAL='X6S',
 PHYS_PAGE='234',
 XY='(-5475,4150)',
 ROT='0',
 VER='1',
 VALUE='10UF',
 PACK_TYPE='0805',
 PART_NUMBER='C95333-007',
 LOCATION='C4A19',
 SEC='1',
 CDS_LIB='mstr_discrete',
 CDS_PART_NAME='CAP_0805-10UF,16V,10%,X6S,C953A',
 VOLTAGE='16V',
 PRIM_FILE='./archive_libs/mstr_discrete/cap/chips/chips.prt';

PART_NAME
 C4A20 'CAP_A_0402V-0.1UF,16V,10%,X7R,A':;

SECTION_NUMBER 1
 '@BASEBOARD_FAB2_LIB.BASEBOARD_FAB2(SCH_1):PAGE234_I199@DEV_DISCRETE.CAP_A(CHIPS)':
 C_PATH='@baseboard_fab2_lib.baseboard_fab2(sch_1):page234_i199@dev_discrete.cap~
_a(chips)',
 P_PATH='@baseboard_fab2_lib.baseboard_fab2(sch_1):page234_i199@dev_discrete.cap~
_a(chips)',
 PATH='I199',
 DRAWING='@BASEBOARD_FAB2_LIB.BASEBOARD_FAB2(SCH_1):PAGE234',
 TOLERANCE='10%',
 SEC_TYPE='0402V',
 MATERIAL='X7R',
 PHYS_PAGE='234',
 XY='(-5175,3525)',
 ROT='0',
 VER='1',
 VALUE='0.1UF',
 PACK_TYPE='0402V',
 PART_NUMBER='A36096-030',
 LOCATION='C4A20',
 SEC='1',
 CDS_LIB='dev_discrete',
 CDS_PART_NAME='CAP_A_0402V-0.1UF,16V,10%,X7R,A',
 VOLTAGE='16V',
 PRIM_FILE='./archive_libs/discrete/cap_a/chips/chips.prt';

PART_NAME
 C4B1 'SC22U16V5MX-4-GP_SMD-BCG5-SC22A':;

SECTION_NUMBER 1
 '@BASEBOARD_FAB2_LIB.BASEBOARD_FAB2(SCH_1):PAGE234_I223@W_HDL.SC22U16V5MX-4-GP(CHIPS)':
 C_PATH='@baseboard_fab2_lib.baseboard_fab2(sch_1):page234_i223@w_hdl.\sc22u16v5~
mx-4-gp\(chips)',
 P_PATH='@baseboard_fab2_lib.baseboard_fab2(sch_1):page234_i223@w_hdl.\sc22u16v5~
mx-4-gp\(chips)',
 PATH='I223',
 DRAWING='@BASEBOARD_FAB2_LIB.BASEBOARD_FAB2(SCH_1):PAGE234',
 TYPE='X6S',
 PACK_SIZE='0805',
 RATED='16V',
 ATTRIBUTE='22UF',
 TOLERANCE='20%',
 SEC_TYPE='SMD-BCG5',
 PHYS_PAGE='234',
 XY='(-7350,4100)',
 ROT='0',
 VER='1',
 VALUE='SC22U16V5MX-4-GP',
 PACK_TYPE='SMD-BCG5',
 PART_NUMBER='078.22611.0811',
 LOCATION='C4B1',
 SEC='1',
 CDS_LIB='w_hdl',
 CDS_PART_NAME='SC22U16V5MX-4-GP_SMD-BCG5-SC22A',
 PRIM_FILE='C:/<user>/w_hdl/sc22u16v5mx#2d4#2dgp/chips/chips.prt';

PART_NAME
 C4B2 'CAP_0805-47UF,4V,20%,X6S,C9533A':
 GROUP='PWR_MLCC_CAP',
 ROOM='PVPP_KLM_VR',
 REUSE_ID='33';

SECTION_NUMBER 1
 '@BASEBOARD_FAB2_LIB.BASEBOARD_FAB2(SCH_1):PAGE234_I180@MSTR_DISCRETE.CAP(CHIPS)':
 C_PATH='@baseboard_fab2_lib.baseboard_fab2(sch_1):page234_i180@mstr_discrete.ca~
p(chips)',
 P_PATH='@baseboard_fab2_lib.baseboard_fab2(sch_1):page234_i180@mstr_discrete.ca~
p(chips)',
 PATH='I180',
 DRAWING='@BASEBOARD_FAB2_LIB.BASEBOARD_FAB2(SCH_1):PAGE234',
 TOLERANCE='20%',
 MATERIAL='X6S',
 BOM_COST='PVPP_KLM_VR',
 PHYS_PAGE='234',
 REUSE_ID='33',
 XY='(-850,3700)',
 ROT='0',
 VER='1',
 VALUE='47UF',
 PACK_TYPE='0805',
 PART_NUMBER='C95333-006',
 LOCATION='C4B2',
 ROOM='PVPP_KLM_VR',
 GROUP='PWR_MLCC_CAP',
 CDS_LIB='mstr_discrete',
 CDS_PART_NAME='CAP_0805-47UF,4V,20%,X6S,C9533A',
 VOLTAGE='4V',
 PRIM_FILE='./archive_libs/mstr_discrete/cap/chips/chips.prt';

PART_NAME
 C4B3 'CAP_0805-47UF,4V,20%,X6S,C9533A':
 GROUP='PWR_MLCC_CAP',
 ROOM='PVPP_KLM_VR',
 REUSE_ID='33';

SECTION_NUMBER 1
 '@BASEBOARD_FAB2_LIB.BASEBOARD_FAB2(SCH_1):PAGE234_I177@MSTR_DISCRETE.CAP(CHIPS)':
 C_PATH='@baseboard_fab2_lib.baseboard_fab2(sch_1):page234_i177@mstr_discrete.ca~
p(chips)',
 P_PATH='@baseboard_fab2_lib.baseboard_fab2(sch_1):page234_i177@mstr_discrete.ca~
p(chips)',
 PATH='I177',
 DRAWING='@BASEBOARD_FAB2_LIB.BASEBOARD_FAB2(SCH_1):PAGE234',
 TOLERANCE='20%',
 MATERIAL='X6S',
 BOM_COST='PVPP_KLM_VR',
 PHYS_PAGE='234',
 REUSE_ID='33',
 XY='(-1150,3700)',
 ROT='0',
 VER='1',
 VALUE='47UF',
 PACK_TYPE='0805',
 PART_NUMBER='C95333-006',
 LOCATION='C4B3',
 ROOM='PVPP_KLM_VR',
 GROUP='PWR_MLCC_CAP',
 CDS_LIB='mstr_discrete',
 CDS_PART_NAME='CAP_0805-47UF,4V,20%,X6S,C9533A',
 VOLTAGE='4V',
 PRIM_FILE='./archive_libs/mstr_discrete/cap/chips/chips.prt';

PART_NAME
 C4B4 'CAP_0402LF-100.0PF,50V,5%,COG,A':
 ROOM='PVPP_KLM_VR',
 REUSE_ID='27';

SECTION_NUMBER 1
 '@BASEBOARD_FAB2_LIB.BASEBOARD_FAB2(SCH_1):PAGE234_I212@MSTR_DISCRETE.CAP(CHIPS)':
 C_PATH='@baseboard_fab2_lib.baseboard_fab2(sch_1):page234_i212@mstr_discrete.ca~
p(chips)',
 P_PATH='@baseboard_fab2_lib.baseboard_fab2(sch_1):page234_i212@mstr_discrete.ca~
p(chips)',
 PATH='I212',
 DRAWING='@BASEBOARD_FAB2_LIB.BASEBOARD_FAB2(SCH_1):PAGE234',
 TOLERANCE='5%',
 SEC_TYPE='0402LF',
 MATERIAL='COG',
 BOM_COST='PVPP_KLM_VR',
 PHYS_PAGE='234',
 REUSE_ID='27',
 XY='(-2225,2825)',
 ROT='2',
 VER='2',
 VALUE='100.0PF',
 PACK_TYPE='0402LF',
 PART_NUMBER='A36095-026',
 LOCATION='C4B4',
 ROOM='PVPP_KLM_VR',
 SEC='1',
 CDS_LIB='mstr_discrete',
 CDS_PART_NAME='CAP_0402LF-100.0PF,50V,5%,COG,A',
 VOLTAGE='50V',
 PRIM_FILE='./archive_libs/mstr_discrete/cap/chips/chips.prt';

PART_NAME
 C4B5 'CAP_0402LF-1000PF,50V,10%,EMPTA':
 ROOM='PVPP_KLM_VR',
 REUSE_ID='1';

SECTION_NUMBER 1
 '@BASEBOARD_FAB2_LIB.BASEBOARD_FAB2(SCH_1):PAGE234_I129@MSTR_DISCRETE.CAP(CHIPS)':
 C_PATH='@baseboard_fab2_lib.baseboard_fab2(sch_1):page234_i129@mstr_discrete.ca~
p(chips)',
 P_PATH='@baseboard_fab2_lib.baseboard_fab2(sch_1):page234_i129@mstr_discrete.ca~
p(chips)',
 PATH='I129',
 DRAWING='@BASEBOARD_FAB2_LIB.BASEBOARD_FAB2(SCH_1):PAGE234',
 FIN='VR_1P2',
 TOLERANCE='10%',
 MATERIAL='EMPTY',
 BOM_COST='PVPP_KLM_VR',
 PHYS_PAGE='234',
 REUSE_ID='1',
 XY='(-6300,2400)',
 ROT='2',
 VER='1',
 VALUE='1000PF',
 PACK_TYPE='0402LF',
 PART_NUMBER='A36096-046',
 LOCATION='C4B5',
 ROOM='PVPP_KLM_VR',
 CDS_LIB='mstr_discrete',
 CDS_PART_NAME='CAP_0402LF-1000PF,50V,10%,EMPTA',
 VOLTAGE='50V',
 PRIM_FILE='./archive_libs/mstr_discrete/cap/chips/chips.prt';

PART_NAME
 C4B6 'CAP_0402-0.027UF,16V,10%,X7R,AA':
 ROOM='PVPP_KLM_VR',
 REUSE_ID='26';

SECTION_NUMBER 1
 '@BASEBOARD_FAB2_LIB.BASEBOARD_FAB2(SCH_1):PAGE234_I146@MSTR_DISCRETE.CAP(CHIPS)':
 C_PATH='@baseboard_fab2_lib.baseboard_fab2(sch_1):page234_i146@mstr_discrete.ca~
p(chips)',
 P_PATH='@baseboard_fab2_lib.baseboard_fab2(sch_1):page234_i146@mstr_discrete.ca~
p(chips)',
 PATH='I146',
 DRAWING='@BASEBOARD_FAB2_LIB.BASEBOARD_FAB2(SCH_1):PAGE234',
 TOLERANCE='10%',
 SEC_TYPE='0402',
 MATERIAL='X7R',
 BOM_COST='PVPP_KLM_VR',
 PHYS_PAGE='234',
 REUSE_ID='26',
 XY='(-5075,2175)',
 ROT='0',
 VER='1',
 VALUE='0.027UF',
 PACK_TYPE='0402',
 PART_NUMBER='A36096-129',
 LOCATION='C4B6',
 ROOM='PVPP_KLM_VR',
 SEC='1',
 CDS_LIB='mstr_discrete',
 CDS_PART_NAME='CAP_0402-0.027UF,16V,10%,X7R,AA',
 VOLTAGE='16V',
 PRIM_FILE='./archive_libs/mstr_discrete/cap/chips/chips.prt';

PART_NAME
 C4B7 'CAP_0402LF-2200PF,50V,10%,X7R,A':
 ROOM='PVPP_KLM_VR',
 REUSE_ID='26';

SECTION_NUMBER 1
 '@BASEBOARD_FAB2_LIB.BASEBOARD_FAB2(SCH_1):PAGE234_I218@MSTR_DISCRETE.CAP(CHIPS)':
 C_PATH='@baseboard_fab2_lib.baseboard_fab2(sch_1):page234_i218@mstr_discrete.ca~
p(chips)',
 P_PATH='@baseboard_fab2_lib.baseboard_fab2(sch_1):page234_i218@mstr_discrete.ca~
p(chips)',
 PATH='I218',
 DRAWING='@BASEBOARD_FAB2_LIB.BASEBOARD_FAB2(SCH_1):PAGE234',
 SPOF='TRUE',
 TOLERANCE='10%',
 SEC_TYPE='0402LF',
 MATERIAL='X7R',
 BOM_COST='PVPP_KLM_VR',
 PHYS_PAGE='234',
 REUSE_ID='26',
 XY='(-1025,1950)',
 ROT='0',
 VER='1',
 VALUE='2200PF',
 PACK_TYPE='0402LF',
 PART_NUMBER='A36096-075',
 LOCATION='C4B7',
 ROOM='PVPP_KLM_VR',
 SEC='1',
 CDS_LIB='mstr_discrete',
 CDS_PART_NAME='CAP_0402LF-2200PF,50V,10%,X7R,A',
 VOLTAGE='50V',
 PRIM_FILE='./archive_libs/mstr_discrete/cap/chips/chips.prt';

PART_NAME
 C4B8 'CAP_0402LF-1000PF,50V,10%,X7R,A':
 ROOM='PVPP_KLM_VR',
 REUSE_ID='17';

SECTION_NUMBER 1
 '@BASEBOARD_FAB2_LIB.BASEBOARD_FAB2(SCH_1):PAGE234_I139@MSTR_DISCRETE.CAP(CHIPS)':
 C_PATH='@baseboard_fab2_lib.baseboard_fab2(sch_1):page234_i139@mstr_discrete.ca~
p(chips)',
 P_PATH='@baseboard_fab2_lib.baseboard_fab2(sch_1):page234_i139@mstr_discrete.ca~
p(chips)',
 PATH='I139',
 DRAWING='@BASEBOARD_FAB2_LIB.BASEBOARD_FAB2(SCH_1):PAGE234',
 TOLERANCE='10%',
 MATERIAL='X7R',
 BOM_COST='PVPP_KLM_VR',
 PHYS_PAGE='234',
 REUSE_ID='17',
 XY='(-3875,725)',
 ROT='0',
 VER='1',
 VALUE='1000PF',
 PACK_TYPE='0402LF',
 PART_NUMBER='A36096-046',
 LOCATION='C4B8',
 ROOM='PVPP_KLM_VR',
 CDS_LIB='mstr_discrete',
 CDS_PART_NAME='CAP_0402LF-1000PF,50V,10%,X7R,A',
 VOLTAGE='50V',
 PRIM_FILE='./archive_libs/mstr_discrete/cap/chips/chips.prt';

PART_NAME
 C4B9 'CAP_0402LF-2200PF,50V,10%,X7R,A':
 ROOM='PVPP_KLM_VR',
 REUSE_ID='27';

SECTION_NUMBER 1
 '@BASEBOARD_FAB2_LIB.BASEBOARD_FAB2(SCH_1):PAGE234_I211@MSTR_DISCRETE.CAP(CHIPS)':
 C_PATH='@baseboard_fab2_lib.baseboard_fab2(sch_1):page234_i211@mstr_discrete.ca~
p(chips)',
 P_PATH='@baseboard_fab2_lib.baseboard_fab2(sch_1):page234_i211@mstr_discrete.ca~
p(chips)',
 PATH='I211',
 DRAWING='@BASEBOARD_FAB2_LIB.BASEBOARD_FAB2(SCH_1):PAGE234',
 TOLERANCE='10%',
 SEC_TYPE='0402LF',
 MATERIAL='X7R',
 BOM_COST='PVPP_KLM_VR',
 PHYS_PAGE='234',
 REUSE_ID='27',
 XY='(-2850,2450)',
 ROT='2',
 VER='2',
 VALUE='2200PF',
 PACK_TYPE='0402LF',
 PART_NUMBER='A36096-075',
 LOCATION='C4B9',
 ROOM='PVPP_KLM_VR',
 SEC='1',
 CDS_LIB='mstr_discrete',
 CDS_PART_NAME='CAP_0402LF-2200PF,50V,10%,X7R,A',
 VOLTAGE='50V',
 PRIM_FILE='./archive_libs/mstr_discrete/cap/chips/chips.prt';

PART_NAME
 C4B11 'CAP_0805-10UF,16V,10%,X7R,G106A':
 ROOM='PVDDQ_DEF_PWR_VR';

SECTION_NUMBER 1
 '@BASEBOARD_FAB2_LIB.BASEBOARD_FAB2(SCH_1):PAGE197_I78@MSTR_DISCRETE.CAP(CHIPS)':
 C_PATH='@baseboard_fab2_lib.baseboard_fab2(sch_1):page197_i78@mstr_discrete.cap~
(chips)',
 P_PATH='@baseboard_fab2_lib.baseboard_fab2(sch_1):page197_i78@mstr_discrete.cap~
(chips)',
 PATH='I78',
 DRAWING='@BASEBOARD_FAB2_LIB.BASEBOARD_FAB2(SCH_1):PAGE197',
 TOLERANCE='10%',
 MATERIAL='X7R',
 PHYS_PAGE='197',
 XY='(2175,3175)',
 ROT='0',
 VER='1',
 VALUE='10UF',
 PACK_TYPE='0805',
 PART_NUMBER='G10601-001',
 LOCATION='C4B11',
 ROOM='PVDDQ_DEF_PWR_VR',
 CDS_LIB='mstr_discrete',
 CDS_PART_NAME='CAP_0805-10UF,16V,10%,X7R,G106A',
 VOLTAGE='16V',
 PRIM_FILE='./archive_libs/mstr_discrete/cap/chips/chips.prt';

PART_NAME
 C4B12 'CAP_A_0402V-0.01UF,25V,10%,X7RA':
 ROOM='DDR4_CH_B';

SECTION_NUMBER 1
 '@BASEBOARD_FAB2_LIB.BASEBOARD_FAB2(SCH_1):PAGE49_I179@DEV_DISCRETE.CAP_A(CHIPS)':
 C_PATH='@baseboard_fab2_lib.baseboard_fab2(sch_1):page49_i179@dev_discrete.cap_~
a(chips)',
 P_PATH='@baseboard_fab2_lib.baseboard_fab2(sch_1):page49_i179@dev_discrete.cap_~
a(chips)',
 PATH='I179',
 DRAWING='@BASEBOARD_FAB2_LIB.BASEBOARD_FAB2(SCH_1):PAGE49',
 TOLERANCE='10%',
 SEC_TYPE='0402V',
 MATERIAL='X7R',
 BOM_COST='MEM',
 PHYS_PAGE='49',
 XY='(-4650,1800)',
 ROT='2',
 VER='1',
 VALUE='0.01UF',
 PACK_TYPE='0402V',
 PART_NUMBER='A36096-045',
 LOCATION='C4B12',
 ROOM='DDR4_CH_B',
 SEC='1',
 CDS_LIB='dev_discrete',
 CDS_PART_NAME='CAP_A_0402V-0.01UF,25V,10%,X7RA',
 VOLTAGE='25V',
 PRIM_FILE='./archive_libs/discrete/cap_a/chips/chips.prt';

PART_NAME
 C4B13 'CAPP_4040LF-470UF,16V,20%,ALUMA':;

SECTION_NUMBER 1
 '@BASEBOARD_FAB2_LIB.BASEBOARD_FAB2(SCH_1):PAGE195_I83@MSTR_DISCRETE.CAPP(CHIPS)':
 C_PATH='@baseboard_fab2_lib.baseboard_fab2(sch_1):page195_i83@mstr_discrete.cap~
p(chips)',
 P_PATH='@baseboard_fab2_lib.baseboard_fab2(sch_1):page195_i83@mstr_discrete.cap~
p(chips)',
 PATH='I83',
 DRAWING='@BASEBOARD_FAB2_LIB.BASEBOARD_FAB2(SCH_1):PAGE195',
 TOLERANCE='20%',
 MATERIAL='ALUM',
 PHYS_PAGE='195',
 XY='(-6675,2950)',
 ROT='0',
 VER='1',
 VALUE='470UF',
 PACK_TYPE='4040LF',
 PART_NUMBER='A93539-036',
 LOCATION='C4B13',
 CDS_LIB='mstr_discrete',
 CDS_PART_NAME='CAPP_4040LF-470UF,16V,20%,ALUMA',
 VOLTAGE='16V',
 PRIM_FILE='./archive_libs/mstr_discrete/capp/chips/chips.prt';

PART_NAME
 C4B14 'CAPP_3018-68UF,16V,20%,TANT,72A':;

SECTION_NUMBER 1
 '@BASEBOARD_FAB2_LIB.BASEBOARD_FAB2(SCH_1):PAGE195_I97@MSTR_DISCRETE.CAPP(CHIPS)':
 C_PATH='@baseboard_fab2_lib.baseboard_fab2(sch_1):page195_i97@mstr_discrete.cap~
p(chips)',
 P_PATH='@baseboard_fab2_lib.baseboard_fab2(sch_1):page195_i97@mstr_discrete.cap~
p(chips)',
 PATH='I97',
 DRAWING='@BASEBOARD_FAB2_LIB.BASEBOARD_FAB2(SCH_1):PAGE195',
 TOLERANCE='20%',
 SEC_TYPE='3018',
 MATERIAL='TANT',
 PHYS_PAGE='195',
 XY='(-6900,775)',
 ROT='0',
 VER='1',
 VALUE='68UF',
 PACK_TYPE='3018',
 PART_NUMBER='724613-112',
 LOCATION='C4B14',
 SEC='1',
 CDS_LIB='mstr_discrete',
 CDS_PART_NAME='CAPP_3018-68UF,16V,20%,TANT,72A',
 VOLTAGE='16V',
 PRIM_FILE='./archive_libs/mstr_discrete/capp/chips/chips.prt';

PART_NAME
 C4B15 'CAP_0603LF-0.1UF,25V,10%,X7R,6A':
 ROOM='PVPP_KLM_VR',
 REUSE_ID='27';

SECTION_NUMBER 1
 '@BASEBOARD_FAB2_LIB.BASEBOARD_FAB2(SCH_1):PAGE234_I182@MSTR_DISCRETE.CAP(CHIPS)':
 C_PATH='@baseboard_fab2_lib.baseboard_fab2(sch_1):page234_i182@mstr_discrete.ca~
p(chips)',
 P_PATH='@baseboard_fab2_lib.baseboard_fab2(sch_1):page234_i182@mstr_discrete.ca~
p(chips)',
 PATH='I182',
 DRAWING='@BASEBOARD_FAB2_LIB.BASEBOARD_FAB2(SCH_1):PAGE234',
 TOLERANCE='10%',
 MATERIAL='X7R',
 BOM_COST='PVPP_KLM_VR',
 PHYS_PAGE='234',
 REUSE_ID='27',
 XY='(-3375,4200)',
 ROT='2',
 VER='2',
 VALUE='0.1UF',
 PACK_TYPE='0603LF',
 PART_NUMBER='602433-020',
 LOCATION='C4B15',
 ROOM='PVPP_KLM_VR',
 CDS_LIB='mstr_discrete',
 CDS_PART_NAME='CAP_0603LF-0.1UF,25V,10%,X7R,6A',
 VOLTAGE='25V',
 PRIM_FILE='./archive_libs/mstr_discrete/cap/chips/chips.prt';

PART_NAME
 C4C1 'CAPP_3018-470UF,2.5V,20%,ALUM,A':
 GROUP='PWR_MCP_CAP',
 ROOM='P0V95_MCP_CPU1_DECAP_VR';

SECTION_NUMBER 1
 '@BASEBOARD_FAB2_LIB.BASEBOARD_FAB2(SCH_1):PAGE193_I29@MSTR_DISCRETE.CAPP(CHIPS)':
 C_PATH='@baseboard_fab2_lib.baseboard_fab2(sch_1):page193_i29@mstr_discrete.cap~
p(chips)',
 P_PATH='@baseboard_fab2_lib.baseboard_fab2(sch_1):page193_i29@mstr_discrete.cap~
p(chips)',
 PATH='I29',
 DRAWING='@BASEBOARD_FAB2_LIB.BASEBOARD_FAB2(SCH_1):PAGE193',
 TOLERANCE='20%',
 SEC_TYPE='3018',
 MATERIAL='ALUM',
 BOM_COST='PROC_VRD_VCCIN_CPU1',
 PHYS_PAGE='193',
 XY='(-1900,3950)',
 ROT='0',
 VER='1',
 VALUE='470UF',
 PACK_TYPE='3018',
 PART_NUMBER='699013-049',
 LOCATION='C4C1',
 ROOM='P0V95_MCP_CPU1_DECAP_VR',
 GROUP='PWR_MCP_CAP',
 SEC='1',
 CDS_LIB='mstr_discrete',
 CDS_PART_NAME='CAPP_3018-470UF,2.5V,20%,ALUM,A',
 VOLTAGE='2.5V',
 PRIM_FILE='./archive_libs/mstr_discrete/capp/chips/chips.prt';

PART_NAME
 C4C3 'CAP_A_0402V-1.0UF,6.3V,10%,X6SA':
 ROOM='PROC_RSTS_PGOODS';

SECTION_NUMBER 1
 '@BASEBOARD_FAB2_LIB.BASEBOARD_FAB2(SCH_1):PAGE96_I75@DEV_DISCRETE.CAP_A(CHIPS)':
 C_PATH='@baseboard_fab2_lib.baseboard_fab2(sch_1):page96_i75@dev_discrete.cap_a~
(chips)',
 P_PATH='@baseboard_fab2_lib.baseboard_fab2(sch_1):page96_i75@dev_discrete.cap_a~
(chips)',
 PATH='I75',
 DRAWING='@BASEBOARD_FAB2_LIB.BASEBOARD_FAB2(SCH_1):PAGE96',
 TOLERANCE='10%',
 SEC_TYPE='0402V',
 MATERIAL='X6S',
 BOM_COST='PROC_SIDEBAND',
 PHYS_PAGE='96',
 XY='(-1725,2325)',
 ROT='0',
 VER='1',
 VALUE='1.0UF',
 PACK_TYPE='0402V',
 PART_NUMBER='D97712-004',
 LOCATION='C4C3',
 ROOM='PROC_RSTS_PGOODS',
 SEC='1',
 CDS_LIB='dev_discrete',
 CDS_PART_NAME='CAP_A_0402V-1.0UF,6.3V,10%,X6SA',
 VOLTAGE='6.3V',
 PRIM_FILE='./archive_libs/discrete/cap_a/chips/chips.prt';

PART_NAME
 C4C4 'SC1U10V2KX-4-GP_SMD-BCG6-SC1U1A':;

SECTION_NUMBER 1
 '@BASEBOARD_FAB2_LIB.BASEBOARD_FAB2(SCH_1):PAGE205_I83@W_HDL.SC1U10V2KX-4-GP(CHIPS)':
 C_PATH='@baseboard_fab2_lib.baseboard_fab2(sch_1):page205_i83@w_hdl.\sc1u10v2kx~
-4-gp\(chips)',
 P_PATH='@baseboard_fab2_lib.baseboard_fab2(sch_1):page205_i83@w_hdl.\sc1u10v2kx~
-4-gp\(chips)',
 PATH='I83',
 DRAWING='@BASEBOARD_FAB2_LIB.BASEBOARD_FAB2(SCH_1):PAGE205',
 PACK_SIZE='0402',
 RATED='10V',
 ATTRIBUTE='1UF',
 TOLERANCE='10%',
 SEC_TYPE='SMD-BCG6',
 PHYS_PAGE='205',
 XY='(-5625,4175)',
 ROT='0',
 VER='1',
 VALUE='SC1U10V2KX-4-GP',
 PACK_TYPE='SMD-BCG6',
 PART_NUMBER='78.10523.8FL',
 LOCATION='C4C4',
 SEC='1',
 CDS_LIB='w_hdl',
 CDS_PART_NAME='SC1U10V2KX-4-GP_SMD-BCG6-SC1U1A',
 PRIM_FILE='C:/<user>/w_hdl/sc1u10v2kx#2d4#2dgp/chips/chips.prt';

PART_NAME
 C4C5 'CAP_0402-0.22UF,16V,10%,X7R,A3A':
 ROOM='PVSA_CPU0_PWR_VR';

SECTION_NUMBER 1
 '@BASEBOARD_FAB2_LIB.BASEBOARD_FAB2(SCH_1):PAGE205_I16@MSTR_DISCRETE.CAP(CHIPS)':
 C_PATH='@baseboard_fab2_lib.baseboard_fab2(sch_1):page205_i16@mstr_discrete.cap~
(chips)',
 P_PATH='@baseboard_fab2_lib.baseboard_fab2(sch_1):page205_i16@mstr_discrete.cap~
(chips)',
 PATH='I16',
 DRAWING='@BASEBOARD_FAB2_LIB.BASEBOARD_FAB2(SCH_1):PAGE205',
 TOLERANCE='10%',
 SEC_TYPE='0402',
 MATERIAL='X7R',
 PHYS_PAGE='205',
 XY='(-5300,4200)',
 ROT='0',
 VER='1',
 VALUE='0.22UF',
 PACK_TYPE='0402',
 PART_NUMBER='A36096-155',
 LOCATION='C4C5',
 ROOM='PVSA_CPU0_PWR_VR',
 SEC='1',
 CDS_LIB='mstr_discrete',
 CDS_PART_NAME='CAP_0402-0.22UF,16V,10%,X7R,A3A',
 VOLTAGE='16V',
 PRIM_FILE='./archive_libs/mstr_discrete/cap/chips/chips.prt';

PART_NAME
 C4C6 'CAP_0402-1.0UF,16V,10%,X6S,D97A':
 ROOM='PVSA_CPU0_PWR_VR';

SECTION_NUMBER 1
 '@BASEBOARD_FAB2_LIB.BASEBOARD_FAB2(SCH_1):PAGE205_I20@MSTR_DISCRETE.CAP(CHIPS)':
 C_PATH='@baseboard_fab2_lib.baseboard_fab2(sch_1):page205_i20@mstr_discrete.cap~
(chips)',
 P_PATH='@baseboard_fab2_lib.baseboard_fab2(sch_1):page205_i20@mstr_discrete.cap~
(chips)',
 PATH='I20',
 DRAWING='@BASEBOARD_FAB2_LIB.BASEBOARD_FAB2(SCH_1):PAGE205',
 TOLERANCE='10%',
 SEC_TYPE='0402',
 MATERIAL='X6S',
 PHYS_PAGE='205',
 XY='(-6000,4200)',
 ROT='0',
 VER='1',
 VALUE='1.0UF',
 PACK_TYPE='0402',
 PART_NUMBER='D97712-011',
 LOCATION='C4C6',
 ROOM='PVSA_CPU0_PWR_VR',
 SEC='1',
 CDS_LIB='mstr_discrete',
 CDS_PART_NAME='CAP_0402-1.0UF,16V,10%,X6S,D97A',
 VOLTAGE='16V',
 PRIM_FILE='./archive_libs/mstr_discrete/cap/chips/chips.prt';

PART_NAME
 C4C8 'CAP_0402-0.220UF,16V,10%,X7R,AA':
 ROOM='PVSA_CPU0_PWR_VR';

SECTION_NUMBER 1
 '@BASEBOARD_FAB2_LIB.BASEBOARD_FAB2(SCH_1):PAGE205_I25@MSTR_DISCRETE.CAP(CHIPS)':
 C_PATH='@baseboard_fab2_lib.baseboard_fab2(sch_1):page205_i25@mstr_discrete.cap~
(chips)',
 P_PATH='@baseboard_fab2_lib.baseboard_fab2(sch_1):page205_i25@mstr_discrete.cap~
(chips)',
 PATH='I25',
 DRAWING='@BASEBOARD_FAB2_LIB.BASEBOARD_FAB2(SCH_1):PAGE205',
 SPOF='TRUE',
 TOLERANCE='10%',
 SEC_TYPE='0402',
 MATERIAL='X7R',
 PHYS_PAGE='205',
 XY='(-6050,3550)',
 ROT='2',
 VER='1',
 VALUE='0.220UF',
 PACK_TYPE='0402',
 PART_NUMBER='A36096-104',
 LOCATION='C4C8',
 ROOM='PVSA_CPU0_PWR_VR',
 SEC='1',
 CDS_LIB='mstr_discrete',
 CDS_PART_NAME='CAP_0402-0.220UF,16V,10%,X7R,AA',
 VOLTAGE='16V',
 PRIM_FILE='./archive_libs/mstr_discrete/cap/chips/chips.prt';

PART_NAME
 C4C9 'CAP_0402-1.0UF,16V,10%,X6S,D97A':
 ROOM='PVSA_CPU0_PWR_VR';

SECTION_NUMBER 1
 '@BASEBOARD_FAB2_LIB.BASEBOARD_FAB2(SCH_1):PAGE205_I32@MSTR_DISCRETE.CAP(CHIPS)':
 C_PATH='@baseboard_fab2_lib.baseboard_fab2(sch_1):page205_i32@mstr_discrete.cap~
(chips)',
 P_PATH='@baseboard_fab2_lib.baseboard_fab2(sch_1):page205_i32@mstr_discrete.cap~
(chips)',
 PATH='I32',
 DRAWING='@BASEBOARD_FAB2_LIB.BASEBOARD_FAB2(SCH_1):PAGE205',
 TOLERANCE='10%',
 SEC_TYPE='0402',
 MATERIAL='X6S',
 PHYS_PAGE='205',
 XY='(-6475,4200)',
 ROT='0',
 VER='1',
 VALUE='1.0UF',
 PACK_TYPE='0402',
 PART_NUMBER='D97712-011',
 LOCATION='C4C9',
 ROOM='PVSA_CPU0_PWR_VR',
 SEC='1',
 CDS_LIB='mstr_discrete',
 CDS_PART_NAME='CAP_0402-1.0UF,16V,10%,X6S,D97A',
 VOLTAGE='16V',
 PRIM_FILE='./archive_libs/mstr_discrete/cap/chips/chips.prt';

PART_NAME
 C4C10 'CAP_A_0402V-0.1UF,16V,10%,X7R,A':
 ROOM='PVSA_CPU0_PWR_VR';

SECTION_NUMBER 1
 '@BASEBOARD_FAB2_LIB.BASEBOARD_FAB2(SCH_1):PAGE205_I31@DEV_DISCRETE.CAP_A(CHIPS)':
 C_PATH='@baseboard_fab2_lib.baseboard_fab2(sch_1):page205_i31@dev_discrete.cap_~
a(chips)',
 P_PATH='@baseboard_fab2_lib.baseboard_fab2(sch_1):page205_i31@dev_discrete.cap_~
a(chips)',
 PATH='I31',
 DRAWING='@BASEBOARD_FAB2_LIB.BASEBOARD_FAB2(SCH_1):PAGE205',
 TOLERANCE='10%',
 SEC_TYPE='0402V',
 MATERIAL='X7R',
 PHYS_PAGE='205',
 XY='(-6250,4200)',
 ROT='0',
 VER='1',
 VALUE='0.1UF',
 PACK_TYPE='0402V',
 PART_NUMBER='A36096-030',
 LOCATION='C4C10',
 ROOM='PVSA_CPU0_PWR_VR',
 SEC='1',
 CDS_LIB='dev_discrete',
 CDS_PART_NAME='CAP_A_0402V-0.1UF,16V,10%,X7R,A',
 VOLTAGE='16V',
 PRIM_FILE='./archive_libs/discrete/cap_a/chips/chips.prt';

PART_NAME
 C4C11 'CAP_A_0603V-22.0UF,4V,20%,X6S,A':;

SECTION_NUMBER 1
 '@BASEBOARD_FAB2_LIB.BASEBOARD_FAB2(SCH_1):PAGE205_I43@DEV_DISCRETE.CAP_A(CHIPS)':
 C_PATH='@baseboard_fab2_lib.baseboard_fab2(sch_1):page205_i43@dev_discrete.cap_~
a(chips)',
 P_PATH='@baseboard_fab2_lib.baseboard_fab2(sch_1):page205_i43@dev_discrete.cap_~
a(chips)',
 PATH='I43',
 DRAWING='@BASEBOARD_FAB2_LIB.BASEBOARD_FAB2(SCH_1):PAGE205',
 TOLERANCE='20%',
 SEC_TYPE='0603V',
 MATERIAL='X6S',
 PHYS_PAGE='205',
 XY='(-600,3075)',
 ROT='0',
 VER='1',
 VALUE='22.0UF',
 PACK_TYPE='0603V',
 PART_NUMBER='E15431-004',
 LOCATION='C4C11',
 SEC='1',
 CDS_LIB='dev_discrete',
 CDS_PART_NAME='CAP_A_0603V-22.0UF,4V,20%,X6S,A',
 VOLTAGE='4V',
 PRIM_FILE='./archive_libs/discrete/cap_a/chips/chips.prt';

PART_NAME
 C4C12 'CAPP_2626-270UF,16V,20%,OSCON,A':
 ROOM='PVCCIN_CPU0_FILTER_VR';

SECTION_NUMBER 1
 '@BASEBOARD_FAB2_LIB.BASEBOARD_FAB2(SCH_1):PAGE204_I67@MSTR_DISCRETE.CAPP(CHIPS)':
 C_PATH='@baseboard_fab2_lib.baseboard_fab2(sch_1):page204_i67@mstr_discrete.cap~
p(chips)',
 P_PATH='@baseboard_fab2_lib.baseboard_fab2(sch_1):page204_i67@mstr_discrete.cap~
p(chips)',
 PATH='I67',
 DRAWING='@BASEBOARD_FAB2_LIB.BASEBOARD_FAB2(SCH_1):PAGE204',
 TOLERANCE='20%',
 SEC_TYPE='2626',
 MATERIAL='OSCON',
 PHYS_PAGE='204',
 XY='(-575,1975)',
 ROT='0',
 VER='1',
 VALUE='270UF',
 PACK_TYPE='2626',
 PART_NUMBER='A31228-047',
 LOCATION='C4C12',
 ROOM='PVCCIN_CPU0_FILTER_VR',
 SEC='1',
 CDS_LIB='mstr_discrete',
 CDS_PART_NAME='CAPP_2626-270UF,16V,20%,OSCON,A',
 VOLTAGE='16V',
 PRIM_FILE='./archive_libs/mstr_discrete/capp/chips/chips.prt';

PART_NAME
 C4C14 'SC1U10V2KX-4-GP_SMD-BCG6-SC1U1A':;

SECTION_NUMBER 1
 '@BASEBOARD_FAB2_LIB.BASEBOARD_FAB2(SCH_1):PAGE204_I113@W_HDL.SC1U10V2KX-4-GP(CHIPS)':
 C_PATH='@baseboard_fab2_lib.baseboard_fab2(sch_1):page204_i113@w_hdl.\sc1u10v2k~
x-4-gp\(chips)',
 P_PATH='@baseboard_fab2_lib.baseboard_fab2(sch_1):page204_i113@w_hdl.\sc1u10v2k~
x-4-gp\(chips)',
 PATH='I113',
 DRAWING='@BASEBOARD_FAB2_LIB.BASEBOARD_FAB2(SCH_1):PAGE204',
 PACK_SIZE='0402',
 RATED='10V',
 ATTRIBUTE='1UF',
 TOLERANCE='10%',
 SEC_TYPE='SMD-BCG6',
 PHYS_PAGE='204',
 XY='(-5200,4150)',
 ROT='0',
 VER='1',
 VALUE='SC1U10V2KX-4-GP',
 PACK_TYPE='SMD-BCG6',
 PART_NUMBER='78.10523.8FL',
 LOCATION='C4C14',
 SEC='1',
 CDS_LIB='w_hdl',
 CDS_PART_NAME='SC1U10V2KX-4-GP_SMD-BCG6-SC1U1A',
 PRIM_FILE='C:/<user>/w_hdl/sc1u10v2kx#2d4#2dgp/chips/chips.prt';

PART_NAME
 C4C17 'CAP_0402-0.220UF,16V,10%,X7R,AA':
 ROOM='PVCCIN_CPU0_PWR_VR',
 NO_XNET_CONNECTION='1';

SECTION_NUMBER 1
 '@BASEBOARD_FAB2_LIB.BASEBOARD_FAB2(SCH_1):PAGE204_I22@MSTR_DISCRETE.CAP(CHIPS)':
 C_PATH='@baseboard_fab2_lib.baseboard_fab2(sch_1):page204_i22@mstr_discrete.cap~
(chips)',
 P_PATH='@baseboard_fab2_lib.baseboard_fab2(sch_1):page204_i22@mstr_discrete.cap~
(chips)',
 PATH='I22',
 DRAWING='@BASEBOARD_FAB2_LIB.BASEBOARD_FAB2(SCH_1):PAGE204',
 SPOF='TRUE',
 TOLERANCE='10%',
 SEC_TYPE='0402',
 MATERIAL='X7R',
 NO_XNET_CONNECTION='1',
 PHYS_PAGE='204',
 XY='(-5825,3575)',
 ROT='2',
 VER='1',
 VALUE='0.220UF',
 PACK_TYPE='0402',
 PART_NUMBER='A36096-104',
 LOCATION='C4C17',
 ROOM='PVCCIN_CPU0_PWR_VR',
 SEC='1',
 CDS_LIB='mstr_discrete',
 CDS_PART_NAME='CAP_0402-0.220UF,16V,10%,X7R,AA',
 VOLTAGE='16V',
 PRIM_FILE='./archive_libs/mstr_discrete/cap/chips/chips.prt';

PART_NAME
 C4C18 'CAP_0402-1.0UF,16V,10%,X6S,D97A':
 ROOM='PVCCIN_CPU0_PWR_VR';

SECTION_NUMBER 1
 '@BASEBOARD_FAB2_LIB.BASEBOARD_FAB2(SCH_1):PAGE204_I36@MSTR_DISCRETE.CAP(CHIPS)':
 C_PATH='@baseboard_fab2_lib.baseboard_fab2(sch_1):page204_i36@mstr_discrete.cap~
(chips)',
 P_PATH='@baseboard_fab2_lib.baseboard_fab2(sch_1):page204_i36@mstr_discrete.cap~
(chips)',
 PATH='I36',
 DRAWING='@BASEBOARD_FAB2_LIB.BASEBOARD_FAB2(SCH_1):PAGE204',
 TOLERANCE='10%',
 SEC_TYPE='0402',
 MATERIAL='X6S',
 PHYS_PAGE='204',
 XY='(-6300,4175)',
 ROT='0',
 VER='1',
 VALUE='1.0UF',
 PACK_TYPE='0402',
 PART_NUMBER='D97712-011',
 LOCATION='C4C18',
 ROOM='PVCCIN_CPU0_PWR_VR',
 SEC='1',
 CDS_LIB='mstr_discrete',
 CDS_PART_NAME='CAP_0402-1.0UF,16V,10%,X6S,D97A',
 VOLTAGE='16V',
 PRIM_FILE='./archive_libs/mstr_discrete/cap/chips/chips.prt';

PART_NAME
 C4C19 'CAP_A_0402V-0.1UF,16V,10%,X7R,A':
 ROOM='PVCCIN_CPU0_PWR_VR';

SECTION_NUMBER 1
 '@BASEBOARD_FAB2_LIB.BASEBOARD_FAB2(SCH_1):PAGE204_I35@DEV_DISCRETE.CAP_A(CHIPS)':
 C_PATH='@baseboard_fab2_lib.baseboard_fab2(sch_1):page204_i35@dev_discrete.cap_~
a(chips)',
 P_PATH='@baseboard_fab2_lib.baseboard_fab2(sch_1):page204_i35@dev_discrete.cap_~
a(chips)',
 PATH='I35',
 DRAWING='@BASEBOARD_FAB2_LIB.BASEBOARD_FAB2(SCH_1):PAGE204',
 TOLERANCE='10%',
 SEC_TYPE='0402V',
 MATERIAL='X7R',
 PHYS_PAGE='204',
 XY='(-6000,4175)',
 ROT='0',
 VER='1',
 VALUE='0.1UF',
 PACK_TYPE='0402V',
 PART_NUMBER='A36096-030',
 LOCATION='C4C19',
 ROOM='PVCCIN_CPU0_PWR_VR',
 SEC='1',
 CDS_LIB='dev_discrete',
 CDS_PART_NAME='CAP_A_0402V-0.1UF,16V,10%,X7R,A',
 VOLTAGE='16V',
 PRIM_FILE='./archive_libs/discrete/cap_a/chips/chips.prt';

PART_NAME
 C4D2 'CAPP_2626-270UF,16V,20%,OSCON,A':
 ROOM='PVCCIN_CPU0_FILTER_VR';

SECTION_NUMBER 1
 '@BASEBOARD_FAB2_LIB.BASEBOARD_FAB2(SCH_1):PAGE204_I48@MSTR_DISCRETE.CAPP(CHIPS)':
 C_PATH='@baseboard_fab2_lib.baseboard_fab2(sch_1):page204_i48@mstr_discrete.cap~
p(chips)',
 P_PATH='@baseboard_fab2_lib.baseboard_fab2(sch_1):page204_i48@mstr_discrete.cap~
p(chips)',
 PATH='I48',
 DRAWING='@BASEBOARD_FAB2_LIB.BASEBOARD_FAB2(SCH_1):PAGE204',
 TOLERANCE='20%',
 SEC_TYPE='2626',
 MATERIAL='OSCON',
 PHYS_PAGE='204',
 XY='(-925,1975)',
 ROT='0',
 VER='1',
 VALUE='270UF',
 PACK_TYPE='2626',
 PART_NUMBER='A31228-047',
 LOCATION='C4D2',
 ROOM='PVCCIN_CPU0_FILTER_VR',
 SEC='1',
 CDS_LIB='mstr_discrete',
 CDS_PART_NAME='CAPP_2626-270UF,16V,20%,OSCON,A',
 VOLTAGE='16V',
 PRIM_FILE='./archive_libs/mstr_discrete/capp/chips/chips.prt';

PART_NAME
 C4D4 'CAP_A_0603V-22.0UF,4V,20%,X6S,A':
 GROUP='PWR_MLCC_CAP';

SECTION_NUMBER 1
 '@BASEBOARD_FAB2_LIB.BASEBOARD_FAB2(SCH_1):PAGE203_I69@DEV_DISCRETE.CAP_A(CHIPS)':
 C_PATH='@baseboard_fab2_lib.baseboard_fab2(sch_1):page203_i69@dev_discrete.cap_~
a(chips)',
 P_PATH='@baseboard_fab2_lib.baseboard_fab2(sch_1):page203_i69@dev_discrete.cap_~
a(chips)',
 PATH='I69',
 DRAWING='@BASEBOARD_FAB2_LIB.BASEBOARD_FAB2(SCH_1):PAGE203',
 TOLERANCE='20%',
 SEC_TYPE='0603V',
 MATERIAL='X6S',
 PHYS_PAGE='203',
 XY='(-450,725)',
 ROT='0',
 VER='1',
 VALUE='22.0UF',
 PACK_TYPE='0603V',
 PART_NUMBER='E15431-004',
 LOCATION='C4D4',
 GROUP='PWR_MLCC_CAP',
 SEC='1',
 CDS_LIB='dev_discrete',
 CDS_PART_NAME='CAP_A_0603V-22.0UF,4V,20%,X6S,A',
 VOLTAGE='4V',
 PRIM_FILE='./archive_libs/discrete/cap_a/chips/chips.prt';

PART_NAME
 C4D5 'CAP_0402-0.22UF,16V,10%,X7R,A3A':
 ROOM='PVCCIN_CPU0_PWR_VR';

SECTION_NUMBER 1
 '@BASEBOARD_FAB2_LIB.BASEBOARD_FAB2(SCH_1):PAGE203_I48@MSTR_DISCRETE.CAP(CHIPS)':
 C_PATH='@baseboard_fab2_lib.baseboard_fab2(sch_1):page203_i48@mstr_discrete.cap~
(chips)',
 P_PATH='@baseboard_fab2_lib.baseboard_fab2(sch_1):page203_i48@mstr_discrete.cap~
(chips)',
 PATH='I48',
 DRAWING='@BASEBOARD_FAB2_LIB.BASEBOARD_FAB2(SCH_1):PAGE203',
 TOLERANCE='10%',
 SEC_TYPE='0402',
 MATERIAL='X7R',
 PHYS_PAGE='203',
 XY='(-4825,1475)',
 ROT='0',
 VER='1',
 VALUE='0.22UF',
 PACK_TYPE='0402',
 PART_NUMBER='A36096-155',
 LOCATION='C4D5',
 ROOM='PVCCIN_CPU0_PWR_VR',
 SEC='1',
 CDS_LIB='mstr_discrete',
 CDS_PART_NAME='CAP_0402-0.22UF,16V,10%,X7R,A3A',
 VOLTAGE='16V',
 PRIM_FILE='./archive_libs/mstr_discrete/cap/chips/chips.prt';

PART_NAME
 C4D6 'SC1U10V2KX-4-GP_SMD-BCG6-SC1U1A':;

SECTION_NUMBER 1
 '@BASEBOARD_FAB2_LIB.BASEBOARD_FAB2(SCH_1):PAGE203_I133@W_HDL.SC1U10V2KX-4-GP(CHIPS)':
 C_PATH='@baseboard_fab2_lib.baseboard_fab2(sch_1):page203_i133@w_hdl.\sc1u10v2k~
x-4-gp\(chips)',
 P_PATH='@baseboard_fab2_lib.baseboard_fab2(sch_1):page203_i133@w_hdl.\sc1u10v2k~
x-4-gp\(chips)',
 PATH='I133',
 DRAWING='@BASEBOARD_FAB2_LIB.BASEBOARD_FAB2(SCH_1):PAGE203',
 PACK_SIZE='0402',
 RATED='10V',
 ATTRIBUTE='1UF',
 TOLERANCE='10%',
 SEC_TYPE='SMD-BCG6',
 PHYS_PAGE='203',
 XY='(-5200,1475)',
 ROT='0',
 VER='1',
 VALUE='SC1U10V2KX-4-GP',
 PACK_TYPE='SMD-BCG6',
 PART_NUMBER='78.10523.8FL',
 LOCATION='C4D6',
 SEC='1',
 CDS_LIB='w_hdl',
 CDS_PART_NAME='SC1U10V2KX-4-GP_SMD-BCG6-SC1U1A',
 PRIM_FILE='C:/<user>/w_hdl/sc1u10v2kx#2d4#2dgp/chips/chips.prt';

PART_NAME
 C4D7 'CAP_0402-1.0UF,16V,10%,X6S,D97A':
 ROOM='PVCCIN_CPU0_PWR_VR';

SECTION_NUMBER 1
 '@BASEBOARD_FAB2_LIB.BASEBOARD_FAB2(SCH_1):PAGE203_I51@MSTR_DISCRETE.CAP(CHIPS)':
 C_PATH='@baseboard_fab2_lib.baseboard_fab2(sch_1):page203_i51@mstr_discrete.cap~
(chips)',
 P_PATH='@baseboard_fab2_lib.baseboard_fab2(sch_1):page203_i51@mstr_discrete.cap~
(chips)',
 PATH='I51',
 DRAWING='@BASEBOARD_FAB2_LIB.BASEBOARD_FAB2(SCH_1):PAGE203',
 TOLERANCE='10%',
 SEC_TYPE='0402',
 MATERIAL='X6S',
 PHYS_PAGE='203',
 XY='(-5675,1475)',
 ROT='0',
 VER='1',
 VALUE='1.0UF',
 PACK_TYPE='0402',
 PART_NUMBER='D97712-011',
 LOCATION='C4D7',
 ROOM='PVCCIN_CPU0_PWR_VR',
 SEC='1',
 CDS_LIB='mstr_discrete',
 CDS_PART_NAME='CAP_0402-1.0UF,16V,10%,X6S,D97A',
 VOLTAGE='16V',
 PRIM_FILE='./archive_libs/mstr_discrete/cap/chips/chips.prt';

PART_NAME
 C4D9 'CAP_0402-0.220UF,16V,10%,X7R,AA':
 ROOM='PVCCIN_CPU0_PWR_VR',
 NO_XNET_CONNECTION='1';

SECTION_NUMBER 1
 '@BASEBOARD_FAB2_LIB.BASEBOARD_FAB2(SCH_1):PAGE203_I3@MSTR_DISCRETE.CAP(CHIPS)':
 C_PATH='@baseboard_fab2_lib.baseboard_fab2(sch_1):page203_i3@mstr_discrete.cap(~
chips)',
 P_PATH='@baseboard_fab2_lib.baseboard_fab2(sch_1):page203_i3@mstr_discrete.cap(~
chips)',
 PATH='I3',
 DRAWING='@BASEBOARD_FAB2_LIB.BASEBOARD_FAB2(SCH_1):PAGE203',
 SPOF='TRUE',
 TOLERANCE='10%',
 SEC_TYPE='0402',
 MATERIAL='X7R',
 NO_XNET_CONNECTION='1',
 PHYS_PAGE='203',
 XY='(-5875,825)',
 ROT='2',
 VER='1',
 VALUE='0.220UF',
 PACK_TYPE='0402',
 PART_NUMBER='A36096-104',
 LOCATION='C4D9',
 ROOM='PVCCIN_CPU0_PWR_VR',
 SEC='1',
 CDS_LIB='mstr_discrete',
 CDS_PART_NAME='CAP_0402-0.220UF,16V,10%,X7R,AA',
 VOLTAGE='16V',
 PRIM_FILE='./archive_libs/mstr_discrete/cap/chips/chips.prt';

PART_NAME
 C4D10 'CAP_0402-1.0UF,16V,10%,X6S,D97A':
 ROOM='PVCCIN_CPU0_PWR_VR';

SECTION_NUMBER 1
 '@BASEBOARD_FAB2_LIB.BASEBOARD_FAB2(SCH_1):PAGE203_I53@MSTR_DISCRETE.CAP(CHIPS)':
 C_PATH='@baseboard_fab2_lib.baseboard_fab2(sch_1):page203_i53@mstr_discrete.cap~
(chips)',
 P_PATH='@baseboard_fab2_lib.baseboard_fab2(sch_1):page203_i53@mstr_discrete.cap~
(chips)',
 PATH='I53',
 DRAWING='@BASEBOARD_FAB2_LIB.BASEBOARD_FAB2(SCH_1):PAGE203',
 TOLERANCE='10%',
 SEC_TYPE='0402',
 MATERIAL='X6S',
 PHYS_PAGE='203',
 XY='(-6250,1475)',
 ROT='0',
 VER='1',
 VALUE='1.0UF',
 PACK_TYPE='0402',
 PART_NUMBER='D97712-011',
 LOCATION='C4D10',
 ROOM='PVCCIN_CPU0_PWR_VR',
 SEC='1',
 CDS_LIB='mstr_discrete',
 CDS_PART_NAME='CAP_0402-1.0UF,16V,10%,X6S,D97A',
 VOLTAGE='16V',
 PRIM_FILE='./archive_libs/mstr_discrete/cap/chips/chips.prt';

PART_NAME
 C4D11 'CAP_A_0402V-0.1UF,16V,10%,X7R,A':
 ROOM='PVCCIN_CPU0_PWR_VR';

SECTION_NUMBER 1
 '@BASEBOARD_FAB2_LIB.BASEBOARD_FAB2(SCH_1):PAGE203_I52@DEV_DISCRETE.CAP_A(CHIPS)':
 C_PATH='@baseboard_fab2_lib.baseboard_fab2(sch_1):page203_i52@dev_discrete.cap_~
a(chips)',
 P_PATH='@baseboard_fab2_lib.baseboard_fab2(sch_1):page203_i52@dev_discrete.cap_~
a(chips)',
 PATH='I52',
 DRAWING='@BASEBOARD_FAB2_LIB.BASEBOARD_FAB2(SCH_1):PAGE203',
 TOLERANCE='10%',
 SEC_TYPE='0402V',
 MATERIAL='X7R',
 PHYS_PAGE='203',
 XY='(-5975,1475)',
 ROT='0',
 VER='1',
 VALUE='0.1UF',
 PACK_TYPE='0402V',
 PART_NUMBER='A36096-030',
 LOCATION='C4D11',
 ROOM='PVCCIN_CPU0_PWR_VR',
 SEC='1',
 CDS_LIB='dev_discrete',
 CDS_PART_NAME='CAP_A_0402V-0.1UF,16V,10%,X7R,A',
 VOLTAGE='16V',
 PRIM_FILE='./archive_libs/discrete/cap_a/chips/chips.prt';

PART_NAME
 C4D12 'CAP_A_0603V-22.0UF,4V,20%,X6S,A':
 GROUP='PWR_MLCC_CAP',
 ROOM='PVCCIN_CPU0_PWR_VR';

SECTION_NUMBER 1
 '@BASEBOARD_FAB2_LIB.BASEBOARD_FAB2(SCH_1):PAGE204_I9@DEV_DISCRETE.CAP_A(CHIPS)':
 C_PATH='@baseboard_fab2_lib.baseboard_fab2(sch_1):page204_i9@dev_discrete.cap_a~
(chips)',
 P_PATH='@baseboard_fab2_lib.baseboard_fab2(sch_1):page204_i9@dev_discrete.cap_a~
(chips)',
 PATH='I9',
 DRAWING='@BASEBOARD_FAB2_LIB.BASEBOARD_FAB2(SCH_1):PAGE204',
 TOLERANCE='20%',
 SEC_TYPE='0603V',
 MATERIAL='X6S',
 BOM_COST='PROC_VRD_VCCIN_CPU0',
 PHYS_PAGE='204',
 XY='(-700,3425)',
 ROT='0',
 VER='1',
 VALUE='22.0UF',
 PACK_TYPE='0603V',
 PART_NUMBER='E15431-004',
 LOCATION='C4D12',
 ROOM='PVCCIN_CPU0_PWR_VR',
 GROUP='PWR_MLCC_CAP',
 SEC='1',
 CDS_LIB='dev_discrete',
 CDS_PART_NAME='CAP_A_0603V-22.0UF,4V,20%,X6S,A',
 VOLTAGE='4V',
 PRIM_FILE='./archive_libs/discrete/cap_a/chips/chips.prt';

PART_NAME
 C4D13 'CAP_0402-0.22UF,16V,10%,X7R,A3A':
 ROOM='PVCCIN_CPU0_PWR_VR';

SECTION_NUMBER 1
 '@BASEBOARD_FAB2_LIB.BASEBOARD_FAB2(SCH_1):PAGE203_I40@MSTR_DISCRETE.CAP(CHIPS)':
 C_PATH='@baseboard_fab2_lib.baseboard_fab2(sch_1):page203_i40@mstr_discrete.cap~
(chips)',
 P_PATH='@baseboard_fab2_lib.baseboard_fab2(sch_1):page203_i40@mstr_discrete.cap~
(chips)',
 PATH='I40',
 DRAWING='@BASEBOARD_FAB2_LIB.BASEBOARD_FAB2(SCH_1):PAGE203',
 TOLERANCE='10%',
 SEC_TYPE='0402',
 MATERIAL='X7R',
 PHYS_PAGE='203',
 XY='(-4600,4150)',
 ROT='0',
 VER='1',
 VALUE='0.22UF',
 PACK_TYPE='0402',
 PART_NUMBER='A36096-155',
 LOCATION='C4D13',
 ROOM='PVCCIN_CPU0_PWR_VR',
 SEC='1',
 CDS_LIB='mstr_discrete',
 CDS_PART_NAME='CAP_0402-0.22UF,16V,10%,X7R,A3A',
 VOLTAGE='16V',
 PRIM_FILE='./archive_libs/mstr_discrete/cap/chips/chips.prt';

PART_NAME
 C4D14 'SC1U10V2KX-4-GP_SMD-BCG6-SC1U1A':;

SECTION_NUMBER 1
 '@BASEBOARD_FAB2_LIB.BASEBOARD_FAB2(SCH_1):PAGE203_I132@W_HDL.SC1U10V2KX-4-GP(CHIPS)':
 C_PATH='@baseboard_fab2_lib.baseboard_fab2(sch_1):page203_i132@w_hdl.\sc1u10v2k~
x-4-gp\(chips)',
 P_PATH='@baseboard_fab2_lib.baseboard_fab2(sch_1):page203_i132@w_hdl.\sc1u10v2k~
x-4-gp\(chips)',
 PATH='I132',
 DRAWING='@BASEBOARD_FAB2_LIB.BASEBOARD_FAB2(SCH_1):PAGE203',
 PACK_SIZE='0402',
 RATED='10V',
 ATTRIBUTE='1UF',
 TOLERANCE='10%',
 SEC_TYPE='SMD-BCG6',
 PHYS_PAGE='203',
 XY='(-5050,4150)',
 ROT='0',
 VER='1',
 VALUE='SC1U10V2KX-4-GP',
 PACK_TYPE='SMD-BCG6',
 PART_NUMBER='78.10523.8FL',
 LOCATION='C4D14',
 SEC='1',
 CDS_LIB='w_hdl',
 CDS_PART_NAME='SC1U10V2KX-4-GP_SMD-BCG6-SC1U1A',
 PRIM_FILE='C:/<user>/w_hdl/sc1u10v2kx#2d4#2dgp/chips/chips.prt';

PART_NAME
 C4D15 'CAP_A_0402V-1.0UF,6.3V,10%,X6SA':
 ROOM='PVCCIN_CPU0_VR';

SECTION_NUMBER 1
 '@BASEBOARD_FAB2_LIB.BASEBOARD_FAB2(SCH_1):PAGE201_I37@DEV_DISCRETE.CAP_A(CHIPS)':
 C_PATH='@baseboard_fab2_lib.baseboard_fab2(sch_1):page201_i37@dev_discrete.cap_~
a(chips)',
 P_PATH='@baseboard_fab2_lib.baseboard_fab2(sch_1):page201_i37@dev_discrete.cap_~
a(chips)',
 PATH='I37',
 DRAWING='@BASEBOARD_FAB2_LIB.BASEBOARD_FAB2(SCH_1):PAGE201',
 TOLERANCE='10%',
 SEC_TYPE='0402V',
 MATERIAL='X6S',
 PHYS_PAGE='201',
 XY='(-3550,3925)',
 ROT='0',
 VER='1',
 VALUE='1.0UF',
 PACK_TYPE='0402V',
 PART_NUMBER='D97712-004',
 LOCATION='C4D15',
 ROOM='PVCCIN_CPU0_VR',
 SEC='1',
 CDS_LIB='dev_discrete',
 CDS_PART_NAME='CAP_A_0402V-1.0UF,6.3V,10%,X6SA',
 VOLTAGE='6.3V',
 PRIM_FILE='./archive_libs/discrete/cap_a/chips/chips.prt';

PART_NAME
 C4D16 'CAP_0402-1.0UF,16V,10%,X6S,D97A':
 ROOM='PVCCIN_CPU0_PWR_VR';

SECTION_NUMBER 1
 '@BASEBOARD_FAB2_LIB.BASEBOARD_FAB2(SCH_1):PAGE203_I45@MSTR_DISCRETE.CAP(CHIPS)':
 C_PATH='@baseboard_fab2_lib.baseboard_fab2(sch_1):page203_i45@mstr_discrete.cap~
(chips)',
 P_PATH='@baseboard_fab2_lib.baseboard_fab2(sch_1):page203_i45@mstr_discrete.cap~
(chips)',
 PATH='I45',
 DRAWING='@BASEBOARD_FAB2_LIB.BASEBOARD_FAB2(SCH_1):PAGE203',
 TOLERANCE='10%',
 SEC_TYPE='0402',
 MATERIAL='X6S',
 PHYS_PAGE='203',
 XY='(-5475,4150)',
 ROT='0',
 VER='1',
 VALUE='1.0UF',
 PACK_TYPE='0402',
 PART_NUMBER='D97712-011',
 LOCATION='C4D16',
 ROOM='PVCCIN_CPU0_PWR_VR',
 SEC='1',
 CDS_LIB='mstr_discrete',
 CDS_PART_NAME='CAP_0402-1.0UF,16V,10%,X6S,D97A',
 VOLTAGE='16V',
 PRIM_FILE='./archive_libs/mstr_discrete/cap/chips/chips.prt';

PART_NAME
 C4D17 'CAP_0402LF-220PF,50V,10%,X7R,AA':
 ROOM='PVCCIN_CPU0_VR';

SECTION_NUMBER 1
 '@BASEBOARD_FAB2_LIB.BASEBOARD_FAB2(SCH_1):PAGE201_I66@MSTR_DISCRETE.CAP(CHIPS)':
 C_PATH='@baseboard_fab2_lib.baseboard_fab2(sch_1):page201_i66@mstr_discrete.cap~
(chips)',
 P_PATH='@baseboard_fab2_lib.baseboard_fab2(sch_1):page201_i66@mstr_discrete.cap~
(chips)',
 PATH='I66',
 DRAWING='@BASEBOARD_FAB2_LIB.BASEBOARD_FAB2(SCH_1):PAGE201',
 TOLERANCE='10%',
 SEC_TYPE='0402LF',
 MATERIAL='X7R',
 PHYS_PAGE='201',
 XY='(-5425,1275)',
 ROT='0',
 VER='1',
 VALUE='220PF',
 PACK_TYPE='0402LF',
 PART_NUMBER='A36096-050',
 LOCATION='C4D17',
 ROOM='PVCCIN_CPU0_VR',
 SEC='1',
 CDS_LIB='mstr_discrete',
 CDS_PART_NAME='CAP_0402LF-220PF,50V,10%,X7R,AA',
 VOLTAGE='50V',
 PRIM_FILE='./archive_libs/mstr_discrete/cap/chips/chips.prt';

PART_NAME
 C4D18 'CAP_0402LF-220PF,50V,10%,X7R,AA':
 ROOM='PVCCIN_CPU0_VR';

SECTION_NUMBER 1
 '@BASEBOARD_FAB2_LIB.BASEBOARD_FAB2(SCH_1):PAGE201_I68@MSTR_DISCRETE.CAP(CHIPS)':
 C_PATH='@baseboard_fab2_lib.baseboard_fab2(sch_1):page201_i68@mstr_discrete.cap~
(chips)',
 P_PATH='@baseboard_fab2_lib.baseboard_fab2(sch_1):page201_i68@mstr_discrete.cap~
(chips)',
 PATH='I68',
 DRAWING='@BASEBOARD_FAB2_LIB.BASEBOARD_FAB2(SCH_1):PAGE201',
 TOLERANCE='10%',
 SEC_TYPE='0402LF',
 MATERIAL='X7R',
 PHYS_PAGE='201',
 XY='(-5125,1000)',
 ROT='2',
 VER='1',
 VALUE='220PF',
 PACK_TYPE='0402LF',
 PART_NUMBER='A36096-050',
 LOCATION='C4D18',
 ROOM='PVCCIN_CPU0_VR',
 SEC='1',
 CDS_LIB='mstr_discrete',
 CDS_PART_NAME='CAP_0402LF-220PF,50V,10%,X7R,AA',
 VOLTAGE='50V',
 PRIM_FILE='./archive_libs/mstr_discrete/cap/chips/chips.prt';

PART_NAME
 C4D19 'CAP_A_0402V-0.1UF,16V,10%,X7R,A':
 ROOM='PVCCIN_CPU0_VR';

SECTION_NUMBER 1
 '@BASEBOARD_FAB2_LIB.BASEBOARD_FAB2(SCH_1):PAGE201_I39@DEV_DISCRETE.CAP_A(CHIPS)':
 C_PATH='@baseboard_fab2_lib.baseboard_fab2(sch_1):page201_i39@dev_discrete.cap_~
a(chips)',
 P_PATH='@baseboard_fab2_lib.baseboard_fab2(sch_1):page201_i39@dev_discrete.cap_~
a(chips)',
 PATH='I39',
 DRAWING='@BASEBOARD_FAB2_LIB.BASEBOARD_FAB2(SCH_1):PAGE201',
 TOLERANCE='10%',
 SEC_TYPE='0402V',
 MATERIAL='X7R',
 PHYS_PAGE='201',
 XY='(-3950,3925)',
 ROT='0',
 VER='1',
 VALUE='0.1UF',
 PACK_TYPE='0402V',
 PART_NUMBER='A36096-030',
 LOCATION='C4D19',
 ROOM='PVCCIN_CPU0_VR',
 SEC='1',
 CDS_LIB='dev_discrete',
 CDS_PART_NAME='CAP_A_0402V-0.1UF,16V,10%,X7R,A',
 VOLTAGE='16V',
 PRIM_FILE='./archive_libs/discrete/cap_a/chips/chips.prt';

PART_NAME
 C4D20 'CAP_A_0402V-0.1UF,16V,10%,X7R,A':
 ROOM='CPU_FANS';

SECTION_NUMBER 1
 '@BASEBOARD_FAB2_LIB.BASEBOARD_FAB2(SCH_1):PAGE201_I192@DEV_DISCRETE.CAP_A(CHIPS)':
 C_PATH='@baseboard_fab2_lib.baseboard_fab2(sch_1):page201_i192@dev_discrete.cap~
_a(chips)',
 P_PATH='@baseboard_fab2_lib.baseboard_fab2(sch_1):page201_i192@dev_discrete.cap~
_a(chips)',
 PATH='I192',
 DRAWING='@BASEBOARD_FAB2_LIB.BASEBOARD_FAB2(SCH_1):PAGE201',
 TOLERANCE='10%',
 SEC_TYPE='0402V',
 MATERIAL='X7R',
 BOM_COST='SM_THERM',
 PHYS_PAGE='201',
 XY='(-6600,4200)',
 ROT='0',
 VER='1',
 VALUE='0.1UF',
 PACK_TYPE='0402V',
 PART_NUMBER='A36096-030',
 LOCATION='C4D20',
 ROOM='CPU_FANS',
 SEC='1',
 CDS_LIB='dev_discrete',
 CDS_PART_NAME='CAP_A_0402V-0.1UF,16V,10%,X7R,A',
 VOLTAGE='16V',
 PRIM_FILE='./archive_libs/discrete/cap_a/chips/chips.prt';

PART_NAME
 C4D22 'CAP_A_0402V-0.1UF,16V,10%,X7R,A':
 ROOM='DB1200ZL';

SECTION_NUMBER 1
 '@BASEBOARD_FAB2_LIB.BASEBOARD_FAB2(SCH_1):PAGE102_I28@DEV_DISCRETE.CAP_A(CHIPS)':
 C_PATH='@baseboard_fab2_lib.baseboard_fab2(sch_1):page102_i28@dev_discrete.cap_~
a(chips)',
 P_PATH='@baseboard_fab2_lib.baseboard_fab2(sch_1):page102_i28@dev_discrete.cap_~
a(chips)',
 PATH='I28',
 DRAWING='@BASEBOARD_FAB2_LIB.BASEBOARD_FAB2(SCH_1):PAGE102',
 TOLERANCE='10%',
 SEC_TYPE='0402V',
 MATERIAL='X7R',
 BOM_COST='SYS_CLOCK',
 PHYS_PAGE='102',
 XY='(-2325,3225)',
 ROT='0',
 VER='1',
 VALUE='0.1UF',
 PACK_TYPE='0402V',
 PART_NUMBER='A36096-030',
 LOCATION='C4D22',
 ROOM='DB1200ZL',
 SEC='1',
 CDS_LIB='dev_discrete',
 CDS_PART_NAME='CAP_A_0402V-0.1UF,16V,10%,X7R,A',
 VOLTAGE='16V',
 PRIM_FILE='./archive_libs/discrete/cap_a/chips/chips.prt';

PART_NAME
 C4D23 'CAP_A_0402V-1.0UF,6.3V,10%,X6SA':
 ROOM='DB1200ZL';

SECTION_NUMBER 1
 '@BASEBOARD_FAB2_LIB.BASEBOARD_FAB2(SCH_1):PAGE102_I19@DEV_DISCRETE.CAP_A(CHIPS)':
 C_PATH='@baseboard_fab2_lib.baseboard_fab2(sch_1):page102_i19@dev_discrete.cap_~
a(chips)',
 P_PATH='@baseboard_fab2_lib.baseboard_fab2(sch_1):page102_i19@dev_discrete.cap_~
a(chips)',
 PATH='I19',
 DRAWING='@BASEBOARD_FAB2_LIB.BASEBOARD_FAB2(SCH_1):PAGE102',
 TOLERANCE='10%',
 SEC_TYPE='0402V',
 MATERIAL='X6S',
 BOM_COST='SYS_CLOCK',
 PHYS_PAGE='102',
 XY='(-1800,3900)',
 ROT='0',
 VER='1',
 VALUE='1.0UF',
 PACK_TYPE='0402V',
 PART_NUMBER='D97712-004',
 LOCATION='C4D23',
 ROOM='DB1200ZL',
 SEC='1',
 CDS_LIB='dev_discrete',
 CDS_PART_NAME='CAP_A_0402V-1.0UF,6.3V,10%,X6SA',
 VOLTAGE='6.3V',
 PRIM_FILE='./archive_libs/discrete/cap_a/chips/chips.prt';

PART_NAME
 C4D24 'CAP_A_0402V-0.1UF,16V,10%,X7R,A':
 ROOM='DB1200ZL';

SECTION_NUMBER 1
 '@BASEBOARD_FAB2_LIB.BASEBOARD_FAB2(SCH_1):PAGE102_I18@DEV_DISCRETE.CAP_A(CHIPS)':
 C_PATH='@baseboard_fab2_lib.baseboard_fab2(sch_1):page102_i18@dev_discrete.cap_~
a(chips)',
 P_PATH='@baseboard_fab2_lib.baseboard_fab2(sch_1):page102_i18@dev_discrete.cap_~
a(chips)',
 PATH='I18',
 DRAWING='@BASEBOARD_FAB2_LIB.BASEBOARD_FAB2(SCH_1):PAGE102',
 TOLERANCE='10%',
 SEC_TYPE='0402V',
 MATERIAL='X7R',
 BOM_COST='SYS_CLOCK',
 PHYS_PAGE='102',
 XY='(-1550,3900)',
 ROT='0',
 VER='1',
 VALUE='0.1UF',
 PACK_TYPE='0402V',
 PART_NUMBER='A36096-030',
 LOCATION='C4D24',
 ROOM='DB1200ZL',
 SEC='1',
 CDS_LIB='dev_discrete',
 CDS_PART_NAME='CAP_A_0402V-0.1UF,16V,10%,X7R,A',
 VOLTAGE='16V',
 PRIM_FILE='./archive_libs/discrete/cap_a/chips/chips.prt';

PART_NAME
 C4D25 'CAP_A_0402V-1.0UF,6.3V,10%,X6SA':
 ROOM='PVCCIN_CPU0_VR';

SECTION_NUMBER 1
 '@BASEBOARD_FAB2_LIB.BASEBOARD_FAB2(SCH_1):PAGE201_I30@DEV_DISCRETE.CAP_A(CHIPS)':
 C_PATH='@baseboard_fab2_lib.baseboard_fab2(sch_1):page201_i30@dev_discrete.cap_~
a(chips)',
 P_PATH='@baseboard_fab2_lib.baseboard_fab2(sch_1):page201_i30@dev_discrete.cap_~
a(chips)',
 PATH='I30',
 DRAWING='@BASEBOARD_FAB2_LIB.BASEBOARD_FAB2(SCH_1):PAGE201',
 TOLERANCE='10%',
 SEC_TYPE='0402V',
 MATERIAL='X6S',
 PHYS_PAGE='201',
 XY='(-1475,1000)',
 ROT='0',
 VER='1',
 VALUE='1.0UF',
 PACK_TYPE='0402V',
 PART_NUMBER='D97712-004',
 LOCATION='C4D25',
 ROOM='PVCCIN_CPU0_VR',
 SEC='1',
 CDS_LIB='dev_discrete',
 CDS_PART_NAME='CAP_A_0402V-1.0UF,6.3V,10%,X6SA',
 VOLTAGE='6.3V',
 PRIM_FILE='./archive_libs/discrete/cap_a/chips/chips.prt';

PART_NAME
 C4D26 'CAP_A_0402V-0.1UF,16V,10%,X7R,A':
 ROOM='PVCCIN_CPU0_VR';

SECTION_NUMBER 1
 '@BASEBOARD_FAB2_LIB.BASEBOARD_FAB2(SCH_1):PAGE201_I32@DEV_DISCRETE.CAP_A(CHIPS)':
 C_PATH='@baseboard_fab2_lib.baseboard_fab2(sch_1):page201_i32@dev_discrete.cap_~
a(chips)',
 P_PATH='@baseboard_fab2_lib.baseboard_fab2(sch_1):page201_i32@dev_discrete.cap_~
a(chips)',
 PATH='I32',
 DRAWING='@BASEBOARD_FAB2_LIB.BASEBOARD_FAB2(SCH_1):PAGE201',
 TOLERANCE='10%',
 SEC_TYPE='0402V',
 MATERIAL='X7R',
 PHYS_PAGE='201',
 XY='(-1875,1000)',
 ROT='0',
 VER='1',
 VALUE='0.1UF',
 PACK_TYPE='0402V',
 PART_NUMBER='A36096-030',
 LOCATION='C4D26',
 ROOM='PVCCIN_CPU0_VR',
 SEC='1',
 CDS_LIB='dev_discrete',
 CDS_PART_NAME='CAP_A_0402V-0.1UF,16V,10%,X7R,A',
 VOLTAGE='16V',
 PRIM_FILE='./archive_libs/discrete/cap_a/chips/chips.prt';

PART_NAME
 C4D27 'CAP_A_0402V-1.0UF,6.3V,10%,X6SA':
 ROOM='DB1200ZL';

SECTION_NUMBER 1
 '@BASEBOARD_FAB2_LIB.BASEBOARD_FAB2(SCH_1):PAGE102_I30@DEV_DISCRETE.CAP_A(CHIPS)':
 C_PATH='@baseboard_fab2_lib.baseboard_fab2(sch_1):page102_i30@dev_discrete.cap_~
a(chips)',
 P_PATH='@baseboard_fab2_lib.baseboard_fab2(sch_1):page102_i30@dev_discrete.cap_~
a(chips)',
 PATH='I30',
 DRAWING='@BASEBOARD_FAB2_LIB.BASEBOARD_FAB2(SCH_1):PAGE102',
 TOLERANCE='10%',
 SEC_TYPE='0402V',
 MATERIAL='X6S',
 BOM_COST='SYS_CLOCK',
 PHYS_PAGE='102',
 XY='(-2575,3225)',
 ROT='0',
 VER='1',
 VALUE='1.0UF',
 PACK_TYPE='0402V',
 PART_NUMBER='D97712-004',
 LOCATION='C4D27',
 ROOM='DB1200ZL',
 SEC='1',
 CDS_LIB='dev_discrete',
 CDS_PART_NAME='CAP_A_0402V-1.0UF,6.3V,10%,X6SA',
 VOLTAGE='6.3V',
 PRIM_FILE='./archive_libs/discrete/cap_a/chips/chips.prt';

PART_NAME
 C4D28 'CAP_0402-0.220UF,16V,10%,X7R,AA':
 ROOM='PVCCIN_CPU0_PWR_VR',
 NO_XNET_CONNECTION='1';

SECTION_NUMBER 1
 '@BASEBOARD_FAB2_LIB.BASEBOARD_FAB2(SCH_1):PAGE203_I42@MSTR_DISCRETE.CAP(CHIPS)':
 C_PATH='@baseboard_fab2_lib.baseboard_fab2(sch_1):page203_i42@mstr_discrete.cap~
(chips)',
 P_PATH='@baseboard_fab2_lib.baseboard_fab2(sch_1):page203_i42@mstr_discrete.cap~
(chips)',
 PATH='I42',
 DRAWING='@BASEBOARD_FAB2_LIB.BASEBOARD_FAB2(SCH_1):PAGE203',
 SPOF='TRUE',
 TOLERANCE='10%',
 SEC_TYPE='0402',
 MATERIAL='X7R',
 NO_XNET_CONNECTION='1',
 PHYS_PAGE='203',
 XY='(-5800,3550)',
 ROT='2',
 VER='1',
 VALUE='0.220UF',
 PACK_TYPE='0402',
 PART_NUMBER='A36096-104',
 LOCATION='C4D28',
 ROOM='PVCCIN_CPU0_PWR_VR',
 SEC='1',
 CDS_LIB='mstr_discrete',
 CDS_PART_NAME='CAP_0402-0.220UF,16V,10%,X7R,AA',
 VOLTAGE='16V',
 PRIM_FILE='./archive_libs/mstr_discrete/cap/chips/chips.prt';

PART_NAME
 C4D29 'CAP_0402LF-220PF,50V,10%,X7R,AA':
 ROOM='PVCCIN_CPU0_VR',
 NO_XNET_CONNECTION='1';

SECTION_NUMBER 1
 '@BASEBOARD_FAB2_LIB.BASEBOARD_FAB2(SCH_1):PAGE201_I64@MSTR_DISCRETE.CAP(CHIPS)':
 C_PATH='@baseboard_fab2_lib.baseboard_fab2(sch_1):page201_i64@mstr_discrete.cap~
(chips)',
 P_PATH='@baseboard_fab2_lib.baseboard_fab2(sch_1):page201_i64@mstr_discrete.cap~
(chips)',
 PATH='I64',
 DRAWING='@BASEBOARD_FAB2_LIB.BASEBOARD_FAB2(SCH_1):PAGE201',
 TOLERANCE='10%',
 SEC_TYPE='0402LF',
 MATERIAL='X7R',
 NO_XNET_CONNECTION='1',
 PHYS_PAGE='201',
 XY='(-5550,2075)',
 ROT='0',
 VER='1',
 VALUE='220PF',
 PACK_TYPE='0402LF',
 PART_NUMBER='A36096-050',
 LOCATION='C4D29',
 ROOM='PVCCIN_CPU0_VR',
 SEC='1',
 CDS_LIB='mstr_discrete',
 CDS_PART_NAME='CAP_0402LF-220PF,50V,10%,X7R,AA',
 VOLTAGE='50V',
 PRIM_FILE='./archive_libs/mstr_discrete/cap/chips/chips.prt';

PART_NAME
 C4D30 'CAP_0402-1.0UF,16V,10%,X6S,D97A':
 ROOM='PVCCIN_CPU0_PWR_VR';

SECTION_NUMBER 1
 '@BASEBOARD_FAB2_LIB.BASEBOARD_FAB2(SCH_1):PAGE203_I47@MSTR_DISCRETE.CAP(CHIPS)':
 C_PATH='@baseboard_fab2_lib.baseboard_fab2(sch_1):page203_i47@mstr_discrete.cap~
(chips)',
 P_PATH='@baseboard_fab2_lib.baseboard_fab2(sch_1):page203_i47@mstr_discrete.cap~
(chips)',
 PATH='I47',
 DRAWING='@BASEBOARD_FAB2_LIB.BASEBOARD_FAB2(SCH_1):PAGE203',
 TOLERANCE='10%',
 SEC_TYPE='0402',
 MATERIAL='X6S',
 PHYS_PAGE='203',
 XY='(-6050,4150)',
 ROT='0',
 VER='1',
 VALUE='1.0UF',
 PACK_TYPE='0402',
 PART_NUMBER='D97712-011',
 LOCATION='C4D30',
 ROOM='PVCCIN_CPU0_PWR_VR',
 SEC='1',
 CDS_LIB='mstr_discrete',
 CDS_PART_NAME='CAP_0402-1.0UF,16V,10%,X6S,D97A',
 VOLTAGE='16V',
 PRIM_FILE='./archive_libs/mstr_discrete/cap/chips/chips.prt';

PART_NAME
 C4D31 'CAP_A_0402V-1.0UF,6.3V,10%,X6SA':
 ROOM='PVCCIO_CPU1';

SECTION_NUMBER 1
 '@BASEBOARD_FAB2_LIB.BASEBOARD_FAB2(SCH_1):PAGE213_I9@DEV_DISCRETE.CAP_A(CHIPS)':
 C_PATH='@baseboard_fab2_lib.baseboard_fab2(sch_1):page213_i9@dev_discrete.cap_a~
(chips)',
 P_PATH='@baseboard_fab2_lib.baseboard_fab2(sch_1):page213_i9@dev_discrete.cap_a~
(chips)',
 PATH='I9',
 DRAWING='@BASEBOARD_FAB2_LIB.BASEBOARD_FAB2(SCH_1):PAGE213',
 TOLERANCE='10%',
 SEC_TYPE='0402V',
 MATERIAL='X6S',
 PHYS_PAGE='213',
 XY='(2425,1575)',
 ROT='0',
 VER='1',
 VALUE='1.0UF',
 PACK_TYPE='0402V',
 PART_NUMBER='D97712-004',
 LOCATION='C4D31',
 ROOM='PVCCIO_CPU1',
 SEC='1',
 CDS_LIB='dev_discrete',
 CDS_PART_NAME='CAP_A_0402V-1.0UF,6.3V,10%,X6SA',
 VOLTAGE='6.3V',
 PRIM_FILE='./archive_libs/discrete/cap_a/chips/chips.prt';

PART_NAME
 C4D32 'CAP_A_0402V-0.1UF,16V,10%,X7R,A':
 ROOM='PVCCIO_CPU1';

SECTION_NUMBER 1
 '@BASEBOARD_FAB2_LIB.BASEBOARD_FAB2(SCH_1):PAGE213_I11@DEV_DISCRETE.CAP_A(CHIPS)':
 C_PATH='@baseboard_fab2_lib.baseboard_fab2(sch_1):page213_i11@dev_discrete.cap_~
a(chips)',
 P_PATH='@baseboard_fab2_lib.baseboard_fab2(sch_1):page213_i11@dev_discrete.cap_~
a(chips)',
 PATH='I11',
 DRAWING='@BASEBOARD_FAB2_LIB.BASEBOARD_FAB2(SCH_1):PAGE213',
 TOLERANCE='10%',
 SEC_TYPE='0402V',
 MATERIAL='X7R',
 PHYS_PAGE='213',
 XY='(2025,1575)',
 ROT='0',
 VER='1',
 VALUE='0.1UF',
 PACK_TYPE='0402V',
 PART_NUMBER='A36096-030',
 LOCATION='C4D32',
 ROOM='PVCCIO_CPU1',
 SEC='1',
 CDS_LIB='dev_discrete',
 CDS_PART_NAME='CAP_A_0402V-0.1UF,16V,10%,X7R,A',
 VOLTAGE='16V',
 PRIM_FILE='./archive_libs/discrete/cap_a/chips/chips.prt';

PART_NAME
 C4D33 'CAP_0402LF-1000PF,50V,10%,X7R,A':
 ROOM='PVCCIO_CPU1_VR';

SECTION_NUMBER 1
 '@BASEBOARD_FAB2_LIB.BASEBOARD_FAB2(SCH_1):PAGE213_I73@MSTR_DISCRETE.CAP(CHIPS)':
 C_PATH='@baseboard_fab2_lib.baseboard_fab2(sch_1):page213_i73@mstr_discrete.cap~
(chips)',
 P_PATH='@baseboard_fab2_lib.baseboard_fab2(sch_1):page213_i73@mstr_discrete.cap~
(chips)',
 PATH='I73',
 DRAWING='@BASEBOARD_FAB2_LIB.BASEBOARD_FAB2(SCH_1):PAGE213',
 TOLERANCE='10%',
 SEC_TYPE='0402LF',
 MATERIAL='X7R',
 PHYS_PAGE='213',
 XY='(1750,2700)',
 ROT='0',
 VER='1',
 VALUE='1000PF',
 PACK_TYPE='0402LF',
 PART_NUMBER='A36096-046',
 LOCATION='C4D33',
 ROOM='PVCCIO_CPU1_VR',
 SEC='1',
 CDS_LIB='mstr_discrete',
 CDS_PART_NAME='CAP_0402LF-1000PF,50V,10%,X7R,A',
 VOLTAGE='50V',
 PRIM_FILE='./archive_libs/mstr_discrete/cap/chips/chips.prt';

PART_NAME
 C4D34 'CAP_A_0603V-22.0UF,4V,20%,X6S,A':
 GROUP='PWR_MLCC_CAP';

SECTION_NUMBER 1
 '@BASEBOARD_FAB2_LIB.BASEBOARD_FAB2(SCH_1):PAGE203_I68@DEV_DISCRETE.CAP_A(CHIPS)':
 C_PATH='@baseboard_fab2_lib.baseboard_fab2(sch_1):page203_i68@dev_discrete.cap_~
a(chips)',
 P_PATH='@baseboard_fab2_lib.baseboard_fab2(sch_1):page203_i68@dev_discrete.cap_~
a(chips)',
 PATH='I68',
 DRAWING='@BASEBOARD_FAB2_LIB.BASEBOARD_FAB2(SCH_1):PAGE203',
 TOLERANCE='20%',
 SEC_TYPE='0603V',
 MATERIAL='X6S',
 PHYS_PAGE='203',
 XY='(-500,3450)',
 ROT='0',
 VER='1',
 VALUE='22.0UF',
 PACK_TYPE='0603V',
 PART_NUMBER='E15431-004',
 LOCATION='C4D34',
 GROUP='PWR_MLCC_CAP',
 SEC='1',
 CDS_LIB='dev_discrete',
 CDS_PART_NAME='CAP_A_0603V-22.0UF,4V,20%,X6S,A',
 VOLTAGE='4V',
 PRIM_FILE='./archive_libs/discrete/cap_a/chips/chips.prt';

PART_NAME
 C4D35 'CAP_A_0402V-0.1UF,16V,10%,X7R,A':
 ROOM='PVCCIN_CPU0_PWR_VR';

SECTION_NUMBER 1
 '@BASEBOARD_FAB2_LIB.BASEBOARD_FAB2(SCH_1):PAGE203_I46@DEV_DISCRETE.CAP_A(CHIPS)':
 C_PATH='@baseboard_fab2_lib.baseboard_fab2(sch_1):page203_i46@dev_discrete.cap_~
a(chips)',
 P_PATH='@baseboard_fab2_lib.baseboard_fab2(sch_1):page203_i46@dev_discrete.cap_~
a(chips)',
 PATH='I46',
 DRAWING='@BASEBOARD_FAB2_LIB.BASEBOARD_FAB2(SCH_1):PAGE203',
 TOLERANCE='10%',
 SEC_TYPE='0402V',
 MATERIAL='X7R',
 PHYS_PAGE='203',
 XY='(-5775,4150)',
 ROT='0',
 VER='1',
 VALUE='0.1UF',
 PACK_TYPE='0402V',
 PART_NUMBER='A36096-030',
 LOCATION='C4D35',
 ROOM='PVCCIN_CPU0_PWR_VR',
 SEC='1',
 CDS_LIB='dev_discrete',
 CDS_PART_NAME='CAP_A_0402V-0.1UF,16V,10%,X7R,A',
 VOLTAGE='16V',
 PRIM_FILE='./archive_libs/discrete/cap_a/chips/chips.prt';

PART_NAME
 C4D36 'CAP_A_0402V-1.0UF,6.3V,10%,X6SA':
 ROOM='PVCCIO_CPU1';

SECTION_NUMBER 1
 '@BASEBOARD_FAB2_LIB.BASEBOARD_FAB2(SCH_1):PAGE213_I17@DEV_DISCRETE.CAP_A(CHIPS)':
 C_PATH='@baseboard_fab2_lib.baseboard_fab2(sch_1):page213_i17@dev_discrete.cap_~
a(chips)',
 P_PATH='@baseboard_fab2_lib.baseboard_fab2(sch_1):page213_i17@dev_discrete.cap_~
a(chips)',
 PATH='I17',
 DRAWING='@BASEBOARD_FAB2_LIB.BASEBOARD_FAB2(SCH_1):PAGE213',
 TOLERANCE='10%',
 SEC_TYPE='0402V',
 MATERIAL='X6S',
 PHYS_PAGE='213',
 XY='(150,4150)',
 ROT='0',
 VER='1',
 VALUE='1.0UF',
 PACK_TYPE='0402V',
 PART_NUMBER='D97712-004',
 LOCATION='C4D36',
 ROOM='PVCCIO_CPU1',
 SEC='1',
 CDS_LIB='dev_discrete',
 CDS_PART_NAME='CAP_A_0402V-1.0UF,6.3V,10%,X6SA',
 VOLTAGE='6.3V',
 PRIM_FILE='./archive_libs/discrete/cap_a/chips/chips.prt';

PART_NAME
 C4D38 'CAP_A_0402V-0.1UF,16V,10%,X7R,A':
 ROOM='PVCCIO_CPU1';

SECTION_NUMBER 1
 '@BASEBOARD_FAB2_LIB.BASEBOARD_FAB2(SCH_1):PAGE213_I35@DEV_DISCRETE.CAP_A(CHIPS)':
 C_PATH='@baseboard_fab2_lib.baseboard_fab2(sch_1):page213_i35@dev_discrete.cap_~
a(chips)',
 P_PATH='@baseboard_fab2_lib.baseboard_fab2(sch_1):page213_i35@dev_discrete.cap_~
a(chips)',
 PATH='I35',
 DRAWING='@BASEBOARD_FAB2_LIB.BASEBOARD_FAB2(SCH_1):PAGE213',
 TOLERANCE='10%',
 SEC_TYPE='0402V',
 MATERIAL='X7R',
 PHYS_PAGE='213',
 XY='(-250,4150)',
 ROT='0',
 VER='1',
 VALUE='0.1UF',
 PACK_TYPE='0402V',
 PART_NUMBER='A36096-030',
 LOCATION='C4D38',
 ROOM='PVCCIO_CPU1',
 SEC='1',
 CDS_LIB='dev_discrete',
 CDS_PART_NAME='CAP_A_0402V-0.1UF,16V,10%,X7R,A',
 VOLTAGE='16V',
 PRIM_FILE='./archive_libs/discrete/cap_a/chips/chips.prt';

PART_NAME
 C4D40 'CAP_A_0402V-0.1UF,16V,10%,X7R,A':
 ROOM='CPU_FANS';

SECTION_NUMBER 1
 '@BASEBOARD_FAB2_LIB.BASEBOARD_FAB2(SCH_1):PAGE213_I105@DEV_DISCRETE.CAP_A(CHIPS)':
 C_PATH='@baseboard_fab2_lib.baseboard_fab2(sch_1):page213_i105@dev_discrete.cap~
_a(chips)',
 P_PATH='@baseboard_fab2_lib.baseboard_fab2(sch_1):page213_i105@dev_discrete.cap~
_a(chips)',
 PATH='I105',
 DRAWING='@BASEBOARD_FAB2_LIB.BASEBOARD_FAB2(SCH_1):PAGE213',
 TOLERANCE='10%',
 SEC_TYPE='0402V',
 MATERIAL='X7R',
 BOM_COST='SM_THERM',
 PHYS_PAGE='213',
 XY='(-2850,4250)',
 ROT='0',
 VER='1',
 VALUE='0.1UF',
 PACK_TYPE='0402V',
 PART_NUMBER='A36096-030',
 LOCATION='C4D40',
 ROOM='CPU_FANS',
 SEC='1',
 CDS_LIB='dev_discrete',
 CDS_PART_NAME='CAP_A_0402V-0.1UF,16V,10%,X7R,A',
 VOLTAGE='16V',
 PRIM_FILE='./archive_libs/discrete/cap_a/chips/chips.prt';

PART_NAME
 C4D42 'CAP_0402LF-1000PF,50V,10%,X7R,A':
 ROOM='PVCCIN_CPU0_VR';

SECTION_NUMBER 1
 '@BASEBOARD_FAB2_LIB.BASEBOARD_FAB2(SCH_1):PAGE201_I125@MSTR_DISCRETE.CAP(CHIPS)':
 C_PATH='@baseboard_fab2_lib.baseboard_fab2(sch_1):page201_i125@mstr_discrete.ca~
p(chips)',
 P_PATH='@baseboard_fab2_lib.baseboard_fab2(sch_1):page201_i125@mstr_discrete.ca~
p(chips)',
 PATH='I125',
 DRAWING='@BASEBOARD_FAB2_LIB.BASEBOARD_FAB2(SCH_1):PAGE201',
 TOLERANCE='10%',
 SEC_TYPE='0402LF',
 MATERIAL='X7R',
 PHYS_PAGE='201',
 XY='(-1450,2075)',
 ROT='0',
 VER='1',
 VALUE='1000PF',
 PACK_TYPE='0402LF',
 PART_NUMBER='A36096-046',
 LOCATION='C4D42',
 ROOM='PVCCIN_CPU0_VR',
 SEC='1',
 CDS_LIB='mstr_discrete',
 CDS_PART_NAME='CAP_0402LF-1000PF,50V,10%,X7R,A',
 VOLTAGE='50V',
 PRIM_FILE='./archive_libs/mstr_discrete/cap/chips/chips.prt';

PART_NAME
 C4D44 'CAP_0402LF-220PF,50V,10%,X7R,AA':
 ROOM='PVCCIO_CPU1';

SECTION_NUMBER 1
 '@BASEBOARD_FAB2_LIB.BASEBOARD_FAB2(SCH_1):PAGE213_I83@MSTR_DISCRETE.CAP(CHIPS)':
 C_PATH='@baseboard_fab2_lib.baseboard_fab2(sch_1):page213_i83@mstr_discrete.cap~
(chips)',
 P_PATH='@baseboard_fab2_lib.baseboard_fab2(sch_1):page213_i83@mstr_discrete.cap~
(chips)',
 PATH='I83',
 DRAWING='@BASEBOARD_FAB2_LIB.BASEBOARD_FAB2(SCH_1):PAGE213',
 TOLERANCE='10%',
 SEC_TYPE='0402LF',
 MATERIAL='X7R',
 PHYS_PAGE='213',
 XY='(-2075,1725)',
 ROT='0',
 VER='1',
 VALUE='220PF',
 PACK_TYPE='0402LF',
 PART_NUMBER='A36096-050',
 LOCATION='C4D44',
 ROOM='PVCCIO_CPU1',
 SEC='1',
 CDS_LIB='mstr_discrete',
 CDS_PART_NAME='CAP_0402LF-220PF,50V,10%,X7R,AA',
 VOLTAGE='50V',
 PRIM_FILE='./archive_libs/mstr_discrete/cap/chips/chips.prt';

PART_NAME
 C4D45 'CAP_0402LF-220PF,50V,10%,X7R,AA':
 ROOM='PVCCIN_CPU0_VR',
 NO_XNET_CONNECTION='1';

SECTION_NUMBER 1
 '@BASEBOARD_FAB2_LIB.BASEBOARD_FAB2(SCH_1):PAGE201_I70@MSTR_DISCRETE.CAP(CHIPS)':
 C_PATH='@baseboard_fab2_lib.baseboard_fab2(sch_1):page201_i70@mstr_discrete.cap~
(chips)',
 P_PATH='@baseboard_fab2_lib.baseboard_fab2(sch_1):page201_i70@mstr_discrete.cap~
(chips)',
 PATH='I70',
 DRAWING='@BASEBOARD_FAB2_LIB.BASEBOARD_FAB2(SCH_1):PAGE201',
 TOLERANCE='10%',
 SEC_TYPE='0402LF',
 MATERIAL='X7R',
 NO_XNET_CONNECTION='1',
 PHYS_PAGE='201',
 XY='(-6450,2375)',
 ROT='0',
 VER='1',
 VALUE='220PF',
 PACK_TYPE='0402LF',
 PART_NUMBER='A36096-050',
 LOCATION='C4D45',
 ROOM='PVCCIN_CPU0_VR',
 SEC='1',
 CDS_LIB='mstr_discrete',
 CDS_PART_NAME='CAP_0402LF-220PF,50V,10%,X7R,AA',
 VOLTAGE='50V',
 PRIM_FILE='./archive_libs/mstr_discrete/cap/chips/chips.prt';

PART_NAME
 C4D46 'CAP_0402-1.0UF,16V,10%,X6S,D97A':
 ROOM='PVCCIN_CPU0_PWR_VR';

SECTION_NUMBER 1
 '@BASEBOARD_FAB2_LIB.BASEBOARD_FAB2(SCH_1):PAGE204_I34@MSTR_DISCRETE.CAP(CHIPS)':
 C_PATH='@baseboard_fab2_lib.baseboard_fab2(sch_1):page204_i34@mstr_discrete.cap~
(chips)',
 P_PATH='@baseboard_fab2_lib.baseboard_fab2(sch_1):page204_i34@mstr_discrete.cap~
(chips)',
 PATH='I34',
 DRAWING='@BASEBOARD_FAB2_LIB.BASEBOARD_FAB2(SCH_1):PAGE204',
 TOLERANCE='10%',
 SEC_TYPE='0402',
 MATERIAL='X6S',
 PHYS_PAGE='204',
 XY='(-5700,4175)',
 ROT='0',
 VER='1',
 VALUE='1.0UF',
 PACK_TYPE='0402',
 PART_NUMBER='D97712-011',
 LOCATION='C4D46',
 ROOM='PVCCIN_CPU0_PWR_VR',
 SEC='1',
 CDS_LIB='mstr_discrete',
 CDS_PART_NAME='CAP_0402-1.0UF,16V,10%,X6S,D97A',
 VOLTAGE='16V',
 PRIM_FILE='./archive_libs/mstr_discrete/cap/chips/chips.prt';

PART_NAME
 C4D47 'CAP_0402-0.22UF,16V,10%,X7R,A3A':
 ROOM='PVCCIN_CPU0_PWR_VR';

SECTION_NUMBER 1
 '@BASEBOARD_FAB2_LIB.BASEBOARD_FAB2(SCH_1):PAGE204_I18@MSTR_DISCRETE.CAP(CHIPS)':
 C_PATH='@baseboard_fab2_lib.baseboard_fab2(sch_1):page204_i18@mstr_discrete.cap~
(chips)',
 P_PATH='@baseboard_fab2_lib.baseboard_fab2(sch_1):page204_i18@mstr_discrete.cap~
(chips)',
 PATH='I18',
 DRAWING='@BASEBOARD_FAB2_LIB.BASEBOARD_FAB2(SCH_1):PAGE204',
 TOLERANCE='10%',
 SEC_TYPE='0402',
 MATERIAL='X7R',
 PHYS_PAGE='204',
 XY='(-4875,4200)',
 ROT='0',
 VER='1',
 VALUE='0.22UF',
 PACK_TYPE='0402',
 PART_NUMBER='A36096-155',
 LOCATION='C4D47',
 ROOM='PVCCIN_CPU0_PWR_VR',
 SEC='1',
 CDS_LIB='mstr_discrete',
 CDS_PART_NAME='CAP_0402-0.22UF,16V,10%,X7R,A3A',
 VOLTAGE='16V',
 PRIM_FILE='./archive_libs/mstr_discrete/cap/chips/chips.prt';

PART_NAME
 C4D48 'CAP_0402-1.0UF,16V,10%,X6S,D97A':
 ROOM='PVCCIN_CPU0_PWR_VR';

SECTION_NUMBER 1
 '@BASEBOARD_FAB2_LIB.BASEBOARD_FAB2(SCH_1):PAGE202_I47@MSTR_DISCRETE.CAP(CHIPS)':
 C_PATH='@baseboard_fab2_lib.baseboard_fab2(sch_1):page202_i47@mstr_discrete.cap~
(chips)',
 P_PATH='@baseboard_fab2_lib.baseboard_fab2(sch_1):page202_i47@mstr_discrete.cap~
(chips)',
 PATH='I47',
 DRAWING='@BASEBOARD_FAB2_LIB.BASEBOARD_FAB2(SCH_1):PAGE202',
 TOLERANCE='10%',
 SEC_TYPE='0402',
 MATERIAL='X6S',
 PHYS_PAGE='202',
 XY='(-6350,1475)',
 ROT='0',
 VER='1',
 VALUE='1.0UF',
 PACK_TYPE='0402',
 PART_NUMBER='D97712-011',
 LOCATION='C4D48',
 ROOM='PVCCIN_CPU0_PWR_VR',
 SEC='1',
 CDS_LIB='mstr_discrete',
 CDS_PART_NAME='CAP_0402-1.0UF,16V,10%,X6S,D97A',
 VOLTAGE='16V',
 PRIM_FILE='./archive_libs/mstr_discrete/cap/chips/chips.prt';

PART_NAME
 C4D49 'CAP_A_0402V-0.1UF,16V,10%,X7R,A':
 ROOM='PVCCIN_CPU0_PWR_VR';

SECTION_NUMBER 1
 '@BASEBOARD_FAB2_LIB.BASEBOARD_FAB2(SCH_1):PAGE202_I46@DEV_DISCRETE.CAP_A(CHIPS)':
 C_PATH='@baseboard_fab2_lib.baseboard_fab2(sch_1):page202_i46@dev_discrete.cap_~
a(chips)',
 P_PATH='@baseboard_fab2_lib.baseboard_fab2(sch_1):page202_i46@dev_discrete.cap_~
a(chips)',
 PATH='I46',
 DRAWING='@BASEBOARD_FAB2_LIB.BASEBOARD_FAB2(SCH_1):PAGE202',
 TOLERANCE='10%',
 SEC_TYPE='0402V',
 MATERIAL='X7R',
 PHYS_PAGE='202',
 XY='(-6050,1475)',
 ROT='0',
 VER='1',
 VALUE='0.1UF',
 PACK_TYPE='0402V',
 PART_NUMBER='A36096-030',
 LOCATION='C4D49',
 ROOM='PVCCIN_CPU0_PWR_VR',
 SEC='1',
 CDS_LIB='dev_discrete',
 CDS_PART_NAME='CAP_A_0402V-0.1UF,16V,10%,X7R,A',
 VOLTAGE='16V',
 PRIM_FILE='./archive_libs/discrete/cap_a/chips/chips.prt';

PART_NAME
 C4D50 'CAP_0402-0.220UF,16V,10%,X7R,AA':
 ROOM='PVCCIN_CPU0_PWR_VR',
 NO_XNET_CONNECTION='1';

SECTION_NUMBER 1
 '@BASEBOARD_FAB2_LIB.BASEBOARD_FAB2(SCH_1):PAGE202_I32@MSTR_DISCRETE.CAP(CHIPS)':
 C_PATH='@baseboard_fab2_lib.baseboard_fab2(sch_1):page202_i32@mstr_discrete.cap~
(chips)',
 P_PATH='@baseboard_fab2_lib.baseboard_fab2(sch_1):page202_i32@mstr_discrete.cap~
(chips)',
 PATH='I32',
 DRAWING='@BASEBOARD_FAB2_LIB.BASEBOARD_FAB2(SCH_1):PAGE202',
 SPOF='TRUE',
 TOLERANCE='10%',
 SEC_TYPE='0402',
 MATERIAL='X7R',
 NO_XNET_CONNECTION='1',
 PHYS_PAGE='202',
 XY='(-5950,825)',
 ROT='2',
 VER='1',
 VALUE='0.220UF',
 PACK_TYPE='0402',
 PART_NUMBER='A36096-104',
 LOCATION='C4D50',
 ROOM='PVCCIN_CPU0_PWR_VR',
 SEC='1',
 CDS_LIB='mstr_discrete',
 CDS_PART_NAME='CAP_0402-0.220UF,16V,10%,X7R,AA',
 VOLTAGE='16V',
 PRIM_FILE='./archive_libs/mstr_discrete/cap/chips/chips.prt';

PART_NAME
 C4E3 'CAP_A_0603V-22.0UF,4V,20%,X6S,A':
 GROUP='PWR_MLCC_CAP';

SECTION_NUMBER 1
 '@BASEBOARD_FAB2_LIB.BASEBOARD_FAB2(SCH_1):PAGE202_I61@DEV_DISCRETE.CAP_A(CHIPS)':
 C_PATH='@baseboard_fab2_lib.baseboard_fab2(sch_1):page202_i61@dev_discrete.cap_~
a(chips)',
 P_PATH='@baseboard_fab2_lib.baseboard_fab2(sch_1):page202_i61@dev_discrete.cap_~
a(chips)',
 PATH='I61',
 DRAWING='@BASEBOARD_FAB2_LIB.BASEBOARD_FAB2(SCH_1):PAGE202',
 TOLERANCE='20%',
 SEC_TYPE='0603V',
 MATERIAL='X6S',
 PHYS_PAGE='202',
 XY='(-650,3300)',
 ROT='0',
 VER='1',
 VALUE='22.0UF',
 PACK_TYPE='0603V',
 PART_NUMBER='E15431-004',
 LOCATION='C4E3',
 GROUP='PWR_MLCC_CAP',
 SEC='1',
 CDS_LIB='dev_discrete',
 CDS_PART_NAME='CAP_A_0603V-22.0UF,4V,20%,X6S,A',
 VOLTAGE='4V',
 PRIM_FILE='./archive_libs/discrete/cap_a/chips/chips.prt';

PART_NAME
 C4E5 'CAP_0402-0.22UF,16V,10%,X7R,A3A':
 ROOM='PVCCIN_CPU0_PWR_VR';

SECTION_NUMBER 1
 '@BASEBOARD_FAB2_LIB.BASEBOARD_FAB2(SCH_1):PAGE202_I18@MSTR_DISCRETE.CAP(CHIPS)':
 C_PATH='@baseboard_fab2_lib.baseboard_fab2(sch_1):page202_i18@mstr_discrete.cap~
(chips)',
 P_PATH='@baseboard_fab2_lib.baseboard_fab2(sch_1):page202_i18@mstr_discrete.cap~
(chips)',
 PATH='I18',
 DRAWING='@BASEBOARD_FAB2_LIB.BASEBOARD_FAB2(SCH_1):PAGE202',
 TOLERANCE='10%',
 SEC_TYPE='0402',
 MATERIAL='X7R',
 PHYS_PAGE='202',
 XY='(-4900,4125)',
 ROT='0',
 VER='1',
 VALUE='0.22UF',
 PACK_TYPE='0402',
 PART_NUMBER='A36096-155',
 LOCATION='C4E5',
 ROOM='PVCCIN_CPU0_PWR_VR',
 SEC='1',
 CDS_LIB='mstr_discrete',
 CDS_PART_NAME='CAP_0402-0.22UF,16V,10%,X7R,A3A',
 VOLTAGE='16V',
 PRIM_FILE='./archive_libs/mstr_discrete/cap/chips/chips.prt';

PART_NAME
 C4E6 'SC1U10V2KX-4-GP_SMD-BCG6-SC1U1A':;

SECTION_NUMBER 1
 '@BASEBOARD_FAB2_LIB.BASEBOARD_FAB2(SCH_1):PAGE202_I112@W_HDL.SC1U10V2KX-4-GP(CHIPS)':
 C_PATH='@baseboard_fab2_lib.baseboard_fab2(sch_1):page202_i112@w_hdl.\sc1u10v2k~
x-4-gp\(chips)',
 P_PATH='@baseboard_fab2_lib.baseboard_fab2(sch_1):page202_i112@w_hdl.\sc1u10v2k~
x-4-gp\(chips)',
 PATH='I112',
 DRAWING='@BASEBOARD_FAB2_LIB.BASEBOARD_FAB2(SCH_1):PAGE202',
 PACK_SIZE='0402',
 RATED='10V',
 ATTRIBUTE='1UF',
 TOLERANCE='10%',
 SEC_TYPE='SMD-BCG6',
 PHYS_PAGE='202',
 XY='(-5275,4075)',
 ROT='0',
 VER='1',
 VALUE='SC1U10V2KX-4-GP',
 PACK_TYPE='SMD-BCG6',
 PART_NUMBER='78.10523.8FL',
 LOCATION='C4E6',
 SEC='1',
 CDS_LIB='w_hdl',
 CDS_PART_NAME='SC1U10V2KX-4-GP_SMD-BCG6-SC1U1A',
 PRIM_FILE='C:/<user>/w_hdl/sc1u10v2kx#2d4#2dgp/chips/chips.prt';

PART_NAME
 C4E7 'CAPP_3018-470UF,2.5V,20%,ALUM,A':
 GROUP='PWR_BULK_CAP',
 ROOM='PVCCIO_CPU1';

SECTION_NUMBER 1
 '@BASEBOARD_FAB2_LIB.BASEBOARD_FAB2(SCH_1):PAGE214_I178@MSTR_DISCRETE.CAPP(CHIPS)':
 C_PATH='@baseboard_fab2_lib.baseboard_fab2(sch_1):page214_i178@mstr_discrete.ca~
pp(chips)',
 P_PATH='@baseboard_fab2_lib.baseboard_fab2(sch_1):page214_i178@mstr_discrete.ca~
pp(chips)',
 PATH='I178',
 DRAWING='@BASEBOARD_FAB2_LIB.BASEBOARD_FAB2(SCH_1):PAGE214',
 TOLERANCE='20%',
 SEC_TYPE='3018',
 MATERIAL='ALUM',
 BOM_COST='PROC_VRD_PVCCIO_CPU1',
 PHYS_PAGE='214',
 XY='(3200,2300)',
 ROT='2',
 VER='1',
 VALUE='470UF',
 PACK_TYPE='3018',
 PART_NUMBER='699013-049',
 LOCATION='C4E7',
 ROOM='PVCCIO_CPU1',
 GROUP='PWR_BULK_CAP',
 SEC='1',
 CDS_LIB='mstr_discrete',
 CDS_PART_NAME='CAPP_3018-470UF,2.5V,20%,ALUM,A',
 VOLTAGE='2.5V',
 PRIM_FILE='./archive_libs/mstr_discrete/capp/chips/chips.prt';

PART_NAME
 C4E8 'SC22U16V5MX-4-GP_SMD-BCG5-SC22A':;

SECTION_NUMBER 1
 '@BASEBOARD_FAB2_LIB.BASEBOARD_FAB2(SCH_1):PAGE214_I161@W_HDL.SC22U16V5MX-4-GP(CHIPS)':
 C_PATH='@baseboard_fab2_lib.baseboard_fab2(sch_1):page214_i161@w_hdl.\sc22u16v5~
mx-4-gp\(chips)',
 P_PATH='@baseboard_fab2_lib.baseboard_fab2(sch_1):page214_i161@w_hdl.\sc22u16v5~
mx-4-gp\(chips)',
 PATH='I161',
 DRAWING='@BASEBOARD_FAB2_LIB.BASEBOARD_FAB2(SCH_1):PAGE214',
 TYPE='X6S',
 PACK_SIZE='0805',
 RATED='16V',
 ATTRIBUTE='22UF',
 TOLERANCE='20%',
 SEC_TYPE='SMD-BCG5',
 PHYS_PAGE='214',
 XY='(1600,1200)',
 ROT='0',
 VER='1',
 VALUE='SC22U16V5MX-4-GP',
 PACK_TYPE='SMD-BCG5',
 PART_NUMBER='078.22611.0811',
 LOCATION='C4E8',
 SEC='1',
 CDS_LIB='w_hdl',
 CDS_PART_NAME='SC22U16V5MX-4-GP_SMD-BCG5-SC22A',
 PRIM_FILE='C:/<user>/w_hdl/sc22u16v5mx#2d4#2dgp/chips/chips.prt';

PART_NAME
 C4E9 'SC22U16V5MX-4-GP_SMD-BCG5-SC22A':;

SECTION_NUMBER 1
 '@BASEBOARD_FAB2_LIB.BASEBOARD_FAB2(SCH_1):PAGE214_I164@W_HDL.SC22U16V5MX-4-GP(CHIPS)':
 C_PATH='@baseboard_fab2_lib.baseboard_fab2(sch_1):page214_i164@w_hdl.\sc22u16v5~
mx-4-gp\(chips)',
 P_PATH='@baseboard_fab2_lib.baseboard_fab2(sch_1):page214_i164@w_hdl.\sc22u16v5~
mx-4-gp\(chips)',
 PATH='I164',
 DRAWING='@BASEBOARD_FAB2_LIB.BASEBOARD_FAB2(SCH_1):PAGE214',
 TYPE='X6S',
 PACK_SIZE='0805',
 RATED='16V',
 ATTRIBUTE='22UF',
 TOLERANCE='20%',
 SEC_TYPE='SMD-BCG5',
 PHYS_PAGE='214',
 XY='(2950,1200)',
 ROT='0',
 VER='1',
 VALUE='SC22U16V5MX-4-GP',
 PACK_TYPE='SMD-BCG5',
 PART_NUMBER='078.22611.0811',
 LOCATION='C4E9',
 SEC='1',
 CDS_LIB='w_hdl',
 CDS_PART_NAME='SC22U16V5MX-4-GP_SMD-BCG5-SC22A',
 PRIM_FILE='C:/<user>/w_hdl/sc22u16v5mx#2d4#2dgp/chips/chips.prt';

PART_NAME
 C4E10 'CAP_0402-1.0UF,16V,10%,X6S,D97A':
 ROOM='PVCCIN_CPU0_PWR_VR';

SECTION_NUMBER 1
 '@BASEBOARD_FAB2_LIB.BASEBOARD_FAB2(SCH_1):PAGE202_I34@MSTR_DISCRETE.CAP(CHIPS)':
 C_PATH='@baseboard_fab2_lib.baseboard_fab2(sch_1):page202_i34@mstr_discrete.cap~
(chips)',
 P_PATH='@baseboard_fab2_lib.baseboard_fab2(sch_1):page202_i34@mstr_discrete.cap~
(chips)',
 PATH='I34',
 DRAWING='@BASEBOARD_FAB2_LIB.BASEBOARD_FAB2(SCH_1):PAGE202',
 TOLERANCE='10%',
 SEC_TYPE='0402',
 MATERIAL='X6S',
 PHYS_PAGE='202',
 XY='(-5700,4025)',
 ROT='0',
 VER='1',
 VALUE='1.0UF',
 PACK_TYPE='0402',
 PART_NUMBER='D97712-011',
 LOCATION='C4E10',
 ROOM='PVCCIN_CPU0_PWR_VR',
 SEC='1',
 CDS_LIB='mstr_discrete',
 CDS_PART_NAME='CAP_0402-1.0UF,16V,10%,X6S,D97A',
 VOLTAGE='16V',
 PRIM_FILE='./archive_libs/mstr_discrete/cap/chips/chips.prt';

PART_NAME
 C4E11 'CAP_A_0603V-22.0UF,4V,20%,X6S,A':
 GROUP='PWR_MLCC_CAP',
 ROOM='PVCCIN_CPU0_PWR_VR';

SECTION_NUMBER 1
 '@BASEBOARD_FAB2_LIB.BASEBOARD_FAB2(SCH_1):PAGE202_I27@DEV_DISCRETE.CAP_A(CHIPS)':
 C_PATH='@baseboard_fab2_lib.baseboard_fab2(sch_1):page202_i27@dev_discrete.cap_~
a(chips)',
 P_PATH='@baseboard_fab2_lib.baseboard_fab2(sch_1):page202_i27@dev_discrete.cap_~
a(chips)',
 PATH='I27',
 DRAWING='@BASEBOARD_FAB2_LIB.BASEBOARD_FAB2(SCH_1):PAGE202',
 TOLERANCE='20%',
 SEC_TYPE='0603V',
 MATERIAL='X6S',
 BOM_COST='PROC_VRD_VCCIN_CPU0',
 PHYS_PAGE='202',
 XY='(-850,750)',
 ROT='0',
 VER='1',
 VALUE='22.0UF',
 PACK_TYPE='0603V',
 PART_NUMBER='E15431-004',
 LOCATION='C4E11',
 ROOM='PVCCIN_CPU0_PWR_VR',
 GROUP='PWR_MLCC_CAP',
 SEC='1',
 CDS_LIB='dev_discrete',
 CDS_PART_NAME='CAP_A_0603V-22.0UF,4V,20%,X6S,A',
 VOLTAGE='4V',
 PRIM_FILE='./archive_libs/discrete/cap_a/chips/chips.prt';

PART_NAME
 C4E13 'CAP_A_0402V-0.1UF,16V,10%,X7R,A':
 ROOM='PVCCIO_CPU1';

SECTION_NUMBER 1
 '@BASEBOARD_FAB2_LIB.BASEBOARD_FAB2(SCH_1):PAGE214_I77@DEV_DISCRETE.CAP_A(CHIPS)':
 C_PATH='@baseboard_fab2_lib.baseboard_fab2(sch_1):page214_i77@dev_discrete.cap_~
a(chips)',
 P_PATH='@baseboard_fab2_lib.baseboard_fab2(sch_1):page214_i77@dev_discrete.cap_~
a(chips)',
 PATH='I77',
 DRAWING='@BASEBOARD_FAB2_LIB.BASEBOARD_FAB2(SCH_1):PAGE214',
 TOLERANCE='10%',
 SEC_TYPE='0402V',
 MATERIAL='X7R',
 PHYS_PAGE='214',
 XY='(-1975,4150)',
 ROT='0',
 VER='1',
 VALUE='0.1UF',
 PACK_TYPE='0402V',
 PART_NUMBER='A36096-030',
 LOCATION='C4E13',
 ROOM='PVCCIO_CPU1',
 SEC='1',
 CDS_LIB='dev_discrete',
 CDS_PART_NAME='CAP_A_0402V-0.1UF,16V,10%,X7R,A',
 VOLTAGE='16V',
 PRIM_FILE='./archive_libs/discrete/cap_a/chips/chips.prt';

PART_NAME
 C4E14 'SC22U16V5MX-4-GP_SMD-BCG5-SC22A':;

SECTION_NUMBER 1
 '@BASEBOARD_FAB2_LIB.BASEBOARD_FAB2(SCH_1):PAGE214_I148@W_HDL.SC22U16V5MX-4-GP(CHIPS)':
 C_PATH='@baseboard_fab2_lib.baseboard_fab2(sch_1):page214_i148@w_hdl.\sc22u16v5~
mx-4-gp\(chips)',
 P_PATH='@baseboard_fab2_lib.baseboard_fab2(sch_1):page214_i148@w_hdl.\sc22u16v5~
mx-4-gp\(chips)',
 PATH='I148',
 DRAWING='@BASEBOARD_FAB2_LIB.BASEBOARD_FAB2(SCH_1):PAGE214',
 TYPE='X6S',
 PACK_SIZE='0805',
 RATED='16V',
 ATTRIBUTE='22UF',
 TOLERANCE='20%',
 SEC_TYPE='SMD-BCG5',
 PHYS_PAGE='214',
 XY='(250,1200)',
 ROT='0',
 VER='1',
 VALUE='SC22U16V5MX-4-GP',
 PACK_TYPE='SMD-BCG5',
 PART_NUMBER='078.22611.0811',
 LOCATION='C4E14',
 SEC='1',
 CDS_LIB='w_hdl',
 CDS_PART_NAME='SC22U16V5MX-4-GP_SMD-BCG5-SC22A',
 PRIM_FILE='C:/<user>/w_hdl/sc22u16v5mx#2d4#2dgp/chips/chips.prt';

PART_NAME
 C4E15 'CAP_0402-1.0UF,16V,10%,X6S,D97A':
 ROOM='PVCCIO_CPU1';

SECTION_NUMBER 1
 '@BASEBOARD_FAB2_LIB.BASEBOARD_FAB2(SCH_1):PAGE214_I79@MSTR_DISCRETE.CAP(CHIPS)':
 C_PATH='@baseboard_fab2_lib.baseboard_fab2(sch_1):page214_i79@mstr_discrete.cap~
(chips)',
 P_PATH='@baseboard_fab2_lib.baseboard_fab2(sch_1):page214_i79@mstr_discrete.cap~
(chips)',
 PATH='I79',
 DRAWING='@BASEBOARD_FAB2_LIB.BASEBOARD_FAB2(SCH_1):PAGE214',
 TOLERANCE='10%',
 SEC_TYPE='0402',
 MATERIAL='X6S',
 PHYS_PAGE='214',
 XY='(-2250,4150)',
 ROT='0',
 VER='1',
 VALUE='1.0UF',
 PACK_TYPE='0402',
 PART_NUMBER='D97712-011',
 LOCATION='C4E15',
 ROOM='PVCCIO_CPU1',
 SEC='1',
 CDS_LIB='mstr_discrete',
 CDS_PART_NAME='CAP_0402-1.0UF,16V,10%,X6S,D97A',
 VOLTAGE='16V',
 PRIM_FILE='./archive_libs/mstr_discrete/cap/chips/chips.prt';

PART_NAME
 C4E16 'CAPP_2626-270UF,16V,20%,OSCON,A':
 ROOM='PVCCIN_CPU0_FILTER_VR';

SECTION_NUMBER 1
 '@BASEBOARD_FAB2_LIB.BASEBOARD_FAB2(SCH_1):PAGE204_I50@MSTR_DISCRETE.CAPP(CHIPS)':
 C_PATH='@baseboard_fab2_lib.baseboard_fab2(sch_1):page204_i50@mstr_discrete.cap~
p(chips)',
 P_PATH='@baseboard_fab2_lib.baseboard_fab2(sch_1):page204_i50@mstr_discrete.cap~
p(chips)',
 PATH='I50',
 DRAWING='@BASEBOARD_FAB2_LIB.BASEBOARD_FAB2(SCH_1):PAGE204',
 TOLERANCE='20%',
 SEC_TYPE='2626',
 MATERIAL='OSCON',
 PHYS_PAGE='204',
 XY='(-1400,2000)',
 ROT='0',
 VER='1',
 VALUE='270UF',
 PACK_TYPE='2626',
 PART_NUMBER='A31228-047',
 LOCATION='C4E16',
 ROOM='PVCCIN_CPU0_FILTER_VR',
 SEC='1',
 CDS_LIB='mstr_discrete',
 CDS_PART_NAME='CAPP_2626-270UF,16V,20%,OSCON,A',
 VOLTAGE='16V',
 PRIM_FILE='./archive_libs/mstr_discrete/capp/chips/chips.prt';

PART_NAME
 C4E17 'CAP_0402-0.220UF,16V,10%,X7R,AA':
 ROOM='PVCCIN_CPU0_PWR_VR',
 NO_XNET_CONNECTION='1';

SECTION_NUMBER 1
 '@BASEBOARD_FAB2_LIB.BASEBOARD_FAB2(SCH_1):PAGE202_I22@MSTR_DISCRETE.CAP(CHIPS)':
 C_PATH='@baseboard_fab2_lib.baseboard_fab2(sch_1):page202_i22@mstr_discrete.cap~
(chips)',
 P_PATH='@baseboard_fab2_lib.baseboard_fab2(sch_1):page202_i22@mstr_discrete.cap~
(chips)',
 PATH='I22',
 DRAWING='@BASEBOARD_FAB2_LIB.BASEBOARD_FAB2(SCH_1):PAGE202',
 SPOF='TRUE',
 TOLERANCE='10%',
 SEC_TYPE='0402',
 MATERIAL='X7R',
 NO_XNET_CONNECTION='1',
 PHYS_PAGE='202',
 XY='(-5850,3450)',
 ROT='2',
 VER='1',
 VALUE='0.220UF',
 PACK_TYPE='0402',
 PART_NUMBER='A36096-104',
 LOCATION='C4E17',
 ROOM='PVCCIN_CPU0_PWR_VR',
 SEC='1',
 CDS_LIB='mstr_discrete',
 CDS_PART_NAME='CAP_0402-0.220UF,16V,10%,X7R,AA',
 VOLTAGE='16V',
 PRIM_FILE='./archive_libs/mstr_discrete/cap/chips/chips.prt';

PART_NAME
 C4E18 'CAP_0402-0.220UF,16V,10%,X7R,AA':
 ROOM='PVCCIO_CPU1';

SECTION_NUMBER 1
 '@BASEBOARD_FAB2_LIB.BASEBOARD_FAB2(SCH_1):PAGE214_I78@MSTR_DISCRETE.CAP(CHIPS)':
 C_PATH='@baseboard_fab2_lib.baseboard_fab2(sch_1):page214_i78@mstr_discrete.cap~
(chips)',
 P_PATH='@baseboard_fab2_lib.baseboard_fab2(sch_1):page214_i78@mstr_discrete.cap~
(chips)',
 PATH='I78',
 DRAWING='@BASEBOARD_FAB2_LIB.BASEBOARD_FAB2(SCH_1):PAGE214',
 SPOF='TRUE',
 TOLERANCE='10%',
 SEC_TYPE='0402',
 MATERIAL='X7R',
 PHYS_PAGE='214',
 XY='(-1625,3575)',
 ROT='2',
 VER='1',
 VALUE='0.220UF',
 PACK_TYPE='0402',
 PART_NUMBER='A36096-104',
 LOCATION='C4E18',
 ROOM='PVCCIO_CPU1',
 SEC='1',
 CDS_LIB='mstr_discrete',
 CDS_PART_NAME='CAP_0402-0.220UF,16V,10%,X7R,AA',
 VOLTAGE='16V',
 PRIM_FILE='./archive_libs/mstr_discrete/cap/chips/chips.prt';

PART_NAME
 C4E19 'CAP_0402-1.0UF,16V,10%,X6S,D97A':
 ROOM='PVCCIN_CPU0_PWR_VR';

SECTION_NUMBER 1
 '@BASEBOARD_FAB2_LIB.BASEBOARD_FAB2(SCH_1):PAGE202_I36@MSTR_DISCRETE.CAP(CHIPS)':
 C_PATH='@baseboard_fab2_lib.baseboard_fab2(sch_1):page202_i36@mstr_discrete.cap~
(chips)',
 P_PATH='@baseboard_fab2_lib.baseboard_fab2(sch_1):page202_i36@mstr_discrete.cap~
(chips)',
 PATH='I36',
 DRAWING='@BASEBOARD_FAB2_LIB.BASEBOARD_FAB2(SCH_1):PAGE202',
 TOLERANCE='10%',
 SEC_TYPE='0402',
 MATERIAL='X6S',
 PHYS_PAGE='202',
 XY='(-6250,4075)',
 ROT='0',
 VER='1',
 VALUE='1.0UF',
 PACK_TYPE='0402',
 PART_NUMBER='D97712-011',
 LOCATION='C4E19',
 ROOM='PVCCIN_CPU0_PWR_VR',
 SEC='1',
 CDS_LIB='mstr_discrete',
 CDS_PART_NAME='CAP_0402-1.0UF,16V,10%,X6S,D97A',
 VOLTAGE='16V',
 PRIM_FILE='./archive_libs/mstr_discrete/cap/chips/chips.prt';

PART_NAME
 C4E20 'CAP_A_0402V-0.1UF,16V,10%,X7R,A':
 ROOM='PVCCIN_CPU0_PWR_VR';

SECTION_NUMBER 1
 '@BASEBOARD_FAB2_LIB.BASEBOARD_FAB2(SCH_1):PAGE202_I35@DEV_DISCRETE.CAP_A(CHIPS)':
 C_PATH='@baseboard_fab2_lib.baseboard_fab2(sch_1):page202_i35@dev_discrete.cap_~
a(chips)',
 P_PATH='@baseboard_fab2_lib.baseboard_fab2(sch_1):page202_i35@dev_discrete.cap_~
a(chips)',
 PATH='I35',
 DRAWING='@BASEBOARD_FAB2_LIB.BASEBOARD_FAB2(SCH_1):PAGE202',
 TOLERANCE='10%',
 SEC_TYPE='0402V',
 MATERIAL='X7R',
 PHYS_PAGE='202',
 XY='(-5975,4050)',
 ROT='0',
 VER='1',
 VALUE='0.1UF',
 PACK_TYPE='0402V',
 PART_NUMBER='A36096-030',
 LOCATION='C4E20',
 ROOM='PVCCIN_CPU0_PWR_VR',
 SEC='1',
 CDS_LIB='dev_discrete',
 CDS_PART_NAME='CAP_A_0402V-0.1UF,16V,10%,X7R,A',
 VOLTAGE='16V',
 PRIM_FILE='./archive_libs/discrete/cap_a/chips/chips.prt';

PART_NAME
 C4E22 'CAP_0402-1.0UF,16V,10%,X6S,D97A':
 ROOM='PVCCIO_CPU1';

SECTION_NUMBER 1
 '@BASEBOARD_FAB2_LIB.BASEBOARD_FAB2(SCH_1):PAGE214_I76@MSTR_DISCRETE.CAP(CHIPS)':
 C_PATH='@baseboard_fab2_lib.baseboard_fab2(sch_1):page214_i76@mstr_discrete.cap~
(chips)',
 P_PATH='@baseboard_fab2_lib.baseboard_fab2(sch_1):page214_i76@mstr_discrete.cap~
(chips)',
 PATH='I76',
 DRAWING='@BASEBOARD_FAB2_LIB.BASEBOARD_FAB2(SCH_1):PAGE214',
 TOLERANCE='10%',
 SEC_TYPE='0402',
 MATERIAL='X6S',
 PHYS_PAGE='214',
 XY='(-1700,4150)',
 ROT='0',
 VER='1',
 VALUE='1.0UF',
 PACK_TYPE='0402',
 PART_NUMBER='D97712-011',
 LOCATION='C4E22',
 ROOM='PVCCIO_CPU1',
 SEC='1',
 CDS_LIB='mstr_discrete',
 CDS_PART_NAME='CAP_0402-1.0UF,16V,10%,X6S,D97A',
 VOLTAGE='16V',
 PRIM_FILE='./archive_libs/mstr_discrete/cap/chips/chips.prt';

PART_NAME
 C4E23 'CAP_0402-0.22UF,16V,10%,X7R,A3A':
 ROOM='PVCCIO_CPU1';

SECTION_NUMBER 1
 '@BASEBOARD_FAB2_LIB.BASEBOARD_FAB2(SCH_1):PAGE214_I73@MSTR_DISCRETE.CAP(CHIPS)':
 C_PATH='@baseboard_fab2_lib.baseboard_fab2(sch_1):page214_i73@mstr_discrete.cap~
(chips)',
 P_PATH='@baseboard_fab2_lib.baseboard_fab2(sch_1):page214_i73@mstr_discrete.cap~
(chips)',
 PATH='I73',
 DRAWING='@BASEBOARD_FAB2_LIB.BASEBOARD_FAB2(SCH_1):PAGE214',
 TOLERANCE='10%',
 SEC_TYPE='0402',
 MATERIAL='X7R',
 PHYS_PAGE='214',
 XY='(-950,4200)',
 ROT='0',
 VER='1',
 VALUE='0.22UF',
 PACK_TYPE='0402',
 PART_NUMBER='A36096-155',
 LOCATION='C4E23',
 ROOM='PVCCIO_CPU1',
 SEC='1',
 CDS_LIB='mstr_discrete',
 CDS_PART_NAME='CAP_0402-0.22UF,16V,10%,X7R,A3A',
 VOLTAGE='16V',
 PRIM_FILE='./archive_libs/mstr_discrete/cap/chips/chips.prt';

PART_NAME
 C4E24 'CAPP_3018-470UF,2.5V,20%,ALUM,A':
 GROUP='PWR_MCP_CAP',
 ROOM='PVMCP_MCP_CPU1_VR';

SECTION_NUMBER 1
 '@BASEBOARD_FAB2_LIB.BASEBOARD_FAB2(SCH_1):PAGE193_I61@MSTR_DISCRETE.CAPP(CHIPS)':
 C_PATH='@baseboard_fab2_lib.baseboard_fab2(sch_1):page193_i61@mstr_discrete.cap~
p(chips)',
 P_PATH='@baseboard_fab2_lib.baseboard_fab2(sch_1):page193_i61@mstr_discrete.cap~
p(chips)',
 PATH='I61',
 DRAWING='@BASEBOARD_FAB2_LIB.BASEBOARD_FAB2(SCH_1):PAGE193',
 TOLERANCE='20%',
 MATERIAL='ALUM',
 BOM_COST='PVMCP_MCP_CPU1_VR',
 PHYS_PAGE='193',
 XY='(-1900,3100)',
 ROT='0',
 VER='1',
 VALUE='470UF',
 PACK_TYPE='3018',
 PART_NUMBER='699013-049',
 LOCATION='C4E24',
 ROOM='PVMCP_MCP_CPU1_VR',
 GROUP='PWR_MCP_CAP',
 CDS_LIB='mstr_discrete',
 CDS_PART_NAME='CAPP_3018-470UF,2.5V,20%,ALUM,A',
 VOLTAGE='2.5V',
 PRIM_FILE='./archive_libs/mstr_discrete/capp/chips/chips.prt';

PART_NAME
 C4E25 'SC1U10V2KX-4-GP_SMD-BCG6-SC1U1A':;

SECTION_NUMBER 1
 '@BASEBOARD_FAB2_LIB.BASEBOARD_FAB2(SCH_1):PAGE202_I111@W_HDL.SC1U10V2KX-4-GP(CHIPS)':
 C_PATH='@baseboard_fab2_lib.baseboard_fab2(sch_1):page202_i111@w_hdl.\sc1u10v2k~
x-4-gp\(chips)',
 P_PATH='@baseboard_fab2_lib.baseboard_fab2(sch_1):page202_i111@w_hdl.\sc1u10v2k~
x-4-gp\(chips)',
 PATH='I111',
 DRAWING='@BASEBOARD_FAB2_LIB.BASEBOARD_FAB2(SCH_1):PAGE202',
 PACK_SIZE='0402',
 RATED='10V',
 ATTRIBUTE='1UF',
 TOLERANCE='10%',
 SEC_TYPE='SMD-BCG6',
 PHYS_PAGE='202',
 XY='(-5275,1425)',
 ROT='0',
 VER='1',
 VALUE='SC1U10V2KX-4-GP',
 PACK_TYPE='SMD-BCG6',
 PART_NUMBER='78.10523.8FL',
 LOCATION='C4E25',
 SEC='1',
 CDS_LIB='w_hdl',
 CDS_PART_NAME='SC1U10V2KX-4-GP_SMD-BCG6-SC1U1A',
 PRIM_FILE='C:/<user>/w_hdl/sc1u10v2kx#2d4#2dgp/chips/chips.prt';

PART_NAME
 C4E26 'CAP_0402-1.0UF,16V,10%,X6S,D97A':
 ROOM='PVCCIN_CPU0_PWR_VR';

SECTION_NUMBER 1
 '@BASEBOARD_FAB2_LIB.BASEBOARD_FAB2(SCH_1):PAGE202_I45@MSTR_DISCRETE.CAP(CHIPS)':
 C_PATH='@baseboard_fab2_lib.baseboard_fab2(sch_1):page202_i45@mstr_discrete.cap~
(chips)',
 P_PATH='@baseboard_fab2_lib.baseboard_fab2(sch_1):page202_i45@mstr_discrete.cap~
(chips)',
 PATH='I45',
 DRAWING='@BASEBOARD_FAB2_LIB.BASEBOARD_FAB2(SCH_1):PAGE202',
 TOLERANCE='10%',
 SEC_TYPE='0402',
 MATERIAL='X6S',
 PHYS_PAGE='202',
 XY='(-5775,1475)',
 ROT='0',
 VER='1',
 VALUE='1.0UF',
 PACK_TYPE='0402',
 PART_NUMBER='D97712-011',
 LOCATION='C4E26',
 ROOM='PVCCIN_CPU0_PWR_VR',
 SEC='1',
 CDS_LIB='mstr_discrete',
 CDS_PART_NAME='CAP_0402-1.0UF,16V,10%,X6S,D97A',
 VOLTAGE='16V',
 PRIM_FILE='./archive_libs/mstr_discrete/cap/chips/chips.prt';

PART_NAME
 C4E27 'CAP_0402-0.22UF,16V,10%,X7R,A3A':
 ROOM='PVCCIN_CPU0_PWR_VR';

SECTION_NUMBER 1
 '@BASEBOARD_FAB2_LIB.BASEBOARD_FAB2(SCH_1):PAGE202_I24@MSTR_DISCRETE.CAP(CHIPS)':
 C_PATH='@baseboard_fab2_lib.baseboard_fab2(sch_1):page202_i24@mstr_discrete.cap~
(chips)',
 P_PATH='@baseboard_fab2_lib.baseboard_fab2(sch_1):page202_i24@mstr_discrete.cap~
(chips)',
 PATH='I24',
 DRAWING='@BASEBOARD_FAB2_LIB.BASEBOARD_FAB2(SCH_1):PAGE202',
 TOLERANCE='10%',
 SEC_TYPE='0402',
 MATERIAL='X7R',
 PHYS_PAGE='202',
 XY='(-4950,1425)',
 ROT='0',
 VER='1',
 VALUE='0.22UF',
 PACK_TYPE='0402',
 PART_NUMBER='A36096-155',
 LOCATION='C4E27',
 ROOM='PVCCIN_CPU0_PWR_VR',
 SEC='1',
 CDS_LIB='mstr_discrete',
 CDS_PART_NAME='CAP_0402-0.22UF,16V,10%,X7R,A3A',
 VOLTAGE='16V',
 PRIM_FILE='./archive_libs/mstr_discrete/cap/chips/chips.prt';

PART_NAME
 C4E28 'SC1U10V2KX-4-GP_SMD-BCG6-SC1U1A':;

SECTION_NUMBER 1
 '@BASEBOARD_FAB2_LIB.BASEBOARD_FAB2(SCH_1):PAGE214_I175@W_HDL.SC1U10V2KX-4-GP(CHIPS)':
 C_PATH='@baseboard_fab2_lib.baseboard_fab2(sch_1):page214_i175@w_hdl.\sc1u10v2k~
x-4-gp\(chips)',
 P_PATH='@baseboard_fab2_lib.baseboard_fab2(sch_1):page214_i175@w_hdl.\sc1u10v2k~
x-4-gp\(chips)',
 PATH='I175',
 DRAWING='@BASEBOARD_FAB2_LIB.BASEBOARD_FAB2(SCH_1):PAGE214',
 PACK_SIZE='0402',
 RATED='10V',
 ATTRIBUTE='1UF',
 TOLERANCE='10%',
 SEC_TYPE='SMD-BCG6',
 PHYS_PAGE='214',
 XY='(-1350,4175)',
 ROT='0',
 VER='1',
 VALUE='SC1U10V2KX-4-GP',
 PACK_TYPE='SMD-BCG6',
 PART_NUMBER='78.10523.8FL',
 LOCATION='C4E28',
 SEC='1',
 CDS_LIB='w_hdl',
 CDS_PART_NAME='SC1U10V2KX-4-GP_SMD-BCG6-SC1U1A',
 PRIM_FILE='C:/<user>/w_hdl/sc1u10v2kx#2d4#2dgp/chips/chips.prt';

PART_NAME
 C4E29 'CAPP_3018-470UF,2.5V,20%,ALUM,A':
 GROUP='PWR_MCP_CAP',
 ROOM='PVMCP_MCP_CPU1_VR';

SECTION_NUMBER 1
 '@BASEBOARD_FAB2_LIB.BASEBOARD_FAB2(SCH_1):PAGE193_I175@MSTR_DISCRETE.CAPP(CHIPS)':
 C_PATH='@baseboard_fab2_lib.baseboard_fab2(sch_1):page193_i175@mstr_discrete.ca~
pp(chips)',
 P_PATH='@baseboard_fab2_lib.baseboard_fab2(sch_1):page193_i175@mstr_discrete.ca~
pp(chips)',
 PATH='I175',
 DRAWING='@BASEBOARD_FAB2_LIB.BASEBOARD_FAB2(SCH_1):PAGE193',
 TOLERANCE='20%',
 SEC_TYPE='3018',
 MATERIAL='ALUM',
 BOM_COST='PVMCP_MCP_CPU1_VR',
 PHYS_PAGE='193',
 XY='(-1300,3100)',
 ROT='0',
 VER='1',
 VALUE='470UF',
 PACK_TYPE='3018',
 PART_NUMBER='699013-049',
 LOCATION='C4E29',
 ROOM='PVMCP_MCP_CPU1_VR',
 GROUP='PWR_MCP_CAP',
 SEC='1',
 CDS_LIB='mstr_discrete',
 CDS_PART_NAME='CAPP_3018-470UF,2.5V,20%,ALUM,A',
 VOLTAGE='2.5V',
 PRIM_FILE='./archive_libs/mstr_discrete/capp/chips/chips.prt';

PART_NAME
 C4F1 'CAP_A_0402V-1.0UF,6.3V,10%,X6SA':
 GROUP='PWR_MCP_CAP',
 ROOM='P1V8_MCP_CPU1';

SECTION_NUMBER 1
 '@BASEBOARD_FAB2_LIB.BASEBOARD_FAB2(SCH_1):PAGE193_I68@DEV_DISCRETE.CAP_A(CHIPS)':
 C_PATH='@baseboard_fab2_lib.baseboard_fab2(sch_1):page193_i68@dev_discrete.cap_~
a(chips)',
 P_PATH='@baseboard_fab2_lib.baseboard_fab2(sch_1):page193_i68@dev_discrete.cap_~
a(chips)',
 PATH='I68',
 DRAWING='@BASEBOARD_FAB2_LIB.BASEBOARD_FAB2(SCH_1):PAGE193',
 TOLERANCE='10%',
 SEC_TYPE='0402V',
 MATERIAL='X6S',
 PHYS_PAGE='193',
 XY='(-1000,2450)',
 ROT='0',
 VER='1',
 VALUE='1.0UF',
 PACK_TYPE='0402V',
 PART_NUMBER='D97712-004',
 LOCATION='C4F1',
 ROOM='P1V8_MCP_CPU1',
 GROUP='PWR_MCP_CAP',
 SEC='1',
 CDS_LIB='dev_discrete',
 CDS_PART_NAME='CAP_A_0402V-1.0UF,6.3V,10%,X6SA',
 VOLTAGE='6.3V',
 PRIM_FILE='./archive_libs/discrete/cap_a/chips/chips.prt';

PART_NAME
 C4F2 'CAP_A_0603V-47UF,4V,20%,X5R,60A':
 GROUP='PWR_MCP_CAP';

SECTION_NUMBER 1
 '@BASEBOARD_FAB2_LIB.BASEBOARD_FAB2(SCH_1):PAGE193_I141@DEV_DISCRETE.CAP_A(CHIPS)':
 C_PATH='@baseboard_fab2_lib.baseboard_fab2(sch_1):page193_i141@dev_discrete.cap~
_a(chips)',
 P_PATH='@baseboard_fab2_lib.baseboard_fab2(sch_1):page193_i141@dev_discrete.cap~
_a(chips)',
 PATH='I141',
 DRAWING='@BASEBOARD_FAB2_LIB.BASEBOARD_FAB2(SCH_1):PAGE193',
 TOLERANCE='20%',
 SEC_TYPE='0603V',
 MATERIAL='X5R',
 PHYS_PAGE='193',
 XY='(-1600,2450)',
 ROT='0',
 VER='1',
 VALUE='47UF',
 PACK_TYPE='0603V',
 PART_NUMBER='602433-106',
 LOCATION='C4F2',
 GROUP='PWR_MCP_CAP',
 SEC='1',
 CDS_LIB='dev_discrete',
 CDS_PART_NAME='CAP_A_0603V-47UF,4V,20%,X5R,60A',
 VOLTAGE='4V',
 PRIM_FILE='./archive_libs/discrete/cap_a/chips/chips.prt';

PART_NAME
 C4F3 'CAP_A_0402V-1.0UF,6.3V,10%,X6SA':
 GROUP='PWR_MCP_CAP',
 ROOM='P1V8_MCP_CPU1';

SECTION_NUMBER 1
 '@BASEBOARD_FAB2_LIB.BASEBOARD_FAB2(SCH_1):PAGE193_I70@DEV_DISCRETE.CAP_A(CHIPS)':
 C_PATH='@baseboard_fab2_lib.baseboard_fab2(sch_1):page193_i70@dev_discrete.cap_~
a(chips)',
 P_PATH='@baseboard_fab2_lib.baseboard_fab2(sch_1):page193_i70@dev_discrete.cap_~
a(chips)',
 PATH='I70',
 DRAWING='@BASEBOARD_FAB2_LIB.BASEBOARD_FAB2(SCH_1):PAGE193',
 TOLERANCE='10%',
 SEC_TYPE='0402V',
 MATERIAL='X6S',
 PHYS_PAGE='193',
 XY='(-1300,2450)',
 ROT='0',
 VER='1',
 VALUE='1.0UF',
 PACK_TYPE='0402V',
 PART_NUMBER='D97712-004',
 LOCATION='C4F3',
 ROOM='P1V8_MCP_CPU1',
 GROUP='PWR_MCP_CAP',
 SEC='1',
 CDS_LIB='dev_discrete',
 CDS_PART_NAME='CAP_A_0402V-1.0UF,6.3V,10%,X6SA',
 VOLTAGE='6.3V',
 PRIM_FILE='./archive_libs/discrete/cap_a/chips/chips.prt';

PART_NAME
 C4F4 'CAPP_3018-68UF,16V,20%,TANT,72A':;

SECTION_NUMBER 1
 '@BASEBOARD_FAB2_LIB.BASEBOARD_FAB2(SCH_1):PAGE195_I112@MSTR_DISCRETE.CAPP(CHIPS)':
 C_PATH='@baseboard_fab2_lib.baseboard_fab2(sch_1):page195_i112@mstr_discrete.ca~
pp(chips)',
 P_PATH='@baseboard_fab2_lib.baseboard_fab2(sch_1):page195_i112@mstr_discrete.ca~
pp(chips)',
 PATH='I112',
 DRAWING='@BASEBOARD_FAB2_LIB.BASEBOARD_FAB2(SCH_1):PAGE195',
 TOLERANCE='20%',
 SEC_TYPE='3018',
 MATERIAL='TANT',
 PHYS_PAGE='195',
 XY='(-7250,1950)',
 ROT='0',
 VER='1',
 VALUE='68UF',
 PACK_TYPE='3018',
 PART_NUMBER='724613-112',
 LOCATION='C4F4',
 SEC='1',
 CDS_LIB='mstr_discrete',
 CDS_PART_NAME='CAPP_3018-68UF,16V,20%,TANT,72A',
 VOLTAGE='16V',
 PRIM_FILE='./archive_libs/mstr_discrete/capp/chips/chips.prt';

PART_NAME
 C4F5 'CAPP_3018-68UF,16V,20%,TANT,72A':;

SECTION_NUMBER 1
 '@BASEBOARD_FAB2_LIB.BASEBOARD_FAB2(SCH_1):PAGE195_I96@MSTR_DISCRETE.CAPP(CHIPS)':
 C_PATH='@baseboard_fab2_lib.baseboard_fab2(sch_1):page195_i96@mstr_discrete.cap~
p(chips)',
 P_PATH='@baseboard_fab2_lib.baseboard_fab2(sch_1):page195_i96@mstr_discrete.cap~
p(chips)',
 PATH='I96',
 DRAWING='@BASEBOARD_FAB2_LIB.BASEBOARD_FAB2(SCH_1):PAGE195',
 TOLERANCE='20%',
 SEC_TYPE='3018',
 MATERIAL='TANT',
 PHYS_PAGE='195',
 XY='(-7275,775)',
 ROT='0',
 VER='1',
 VALUE='68UF',
 PACK_TYPE='3018',
 PART_NUMBER='724613-112',
 LOCATION='C4F5',
 SEC='1',
 CDS_LIB='mstr_discrete',
 CDS_PART_NAME='CAPP_3018-68UF,16V,20%,TANT,72A',
 VOLTAGE='16V',
 PRIM_FILE='./archive_libs/mstr_discrete/capp/chips/chips.prt';

PART_NAME
 C4F6 'CAPP_4040LF-470UF,16V,20%,ALUMA':;

SECTION_NUMBER 1
 '@BASEBOARD_FAB2_LIB.BASEBOARD_FAB2(SCH_1):PAGE195_I82@MSTR_DISCRETE.CAPP(CHIPS)':
 C_PATH='@baseboard_fab2_lib.baseboard_fab2(sch_1):page195_i82@mstr_discrete.cap~
p(chips)',
 P_PATH='@baseboard_fab2_lib.baseboard_fab2(sch_1):page195_i82@mstr_discrete.cap~
p(chips)',
 PATH='I82',
 DRAWING='@BASEBOARD_FAB2_LIB.BASEBOARD_FAB2(SCH_1):PAGE195',
 TOLERANCE='20%',
 MATERIAL='ALUM',
 PHYS_PAGE='195',
 XY='(-7175,2950)',
 ROT='0',
 VER='1',
 VALUE='470UF',
 PACK_TYPE='4040LF',
 PART_NUMBER='A93539-036',
 LOCATION='C4F6',
 CDS_LIB='mstr_discrete',
 CDS_PART_NAME='CAPP_4040LF-470UF,16V,20%,ALUMA',
 VOLTAGE='16V',
 PRIM_FILE='./archive_libs/mstr_discrete/capp/chips/chips.prt';

PART_NAME
 C4F7 'CAPP_7343LF-330UF,6.3V,20%,POSA':
 GROUP='PWR_BULK_CAP',
 ROOM='PVPP_KLM_VR',
 REUSE_ID='28';

SECTION_NUMBER 1
 '@BASEBOARD_FAB2_LIB.BASEBOARD_FAB2(SCH_1):PAGE233_I217@MSTR_DISCRETE.CAPP(CHIPS)':
 C_PATH='@baseboard_fab2_lib.baseboard_fab2(sch_1):page233_i217@mstr_discrete.ca~
pp(chips)',
 P_PATH='@baseboard_fab2_lib.baseboard_fab2(sch_1):page233_i217@mstr_discrete.ca~
pp(chips)',
 PATH='I217',
 DRAWING='@BASEBOARD_FAB2_LIB.BASEBOARD_FAB2(SCH_1):PAGE233',
 TOLERANCE='20%',
 MATERIAL='POSCAP',
 BOM_COST='PVPP_KLM_VR',
 PHYS_PAGE='233',
 REUSE_ID='28',
 XY='(-1700,3500)',
 ROT='0',
 VER='1',
 VALUE='330UF',
 PACK_TYPE='7343LF',
 PART_NUMBER='724613-042',
 LOCATION='C4F7',
 ROOM='PVPP_KLM_VR',
 GROUP='PWR_BULK_CAP',
 CDS_LIB='mstr_discrete',
 CDS_PART_NAME='CAPP_7343LF-330UF,6.3V,20%,POSA',
 VOLTAGE='6.3V',
 PRIM_FILE='./archive_libs/mstr_discrete/capp/chips/chips.prt';

PART_NAME
 C4F9 'CAP_A_0402V-0.01UF,25V,10%,X7RA':
 ROOM='MEM';

SECTION_NUMBER 1
 '@BASEBOARD_FAB2_LIB.BASEBOARD_FAB2(SCH_1):PAGE98_I7@DEV_DISCRETE.CAP_A(CHIPS)':
 C_PATH='@baseboard_fab2_lib.baseboard_fab2(sch_1):page98_i7@dev_discrete.cap_a(~
chips)',
 P_PATH='@baseboard_fab2_lib.baseboard_fab2(sch_1):page98_i7@dev_discrete.cap_a(~
chips)',
 PATH='I7',
 DRAWING='@BASEBOARD_FAB2_LIB.BASEBOARD_FAB2(SCH_1):PAGE98',
 TOLERANCE='10%',
 SEC_TYPE='0402V',
 MATERIAL='X7R',
 BOM_COST='SM_CONTROLLER',
 PHYS_PAGE='98',
 XY='(-2250,3725)',
 ROT='0',
 VER='1',
 VALUE='0.01UF',
 PACK_TYPE='0402V',
 PART_NUMBER='A36096-045',
 LOCATION='C4F9',
 ROOM='MEM',
 SEC='1',
 CDS_LIB='dev_discrete',
 CDS_PART_NAME='CAP_A_0402V-0.01UF,25V,10%,X7RA',
 VOLTAGE='25V',
 PRIM_FILE='./archive_libs/discrete/cap_a/chips/chips.prt';

PART_NAME
 C4F10 'CAP_A_0402V-0.01UF,25V,10%,X7RA':
 ROOM='DDR4_CH_A';

SECTION_NUMBER 1
 '@BASEBOARD_FAB2_LIB.BASEBOARD_FAB2(SCH_1):PAGE43_I272@DEV_DISCRETE.CAP_A(CHIPS)':
 C_PATH='@baseboard_fab2_lib.baseboard_fab2(sch_1):page43_i272@dev_discrete.cap_~
a(chips)',
 P_PATH='@baseboard_fab2_lib.baseboard_fab2(sch_1):page43_i272@dev_discrete.cap_~
a(chips)',
 PATH='I272',
 DRAWING='@BASEBOARD_FAB2_LIB.BASEBOARD_FAB2(SCH_1):PAGE43',
 TOLERANCE='10%',
 SEC_TYPE='0402V',
 MATERIAL='X7R',
 BOM_COST='MEM',
 PHYS_PAGE='43',
 XY='(-4350,1050)',
 ROT='2',
 VER='1',
 VALUE='0.01UF',
 PACK_TYPE='0402V',
 PART_NUMBER='A36096-045',
 LOCATION='C4F10',
 ROOM='DDR4_CH_A',
 SEC='1',
 CDS_LIB='dev_discrete',
 CDS_PART_NAME='CAP_A_0402V-0.01UF,25V,10%,X7RA',
 VOLTAGE='25V',
 PRIM_FILE='./archive_libs/discrete/cap_a/chips/chips.prt';

PART_NAME
 C4F11 'CAPP_7343-220UF,4V,20%,POSCAP,A':
 GROUP='PWR_BULK_CAP';

SECTION_NUMBER 1
 '@BASEBOARD_FAB2_LIB.BASEBOARD_FAB2(SCH_1):PAGE233_I256@MSTR_DISCRETE.CAPP(CHIPS)':
 C_PATH='@baseboard_fab2_lib.baseboard_fab2(sch_1):page233_i256@mstr_discrete.ca~
pp(chips)',
 P_PATH='@baseboard_fab2_lib.baseboard_fab2(sch_1):page233_i256@mstr_discrete.ca~
pp(chips)',
 PATH='I256',
 DRAWING='@BASEBOARD_FAB2_LIB.BASEBOARD_FAB2(SCH_1):PAGE233',
 TOLERANCE='20%',
 SEC_TYPE='7343',
 MATERIAL='POSCAP',
 PHYS_PAGE='233',
 XY='(-1400,3500)',
 ROT='0',
 VER='1',
 VALUE='220UF',
 PACK_TYPE='7343',
 PART_NUMBER='724613-067',
 LOCATION='C4F11',
 GROUP='PWR_BULK_CAP',
 SEC='1',
 CDS_LIB='mstr_discrete',
 CDS_PART_NAME='CAPP_7343-220UF,4V,20%,POSCAP,A',
 VOLTAGE='4V',
 PRIM_FILE='./archive_libs/mstr_discrete/capp/chips/chips.prt';

PART_NAME
 C4F12 'CAP_0402LF-3300PF,50V,10%,EMPTA':
 ROOM='PVPP_KLM_VR',
 REUSE_ID='26';

SECTION_NUMBER 1
 '@BASEBOARD_FAB2_LIB.BASEBOARD_FAB2(SCH_1):PAGE233_I209@MSTR_DISCRETE.CAP(CHIPS)':
 C_PATH='@baseboard_fab2_lib.baseboard_fab2(sch_1):page233_i209@mstr_discrete.ca~
p(chips)',
 P_PATH='@baseboard_fab2_lib.baseboard_fab2(sch_1):page233_i209@mstr_discrete.ca~
p(chips)',
 PATH='I209',
 DRAWING='@BASEBOARD_FAB2_LIB.BASEBOARD_FAB2(SCH_1):PAGE233',
 TOLERANCE='10%',
 MATERIAL='EMPTY',
 BOM_COST='PVPP_KLM_VR',
 PHYS_PAGE='233',
 REUSE_ID='26',
 XY='(-2450,3475)',
 ROT='0',
 VER='1',
 VALUE='3300PF',
 PACK_TYPE='0402LF',
 PART_NUMBER='A36096-091',
 LOCATION='C4F12',
 ROOM='PVPP_KLM_VR',
 CDS_LIB='mstr_discrete',
 CDS_PART_NAME='CAP_0402LF-3300PF,50V,10%,EMPTA',
 VOLTAGE='50V',
 PRIM_FILE='./archive_libs/mstr_discrete/cap/chips/chips.prt';

PART_NAME
 C4G1 'CAP_A_0402V-0.01UF,25V,10%,X7RA':
 ROOM='MEM';

SECTION_NUMBER 1
 '@BASEBOARD_FAB2_LIB.BASEBOARD_FAB2(SCH_1):PAGE98_I43@DEV_DISCRETE.CAP_A(CHIPS)':
 C_PATH='@baseboard_fab2_lib.baseboard_fab2(sch_1):page98_i43@dev_discrete.cap_a~
(chips)',
 P_PATH='@baseboard_fab2_lib.baseboard_fab2(sch_1):page98_i43@dev_discrete.cap_a~
(chips)',
 PATH='I43',
 DRAWING='@BASEBOARD_FAB2_LIB.BASEBOARD_FAB2(SCH_1):PAGE98',
 TOLERANCE='10%',
 SEC_TYPE='0402V',
 MATERIAL='X7R',
 BOM_COST='SM_CONTROLLER',
 PHYS_PAGE='98',
 XY='(-200,3725)',
 ROT='0',
 VER='1',
 VALUE='0.01UF',
 PACK_TYPE='0402V',
 PART_NUMBER='A36096-045',
 LOCATION='C4G1',
 ROOM='MEM',
 SEC='1',
 CDS_LIB='dev_discrete',
 CDS_PART_NAME='CAP_A_0402V-0.01UF,25V,10%,X7RA',
 VOLTAGE='25V',
 PRIM_FILE='./archive_libs/discrete/cap_a/chips/chips.prt';

PART_NAME
 C4G2 'CAP_0805-10UF,16V,10%,X6S,C953A':;

SECTION_NUMBER 1
 '@BASEBOARD_FAB2_LIB.BASEBOARD_FAB2(SCH_1):PAGE233_I253@MSTR_DISCRETE.CAP(CHIPS)':
 C_PATH='@baseboard_fab2_lib.baseboard_fab2(sch_1):page233_i253@mstr_discrete.ca~
p(chips)',
 P_PATH='@baseboard_fab2_lib.baseboard_fab2(sch_1):page233_i253@mstr_discrete.ca~
p(chips)',
 PATH='I253',
 DRAWING='@BASEBOARD_FAB2_LIB.BASEBOARD_FAB2(SCH_1):PAGE233',
 TOLERANCE='10%',
 SEC_TYPE='0805',
 MATERIAL='X6S',
 PHYS_PAGE='233',
 XY='(-6250,4000)',
 ROT='0',
 VER='1',
 VALUE='10UF',
 PACK_TYPE='0805',
 PART_NUMBER='C95333-007',
 LOCATION='C4G2',
 SEC='1',
 CDS_LIB='mstr_discrete',
 CDS_PART_NAME='CAP_0805-10UF,16V,10%,X6S,C953A',
 VOLTAGE='16V',
 PRIM_FILE='./archive_libs/mstr_discrete/cap/chips/chips.prt';

PART_NAME
 C4G3 'CAP_A_0402V-0.01UF,25V,10%,X7RA':
 ROOM='DDR4_CH_A';

SECTION_NUMBER 1
 '@BASEBOARD_FAB2_LIB.BASEBOARD_FAB2(SCH_1):PAGE45_I179@DEV_DISCRETE.CAP_A(CHIPS)':
 C_PATH='@baseboard_fab2_lib.baseboard_fab2(sch_1):page45_i179@dev_discrete.cap_~
a(chips)',
 P_PATH='@baseboard_fab2_lib.baseboard_fab2(sch_1):page45_i179@dev_discrete.cap_~
a(chips)',
 PATH='I179',
 DRAWING='@BASEBOARD_FAB2_LIB.BASEBOARD_FAB2(SCH_1):PAGE45',
 TOLERANCE='10%',
 SEC_TYPE='0402V',
 MATERIAL='X7R',
 BOM_COST='MEM',
 PHYS_PAGE='45',
 XY='(-4600,1250)',
 ROT='2',
 VER='1',
 VALUE='0.01UF',
 PACK_TYPE='0402V',
 PART_NUMBER='A36096-045',
 LOCATION='C4G3',
 ROOM='DDR4_CH_A',
 SEC='1',
 CDS_LIB='dev_discrete',
 CDS_PART_NAME='CAP_A_0402V-0.01UF,25V,10%,X7RA',
 VOLTAGE='25V',
 PRIM_FILE='./archive_libs/discrete/cap_a/chips/chips.prt';

PART_NAME
 C4G4 'CAP_0402-1.0UF,16V,10%,X6S,D97A':
 ROOM='PVPP_KLM_VR',
 REUSE_ID='1';

SECTION_NUMBER 1
 '@BASEBOARD_FAB2_LIB.BASEBOARD_FAB2(SCH_1):PAGE233_I196@MSTR_DISCRETE.CAP(CHIPS)':
 C_PATH='@baseboard_fab2_lib.baseboard_fab2(sch_1):page233_i196@mstr_discrete.ca~
p(chips)',
 P_PATH='@baseboard_fab2_lib.baseboard_fab2(sch_1):page233_i196@mstr_discrete.ca~
p(chips)',
 PATH='I196',
 DRAWING='@BASEBOARD_FAB2_LIB.BASEBOARD_FAB2(SCH_1):PAGE233',
 FIN='VR_1P2',
 TOLERANCE='10%',
 MATERIAL='X6S',
 BOM_COST='PVPP_KLM_VR',
 PHYS_PAGE='233',
 REUSE_ID='1',
 XY='(-5000,4000)',
 ROT='0',
 VER='1',
 VALUE='1.0UF',
 PACK_TYPE='0402',
 PART_NUMBER='D97712-011',
 LOCATION='C4G4',
 ROOM='PVPP_KLM_VR',
 CDS_LIB='mstr_discrete',
 CDS_PART_NAME='CAP_0402-1.0UF,16V,10%,X6S,D97A',
 VOLTAGE='16V',
 PRIM_FILE='./archive_libs/mstr_discrete/cap/chips/chips.prt';

PART_NAME
 C4G5 'SC22U16V5MX-4-GP_SMD-BCG5-SC22A':;

SECTION_NUMBER 1
 '@BASEBOARD_FAB2_LIB.BASEBOARD_FAB2(SCH_1):PAGE233_I280@W_HDL.SC22U16V5MX-4-GP(CHIPS)':
 C_PATH='@baseboard_fab2_lib.baseboard_fab2(sch_1):page233_i280@w_hdl.\sc22u16v5~
mx-4-gp\(chips)',
 P_PATH='@baseboard_fab2_lib.baseboard_fab2(sch_1):page233_i280@w_hdl.\sc22u16v5~
mx-4-gp\(chips)',
 PATH='I280',
 DRAWING='@BASEBOARD_FAB2_LIB.BASEBOARD_FAB2(SCH_1):PAGE233',
 TYPE='X6S',
 PACK_SIZE='0805',
 RATED='16V',
 ATTRIBUTE='22UF',
 TOLERANCE='20%',
 SEC_TYPE='SMD-BCG5',
 PHYS_PAGE='233',
 XY='(-7300,3950)',
 ROT='0',
 VER='1',
 VALUE='SC22U16V5MX-4-GP',
 PACK_TYPE='SMD-BCG5',
 PART_NUMBER='078.22611.0811',
 LOCATION='C4G5',
 SEC='1',
 CDS_LIB='w_hdl',
 CDS_PART_NAME='SC22U16V5MX-4-GP_SMD-BCG5-SC22A',
 PRIM_FILE='C:/<user>/w_hdl/sc22u16v5mx#2d4#2dgp/chips/chips.prt';

PART_NAME
 C4G6 'CAP_0402LF-100.0PF,50V,5%,COG,A':
 ROOM='PVPP_KLM_VR',
 REUSE_ID='27';

SECTION_NUMBER 1
 '@BASEBOARD_FAB2_LIB.BASEBOARD_FAB2(SCH_1):PAGE233_I273@MSTR_DISCRETE.CAP(CHIPS)':
 C_PATH='@baseboard_fab2_lib.baseboard_fab2(sch_1):page233_i273@mstr_discrete.ca~
p(chips)',
 P_PATH='@baseboard_fab2_lib.baseboard_fab2(sch_1):page233_i273@mstr_discrete.ca~
p(chips)',
 PATH='I273',
 DRAWING='@BASEBOARD_FAB2_LIB.BASEBOARD_FAB2(SCH_1):PAGE233',
 TOLERANCE='5%',
 SEC_TYPE='0402LF',
 MATERIAL='COG',
 BOM_COST='PVPP_KLM_VR',
 PHYS_PAGE='233',
 REUSE_ID='27',
 XY='(-2150,2675)',
 ROT='2',
 VER='2',
 VALUE='100.0PF',
 PACK_TYPE='0402LF',
 PART_NUMBER='A36095-026',
 LOCATION='C4G6',
 ROOM='PVPP_KLM_VR',
 SEC='1',
 CDS_LIB='mstr_discrete',
 CDS_PART_NAME='CAP_0402LF-100.0PF,50V,5%,COG,A',
 VOLTAGE='50V',
 PRIM_FILE='./archive_libs/mstr_discrete/cap/chips/chips.prt';

PART_NAME
 C4G7 'CAP_0402LF-1000PF,50V,10%,EMPTA':
 ROOM='PVPP_KLM_VR',
 REUSE_ID='1';

SECTION_NUMBER 1
 '@BASEBOARD_FAB2_LIB.BASEBOARD_FAB2(SCH_1):PAGE233_I183@MSTR_DISCRETE.CAP(CHIPS)':
 C_PATH='@baseboard_fab2_lib.baseboard_fab2(sch_1):page233_i183@mstr_discrete.ca~
p(chips)',
 P_PATH='@baseboard_fab2_lib.baseboard_fab2(sch_1):page233_i183@mstr_discrete.ca~
p(chips)',
 PATH='I183',
 DRAWING='@BASEBOARD_FAB2_LIB.BASEBOARD_FAB2(SCH_1):PAGE233',
 FIN='VR_1P2',
 TOLERANCE='10%',
 MATERIAL='EMPTY',
 BOM_COST='PVPP_KLM_VR',
 PHYS_PAGE='233',
 REUSE_ID='1',
 XY='(-6500,2200)',
 ROT='2',
 VER='1',
 VALUE='1000PF',
 PACK_TYPE='0402LF',
 PART_NUMBER='A36096-046',
 LOCATION='C4G7',
 ROOM='PVPP_KLM_VR',
 CDS_LIB='mstr_discrete',
 CDS_PART_NAME='CAP_0402LF-1000PF,50V,10%,EMPTA',
 VOLTAGE='50V',
 PRIM_FILE='./archive_libs/mstr_discrete/cap/chips/chips.prt';

PART_NAME
 C4G8 'CAP_0402-0.027UF,16V,10%,X7R,AA':
 ROOM='PVPP_KLM_VR',
 REUSE_ID='26';

SECTION_NUMBER 1
 '@BASEBOARD_FAB2_LIB.BASEBOARD_FAB2(SCH_1):PAGE233_I194@MSTR_DISCRETE.CAP(CHIPS)':
 C_PATH='@baseboard_fab2_lib.baseboard_fab2(sch_1):page233_i194@mstr_discrete.ca~
p(chips)',
 P_PATH='@baseboard_fab2_lib.baseboard_fab2(sch_1):page233_i194@mstr_discrete.ca~
p(chips)',
 PATH='I194',
 DRAWING='@BASEBOARD_FAB2_LIB.BASEBOARD_FAB2(SCH_1):PAGE233',
 TOLERANCE='10%',
 SEC_TYPE='0402',
 MATERIAL='X7R',
 BOM_COST='PVPP_KLM_VR',
 PHYS_PAGE='233',
 REUSE_ID='26',
 XY='(-5000,2025)',
 ROT='0',
 VER='1',
 VALUE='0.027UF',
 PACK_TYPE='0402',
 PART_NUMBER='A36096-129',
 LOCATION='C4G8',
 ROOM='PVPP_KLM_VR',
 SEC='1',
 CDS_LIB='mstr_discrete',
 CDS_PART_NAME='CAP_0402-0.027UF,16V,10%,X7R,AA',
 VOLTAGE='16V',
 PRIM_FILE='./archive_libs/mstr_discrete/cap/chips/chips.prt';

PART_NAME
 C4G9 'CAP_0402LF-1000PF,50V,10%,X7R,A':
 ROOM='PVPP_KLM_VR',
 REUSE_ID='17';

SECTION_NUMBER 1
 '@BASEBOARD_FAB2_LIB.BASEBOARD_FAB2(SCH_1):PAGE233_I201@MSTR_DISCRETE.CAP(CHIPS)':
 C_PATH='@baseboard_fab2_lib.baseboard_fab2(sch_1):page233_i201@mstr_discrete.ca~
p(chips)',
 P_PATH='@baseboard_fab2_lib.baseboard_fab2(sch_1):page233_i201@mstr_discrete.ca~
p(chips)',
 PATH='I201',
 DRAWING='@BASEBOARD_FAB2_LIB.BASEBOARD_FAB2(SCH_1):PAGE233',
 TOLERANCE='10%',
 MATERIAL='X7R',
 BOM_COST='PVPP_KLM_VR',
 PHYS_PAGE='233',
 REUSE_ID='17',
 XY='(-3800,575)',
 ROT='0',
 VER='1',
 VALUE='1000PF',
 PACK_TYPE='0402LF',
 PART_NUMBER='A36096-046',
 LOCATION='C4G9',
 ROOM='PVPP_KLM_VR',
 CDS_LIB='mstr_discrete',
 CDS_PART_NAME='CAP_0402LF-1000PF,50V,10%,X7R,A',
 VOLTAGE='50V',
 PRIM_FILE='./archive_libs/mstr_discrete/cap/chips/chips.prt';

PART_NAME
 C4G10 'CAP_0402LF-2200PF,50V,10%,X7R,A':
 ROOM='PVPP_KLM_VR',
 REUSE_ID='27';

SECTION_NUMBER 1
 '@BASEBOARD_FAB2_LIB.BASEBOARD_FAB2(SCH_1):PAGE233_I274@MSTR_DISCRETE.CAP(CHIPS)':
 C_PATH='@baseboard_fab2_lib.baseboard_fab2(sch_1):page233_i274@mstr_discrete.ca~
p(chips)',
 P_PATH='@baseboard_fab2_lib.baseboard_fab2(sch_1):page233_i274@mstr_discrete.ca~
p(chips)',
 PATH='I274',
 DRAWING='@BASEBOARD_FAB2_LIB.BASEBOARD_FAB2(SCH_1):PAGE233',
 TOLERANCE='10%',
 SEC_TYPE='0402LF',
 MATERIAL='X7R',
 BOM_COST='PVPP_KLM_VR',
 PHYS_PAGE='233',
 REUSE_ID='27',
 XY='(-2775,2300)',
 ROT='2',
 VER='2',
 VALUE='2200PF',
 PACK_TYPE='0402LF',
 PART_NUMBER='A36096-075',
 LOCATION='C4G10',
 ROOM='PVPP_KLM_VR',
 SEC='1',
 CDS_LIB='mstr_discrete',
 CDS_PART_NAME='CAP_0402LF-2200PF,50V,10%,X7R,A',
 VOLTAGE='50V',
 PRIM_FILE='./archive_libs/mstr_discrete/cap/chips/chips.prt';

PART_NAME
 C4G11 'CAP_0402LF-2200PF,50V,10%,X7R,A':
 ROOM='PVPP_KLM_VR',
 REUSE_ID='26';

SECTION_NUMBER 1
 '@BASEBOARD_FAB2_LIB.BASEBOARD_FAB2(SCH_1):PAGE233_I267@MSTR_DISCRETE.CAP(CHIPS)':
 C_PATH='@baseboard_fab2_lib.baseboard_fab2(sch_1):page233_i267@mstr_discrete.ca~
p(chips)',
 P_PATH='@baseboard_fab2_lib.baseboard_fab2(sch_1):page233_i267@mstr_discrete.ca~
p(chips)',
 PATH='I267',
 DRAWING='@BASEBOARD_FAB2_LIB.BASEBOARD_FAB2(SCH_1):PAGE233',
 SPOF='TRUE',
 TOLERANCE='10%',
 SEC_TYPE='0402LF',
 MATERIAL='X7R',
 BOM_COST='PVPP_KLM_VR',
 PHYS_PAGE='233',
 REUSE_ID='26',
 XY='(-950,1700)',
 ROT='0',
 VER='1',
 VALUE='2200PF',
 PACK_TYPE='0402LF',
 PART_NUMBER='A36096-075',
 LOCATION='C4G11',
 ROOM='PVPP_KLM_VR',
 SEC='1',
 CDS_LIB='mstr_discrete',
 CDS_PART_NAME='CAP_0402LF-2200PF,50V,10%,X7R,A',
 VOLTAGE='50V',
 PRIM_FILE='./archive_libs/mstr_discrete/cap/chips/chips.prt';

PART_NAME
 C4G12 'CAP_0402LF-1000PF,50V,10%,EMPTA':
 ROOM='VTT_GHJ_PWR_VR';

SECTION_NUMBER 1
 '@BASEBOARD_FAB2_LIB.BASEBOARD_FAB2(SCH_1):PAGE229_I2@MSTR_DISCRETE.CAP(CHIPS)':
 C_PATH='@baseboard_fab2_lib.baseboard_fab2(sch_1):page229_i2@mstr_discrete.cap(~
chips)',
 P_PATH='@baseboard_fab2_lib.baseboard_fab2(sch_1):page229_i2@mstr_discrete.cap(~
chips)',
 PATH='I2',
 DRAWING='@BASEBOARD_FAB2_LIB.BASEBOARD_FAB2(SCH_1):PAGE229',
 TOLERANCE='10%',
 SEC_TYPE='0402LF',
 MATERIAL='EMPTY',
 BOM_COST='MEM_VRD_VTT_GHJ',
 PHYS_PAGE='229',
 XY='(-475,-550)',
 ROT='2',
 VER='1',
 VALUE='1000PF',
 PACK_TYPE='0402LF',
 PART_NUMBER='A36096-046',
 LOCATION='C4G12',
 ROOM='VTT_GHJ_PWR_VR',
 SEC='1',
 CDS_LIB='mstr_discrete',
 CDS_PART_NAME='CAP_0402LF-1000PF,50V,10%,EMPTA',
 VOLTAGE='50V',
 PRIM_FILE='./archive_libs/mstr_discrete/cap/chips/chips.prt';

PART_NAME
 C4G13 'CAP_0402LF-1000PF,50V,10%,X7R,A':
 ROOM='VTT_GHJ_PWR_VR';

SECTION_NUMBER 1
 '@BASEBOARD_FAB2_LIB.BASEBOARD_FAB2(SCH_1):PAGE229_I26@MSTR_DISCRETE.CAP(CHIPS)':
 C_PATH='@baseboard_fab2_lib.baseboard_fab2(sch_1):page229_i26@mstr_discrete.cap~
(chips)',
 P_PATH='@baseboard_fab2_lib.baseboard_fab2(sch_1):page229_i26@mstr_discrete.cap~
(chips)',
 PATH='I26',
 DRAWING='@BASEBOARD_FAB2_LIB.BASEBOARD_FAB2(SCH_1):PAGE229',
 TOLERANCE='10%',
 SEC_TYPE='0402LF',
 MATERIAL='X7R',
 BOM_COST='MEM_VRD_VTT_GHJ',
 PHYS_PAGE='229',
 XY='(3975,1450)',
 ROT='2',
 VER='1',
 VALUE='1000PF',
 PACK_TYPE='0402LF',
 PART_NUMBER='A36096-046',
 LOCATION='C4G13',
 ROOM='VTT_GHJ_PWR_VR',
 SEC='1',
 CDS_LIB='mstr_discrete',
 CDS_PART_NAME='CAP_0402LF-1000PF,50V,10%,X7R,A',
 VOLTAGE='50V',
 PRIM_FILE='./archive_libs/mstr_discrete/cap/chips/chips.prt';

PART_NAME
 C4G14 'CAP_0402LF-1000PF,50V,10%,X7R,A':
 ROOM='VTT_ABC_PWR_VR';

SECTION_NUMBER 1
 '@BASEBOARD_FAB2_LIB.BASEBOARD_FAB2(SCH_1):PAGE221_I30@MSTR_DISCRETE.CAP(CHIPS)':
 C_PATH='@baseboard_fab2_lib.baseboard_fab2(sch_1):page221_i30@mstr_discrete.cap~
(chips)',
 P_PATH='@baseboard_fab2_lib.baseboard_fab2(sch_1):page221_i30@mstr_discrete.cap~
(chips)',
 PATH='I30',
 DRAWING='@BASEBOARD_FAB2_LIB.BASEBOARD_FAB2(SCH_1):PAGE221',
 TOLERANCE='10%',
 SEC_TYPE='0402LF',
 MATERIAL='X7R',
 BOM_COST='MEM_VRD_VTT_ABC',
 PHYS_PAGE='221',
 XY='(3850,1525)',
 ROT='0',
 VER='1',
 VALUE='1000PF',
 PACK_TYPE='0402LF',
 PART_NUMBER='A36096-046',
 LOCATION='C4G14',
 ROOM='VTT_ABC_PWR_VR',
 SEC='1',
 CDS_LIB='mstr_discrete',
 CDS_PART_NAME='CAP_0402LF-1000PF,50V,10%,X7R,A',
 VOLTAGE='50V',
 PRIM_FILE='./archive_libs/mstr_discrete/cap/chips/chips.prt';

PART_NAME
 C4G15 'CAP_0402-1.0UF,16V,10%,X6S,D97A':
 ROOM='VTT_ABC_PWR_VR';

SECTION_NUMBER 1
 '@BASEBOARD_FAB2_LIB.BASEBOARD_FAB2(SCH_1):PAGE221_I13@MSTR_DISCRETE.CAP(CHIPS)':
 C_PATH='@baseboard_fab2_lib.baseboard_fab2(sch_1):page221_i13@mstr_discrete.cap~
(chips)',
 P_PATH='@baseboard_fab2_lib.baseboard_fab2(sch_1):page221_i13@mstr_discrete.cap~
(chips)',
 PATH='I13',
 DRAWING='@BASEBOARD_FAB2_LIB.BASEBOARD_FAB2(SCH_1):PAGE221',
 TOLERANCE='10%',
 MATERIAL='X6S',
 BOM_COST='MEM_VRD_VTT_ABC',
 PHYS_PAGE='221',
 XY='(200,1400)',
 ROT='0',
 VER='1',
 VALUE='1.0UF',
 PACK_TYPE='0402',
 PART_NUMBER='D97712-011',
 LOCATION='C4G15',
 ROOM='VTT_ABC_PWR_VR',
 CDS_LIB='mstr_discrete',
 CDS_PART_NAME='CAP_0402-1.0UF,16V,10%,X6S,D97A',
 VOLTAGE='16V',
 PRIM_FILE='./archive_libs/mstr_discrete/cap/chips/chips.prt';

PART_NAME
 C4G16 'CAP_0402-1.0UF,16V,10%,X6S,D97A':
 ROOM='VTT_ABC_PWR_VR';

SECTION_NUMBER 1
 '@BASEBOARD_FAB2_LIB.BASEBOARD_FAB2(SCH_1):PAGE221_I22@MSTR_DISCRETE.CAP(CHIPS)':
 C_PATH='@baseboard_fab2_lib.baseboard_fab2(sch_1):page221_i22@mstr_discrete.cap~
(chips)',
 P_PATH='@baseboard_fab2_lib.baseboard_fab2(sch_1):page221_i22@mstr_discrete.cap~
(chips)',
 PATH='I22',
 DRAWING='@BASEBOARD_FAB2_LIB.BASEBOARD_FAB2(SCH_1):PAGE221',
 TOLERANCE='10%',
 SEC_TYPE='0402',
 MATERIAL='X6S',
 BOM_COST='MEM_VRD_VTT_ABC',
 PHYS_PAGE='221',
 XY='(2100,750)',
 ROT='0',
 VER='1',
 VALUE='1.0UF',
 PACK_TYPE='0402',
 PART_NUMBER='D97712-011',
 LOCATION='C4G16',
 ROOM='VTT_ABC_PWR_VR',
 SEC='1',
 CDS_LIB='mstr_discrete',
 CDS_PART_NAME='CAP_0402-1.0UF,16V,10%,X6S,D97A',
 VOLTAGE='16V',
 PRIM_FILE='./archive_libs/mstr_discrete/cap/chips/chips.prt';

PART_NAME
 C4G17 'CAP_A_0402V-0.01UF,25V,10%,X7RA':
 ROOM='MEM';

SECTION_NUMBER 1
 '@BASEBOARD_FAB2_LIB.BASEBOARD_FAB2(SCH_1):PAGE98_I51@DEV_DISCRETE.CAP_A(CHIPS)':
 C_PATH='@baseboard_fab2_lib.baseboard_fab2(sch_1):page98_i51@dev_discrete.cap_a~
(chips)',
 P_PATH='@baseboard_fab2_lib.baseboard_fab2(sch_1):page98_i51@dev_discrete.cap_a~
(chips)',
 PATH='I51',
 DRAWING='@BASEBOARD_FAB2_LIB.BASEBOARD_FAB2(SCH_1):PAGE98',
 TOLERANCE='10%',
 SEC_TYPE='0402V',
 MATERIAL='X7R',
 BOM_COST='SM_CONTROLLER',
 PHYS_PAGE='98',
 XY='(1950,3725)',
 ROT='0',
 VER='1',
 VALUE='0.01UF',
 PACK_TYPE='0402V',
 PART_NUMBER='A36096-045',
 LOCATION='C4G17',
 ROOM='MEM',
 SEC='1',
 CDS_LIB='dev_discrete',
 CDS_PART_NAME='CAP_A_0402V-0.01UF,25V,10%,X7RA',
 VOLTAGE='25V',
 PRIM_FILE='./archive_libs/discrete/cap_a/chips/chips.prt';

PART_NAME
 C4G18 'CAP_0402-1.0UF,16V,10%,X6S,D97A':
 ROOM='VTT_GHJ_PWR_VR';

SECTION_NUMBER 1
 '@BASEBOARD_FAB2_LIB.BASEBOARD_FAB2(SCH_1):PAGE229_I16@MSTR_DISCRETE.CAP(CHIPS)':
 C_PATH='@baseboard_fab2_lib.baseboard_fab2(sch_1):page229_i16@mstr_discrete.cap~
(chips)',
 P_PATH='@baseboard_fab2_lib.baseboard_fab2(sch_1):page229_i16@mstr_discrete.cap~
(chips)',
 PATH='I16',
 DRAWING='@BASEBOARD_FAB2_LIB.BASEBOARD_FAB2(SCH_1):PAGE229',
 TOLERANCE='10%',
 SEC_TYPE='0402',
 MATERIAL='X6S',
 BOM_COST='MEM_VRD_VTT_GHJ',
 PHYS_PAGE='229',
 XY='(350,1325)',
 ROT='0',
 VER='1',
 VALUE='1.0UF',
 PACK_TYPE='0402',
 PART_NUMBER='D97712-011',
 LOCATION='C4G18',
 ROOM='VTT_GHJ_PWR_VR',
 SEC='1',
 CDS_LIB='mstr_discrete',
 CDS_PART_NAME='CAP_0402-1.0UF,16V,10%,X6S,D97A',
 VOLTAGE='16V',
 PRIM_FILE='./archive_libs/mstr_discrete/cap/chips/chips.prt';

PART_NAME
 C4G19 'CAP_A_0402V-0.01UF,25V,10%,X7RA':
 ROOM='DDR4_CH_C';

SECTION_NUMBER 1
 '@BASEBOARD_FAB2_LIB.BASEBOARD_FAB2(SCH_1):PAGE47_I188@DEV_DISCRETE.CAP_A(CHIPS)':
 C_PATH='@baseboard_fab2_lib.baseboard_fab2(sch_1):page47_i188@dev_discrete.cap_~
a(chips)',
 P_PATH='@baseboard_fab2_lib.baseboard_fab2(sch_1):page47_i188@dev_discrete.cap_~
a(chips)',
 PATH='I188',
 DRAWING='@BASEBOARD_FAB2_LIB.BASEBOARD_FAB2(SCH_1):PAGE47',
 TOLERANCE='10%',
 SEC_TYPE='0402V',
 MATERIAL='X7R',
 BOM_COST='MEM',
 PHYS_PAGE='47',
 XY='(-4650,1300)',
 ROT='2',
 VER='1',
 VALUE='0.01UF',
 PACK_TYPE='0402V',
 PART_NUMBER='A36096-045',
 LOCATION='C4G19',
 ROOM='DDR4_CH_C',
 SEC='1',
 CDS_LIB='dev_discrete',
 CDS_PART_NAME='CAP_A_0402V-0.01UF,25V,10%,X7RA',
 VOLTAGE='25V',
 PRIM_FILE='./archive_libs/discrete/cap_a/chips/chips.prt';

PART_NAME
 C4G20 'CAP_0805LF-22UF,4V,20%,X6S,C95A':
 GROUP='PWR_MLCC_CAP',
 ROOM='VTT_GHJ_PWR_VR';

SECTION_NUMBER 1
 '@BASEBOARD_FAB2_LIB.BASEBOARD_FAB2(SCH_1):PAGE229_I23@MSTR_DISCRETE.CAP(CHIPS)':
 C_PATH='@baseboard_fab2_lib.baseboard_fab2(sch_1):page229_i23@mstr_discrete.cap~
(chips)',
 P_PATH='@baseboard_fab2_lib.baseboard_fab2(sch_1):page229_i23@mstr_discrete.cap~
(chips)',
 PATH='I23',
 DRAWING='@BASEBOARD_FAB2_LIB.BASEBOARD_FAB2(SCH_1):PAGE229',
 TOLERANCE='20%',
 SEC_TYPE='0805LF',
 MATERIAL='X6S',
 BOM_COST='MEM_VRD_VTT_GHJ',
 PHYS_PAGE='229',
 XY='(3850,900)',
 ROT='0',
 VER='1',
 VALUE='22UF',
 PACK_TYPE='0805LF',
 PART_NUMBER='C95333-002',
 LOCATION='C4G20',
 ROOM='VTT_GHJ_PWR_VR',
 GROUP='PWR_MLCC_CAP',
 SEC='1',
 CDS_LIB='mstr_discrete',
 CDS_PART_NAME='CAP_0805LF-22UF,4V,20%,X6S,C95A',
 VOLTAGE='4V',
 PRIM_FILE='./archive_libs/mstr_discrete/cap/chips/chips.prt';

PART_NAME
 C4G21 'CAP_0402-1.0UF,16V,10%,X6S,D97A':
 ROOM='VTT_GHJ_PWR_VR';

SECTION_NUMBER 1
 '@BASEBOARD_FAB2_LIB.BASEBOARD_FAB2(SCH_1):PAGE229_I21@MSTR_DISCRETE.CAP(CHIPS)':
 C_PATH='@baseboard_fab2_lib.baseboard_fab2(sch_1):page229_i21@mstr_discrete.cap~
(chips)',
 P_PATH='@baseboard_fab2_lib.baseboard_fab2(sch_1):page229_i21@mstr_discrete.cap~
(chips)',
 PATH='I21',
 DRAWING='@BASEBOARD_FAB2_LIB.BASEBOARD_FAB2(SCH_1):PAGE229',
 TOLERANCE='10%',
 SEC_TYPE='0402',
 MATERIAL='X6S',
 BOM_COST='MEM_VRD_VTT_GHJ',
 PHYS_PAGE='229',
 XY='(2200,675)',
 ROT='0',
 VER='1',
 VALUE='1.0UF',
 PACK_TYPE='0402',
 PART_NUMBER='D97712-011',
 LOCATION='C4G21',
 ROOM='VTT_GHJ_PWR_VR',
 SEC='1',
 CDS_LIB='mstr_discrete',
 CDS_PART_NAME='CAP_0402-1.0UF,16V,10%,X6S,D97A',
 VOLTAGE='16V',
 PRIM_FILE='./archive_libs/mstr_discrete/cap/chips/chips.prt';

PART_NAME
 C4G22 'CAP_A_0402V-0.1UF,16V,10%,X7R,A':
 ROOM='MEM',
 SIGNAL_MODEL='DEFAULT_CAPACITOR_100000pF_2_1';

SECTION_NUMBER 1
 '@BASEBOARD_FAB2_LIB.BASEBOARD_FAB2(SCH_1):PAGE99_I27@DEV_DISCRETE.CAP_A(CHIPS)':
 C_PATH='@baseboard_fab2_lib.baseboard_fab2(sch_1):page99_i27@dev_discrete.cap_a~
(chips)',
 P_PATH='@baseboard_fab2_lib.baseboard_fab2(sch_1):page99_i27@dev_discrete.cap_a~
(chips)',
 PATH='I27',
 DRAWING='@BASEBOARD_FAB2_LIB.BASEBOARD_FAB2(SCH_1):PAGE99',
 CD_SEC='1',
 TOLERANCE='10%',
 MATERIAL='X7R',
 BOM_COST='SM_CONTROLLER',
 PHYS_PAGE='99',
 XY='(2225,2700)',
 ROT='0',
 VER='1',
 VALUE='0.1UF',
 PACK_TYPE='0402V',
 PART_NUMBER='A36096-030',
 LOCATION='C4G22',
 SIGNAL_MODEL='DEFAULT_CAPACITOR_100000pF_2_1',
 ROOM='MEM',
 CDS_LIB='dev_discrete',
 CDS_PART_NAME='CAP_A_0402V-0.1UF,16V,10%,X7R,A',
 VOLTAGE='16V',
 PRIM_FILE='./archive_libs/discrete/cap_a/chips/chips.prt';

PART_NAME
 C4G23 'CAP_0402LF-1000PF,50V,10%,EMPTA':
 ROOM='VTT_ABC_PWR_VR';

SECTION_NUMBER 1
 '@BASEBOARD_FAB2_LIB.BASEBOARD_FAB2(SCH_1):PAGE221_I2@MSTR_DISCRETE.CAP(CHIPS)':
 C_PATH='@baseboard_fab2_lib.baseboard_fab2(sch_1):page221_i2@mstr_discrete.cap(~
chips)',
 P_PATH='@baseboard_fab2_lib.baseboard_fab2(sch_1):page221_i2@mstr_discrete.cap(~
chips)',
 PATH='I2',
 DRAWING='@BASEBOARD_FAB2_LIB.BASEBOARD_FAB2(SCH_1):PAGE221',
 TOLERANCE='10%',
 SEC_TYPE='0402LF',
 MATERIAL='EMPTY',
 BOM_COST='MEM_VRD_VTT_ABC',
 PHYS_PAGE='221',
 XY='(-650,-475)',
 ROT='2',
 VER='1',
 VALUE='1000PF',
 PACK_TYPE='0402LF',
 PART_NUMBER='A36096-046',
 LOCATION='C4G23',
 ROOM='VTT_ABC_PWR_VR',
 SEC='1',
 CDS_LIB='mstr_discrete',
 CDS_PART_NAME='CAP_0402LF-1000PF,50V,10%,EMPTA',
 VOLTAGE='50V',
 PRIM_FILE='./archive_libs/mstr_discrete/cap/chips/chips.prt';

PART_NAME
 C4G24 'CAP_0805LF-22UF,4V,20%,X6S,C95A':
 GROUP='PWR_MLCC_CAP',
 ROOM='VTT_ABC_PWR_VR';

SECTION_NUMBER 1
 '@BASEBOARD_FAB2_LIB.BASEBOARD_FAB2(SCH_1):PAGE221_I24@MSTR_DISCRETE.CAP(CHIPS)':
 C_PATH='@baseboard_fab2_lib.baseboard_fab2(sch_1):page221_i24@mstr_discrete.cap~
(chips)',
 P_PATH='@baseboard_fab2_lib.baseboard_fab2(sch_1):page221_i24@mstr_discrete.cap~
(chips)',
 PATH='I24',
 DRAWING='@BASEBOARD_FAB2_LIB.BASEBOARD_FAB2(SCH_1):PAGE221',
 TOLERANCE='20%',
 SEC_TYPE='0805LF',
 MATERIAL='X6S',
 BOM_COST='MEM_VRD_VTT_ABC',
 PHYS_PAGE='221',
 XY='(3700,950)',
 ROT='0',
 VER='1',
 VALUE='22UF',
 PACK_TYPE='0805LF',
 PART_NUMBER='C95333-002',
 LOCATION='C4G24',
 ROOM='VTT_ABC_PWR_VR',
 GROUP='PWR_MLCC_CAP',
 SEC='1',
 CDS_LIB='mstr_discrete',
 CDS_PART_NAME='CAP_0805LF-22UF,4V,20%,X6S,C95A',
 VOLTAGE='4V',
 PRIM_FILE='./archive_libs/mstr_discrete/cap/chips/chips.prt';

PART_NAME
 C4G25 'CAP_A_0402V-0.1UF,16V,10%,X7R,A':
 ROOM='MEM',
 SIGNAL_MODEL='DEFAULT_CAPACITOR_100000pF_2_1';

SECTION_NUMBER 1
 '@BASEBOARD_FAB2_LIB.BASEBOARD_FAB2(SCH_1):PAGE99_I41@DEV_DISCRETE.CAP_A(CHIPS)':
 C_PATH='@baseboard_fab2_lib.baseboard_fab2(sch_1):page99_i41@dev_discrete.cap_a~
(chips)',
 P_PATH='@baseboard_fab2_lib.baseboard_fab2(sch_1):page99_i41@dev_discrete.cap_a~
(chips)',
 PATH='I41',
 DRAWING='@BASEBOARD_FAB2_LIB.BASEBOARD_FAB2(SCH_1):PAGE99',
 CD_SEC='1',
 TOLERANCE='10%',
 MATERIAL='X7R',
 BOM_COST='SM_CONTROLLER',
 PHYS_PAGE='99',
 XY='(1650,2675)',
 ROT='0',
 VER='1',
 VALUE='0.1UF',
 PACK_TYPE='0402V',
 PART_NUMBER='A36096-030',
 LOCATION='C4G25',
 SIGNAL_MODEL='DEFAULT_CAPACITOR_100000pF_2_1',
 ROOM='MEM',
 CDS_LIB='dev_discrete',
 CDS_PART_NAME='CAP_A_0402V-0.1UF,16V,10%,X7R,A',
 VOLTAGE='16V',
 PRIM_FILE='./archive_libs/discrete/cap_a/chips/chips.prt';

PART_NAME
 C4G26 'CAP_0603LF-0.1UF,25V,10%,X7R,6A':
 ROOM='PVPP_KLM_VR',
 REUSE_ID='27';

SECTION_NUMBER 1
 '@BASEBOARD_FAB2_LIB.BASEBOARD_FAB2(SCH_1):PAGE233_I224@MSTR_DISCRETE.CAP(CHIPS)':
 C_PATH='@baseboard_fab2_lib.baseboard_fab2(sch_1):page233_i224@mstr_discrete.ca~
p(chips)',
 P_PATH='@baseboard_fab2_lib.baseboard_fab2(sch_1):page233_i224@mstr_discrete.ca~
p(chips)',
 PATH='I224',
 DRAWING='@BASEBOARD_FAB2_LIB.BASEBOARD_FAB2(SCH_1):PAGE233',
 SPOF='TRUE',
 TOLERANCE='10%',
 MATERIAL='X7R',
 BOM_COST='PVPP_KLM_VR',
 PHYS_PAGE='233',
 REUSE_ID='27',
 XY='(-3300,4050)',
 ROT='2',
 VER='2',
 VALUE='0.1UF',
 PACK_TYPE='0603LF',
 PART_NUMBER='602433-020',
 LOCATION='C4G26',
 ROOM='PVPP_KLM_VR',
 CDS_LIB='mstr_discrete',
 CDS_PART_NAME='CAP_0603LF-0.1UF,25V,10%,X7R,6A',
 VOLTAGE='25V',
 PRIM_FILE='./archive_libs/mstr_discrete/cap/chips/chips.prt';

PART_NAME
 C4L1 'CAP_0603LF-10UF,4V,20%,X6S,E15A':
 GROUP='PWR_MLCC_CAP',
 ROOM='PVPP_KLM_VR';

SECTION_NUMBER 1
 '@BASEBOARD_FAB2_LIB.BASEBOARD_FAB2(SCH_1):PAGE232_I129@MSTR_DISCRETE.CAP(CHIPS)':
 C_PATH='@baseboard_fab2_lib.baseboard_fab2(sch_1):page232_i129@mstr_discrete.ca~
p(chips)',
 P_PATH='@baseboard_fab2_lib.baseboard_fab2(sch_1):page232_i129@mstr_discrete.ca~
p(chips)',
 PATH='I129',
 DRAWING='@BASEBOARD_FAB2_LIB.BASEBOARD_FAB2(SCH_1):PAGE232',
 TOLERANCE='20%',
 SEC_TYPE='0603LF',
 MATERIAL='X6S',
 BOM_COST='MEM_VRD_PVPP_AB',
 PHYS_PAGE='232',
 XY='(-5500,875)',
 ROT='0',
 VER='1',
 VALUE='10UF',
 PACK_TYPE='0603LF',
 PART_NUMBER='E15431-001',
 LOCATION='C4L1',
 ROOM='PVPP_KLM_VR',
 GROUP='PWR_MLCC_CAP',
 SEC='1',
 CDS_LIB='mstr_discrete',
 CDS_PART_NAME='CAP_0603LF-10UF,4V,20%,X6S,E15A',
 VOLTAGE='4V',
 PRIM_FILE='./archive_libs/mstr_discrete/cap/chips/chips.prt';

PART_NAME
 C4L2 'CAP_0603LF-10UF,4V,20%,X6S,E15A':
 GROUP='PWR_MLCC_CAP',
 ROOM='PVPP_KLM_VR';

SECTION_NUMBER 1
 '@BASEBOARD_FAB2_LIB.BASEBOARD_FAB2(SCH_1):PAGE232_I102@MSTR_DISCRETE.CAP(CHIPS)':
 C_PATH='@baseboard_fab2_lib.baseboard_fab2(sch_1):page232_i102@mstr_discrete.ca~
p(chips)',
 P_PATH='@baseboard_fab2_lib.baseboard_fab2(sch_1):page232_i102@mstr_discrete.ca~
p(chips)',
 PATH='I102',
 DRAWING='@BASEBOARD_FAB2_LIB.BASEBOARD_FAB2(SCH_1):PAGE232',
 TOLERANCE='20%',
 MATERIAL='X6S',
 BOM_COST='MEM_VRD_PVPP_AB',
 PHYS_PAGE='232',
 XY='(-8600,875)',
 ROT='0',
 VER='1',
 VALUE='10UF',
 PACK_TYPE='0603LF',
 PART_NUMBER='E15431-001',
 LOCATION='C4L2',
 ROOM='PVPP_KLM_VR',
 GROUP='PWR_MLCC_CAP',
 CDS_LIB='mstr_discrete',
 CDS_PART_NAME='CAP_0603LF-10UF,4V,20%,X6S,E15A',
 VOLTAGE='4V',
 PRIM_FILE='./archive_libs/mstr_discrete/cap/chips/chips.prt';

PART_NAME
 C4L3 'CAP_0603LF-10UF,4V,20%,X6S,E15A':
 GROUP='PWR_MLCC_CAP',
 ROOM='PVPP_KLM_VR';

SECTION_NUMBER 1
 '@BASEBOARD_FAB2_LIB.BASEBOARD_FAB2(SCH_1):PAGE232_I106@MSTR_DISCRETE.CAP(CHIPS)':
 C_PATH='@baseboard_fab2_lib.baseboard_fab2(sch_1):page232_i106@mstr_discrete.ca~
p(chips)',
 P_PATH='@baseboard_fab2_lib.baseboard_fab2(sch_1):page232_i106@mstr_discrete.ca~
p(chips)',
 PATH='I106',
 DRAWING='@BASEBOARD_FAB2_LIB.BASEBOARD_FAB2(SCH_1):PAGE232',
 TOLERANCE='20%',
 MATERIAL='X6S',
 BOM_COST='MEM_VRD_PVPP_AB',
 PHYS_PAGE='232',
 XY='(-7775,875)',
 ROT='0',
 VER='1',
 VALUE='10UF',
 PACK_TYPE='0603LF',
 PART_NUMBER='E15431-001',
 LOCATION='C4L3',
 ROOM='PVPP_KLM_VR',
 GROUP='PWR_MLCC_CAP',
 CDS_LIB='mstr_discrete',
 CDS_PART_NAME='CAP_0603LF-10UF,4V,20%,X6S,E15A',
 VOLTAGE='4V',
 PRIM_FILE='./archive_libs/mstr_discrete/cap/chips/chips.prt';

PART_NAME
 C4L4 'CAP_0603LF-10UF,4V,20%,X6S,E15A':
 GROUP='PWR_MLCC_CAP',
 ROOM='PVPP_KLM_VR';

SECTION_NUMBER 1
 '@BASEBOARD_FAB2_LIB.BASEBOARD_FAB2(SCH_1):PAGE232_I108@MSTR_DISCRETE.CAP(CHIPS)':
 C_PATH='@baseboard_fab2_lib.baseboard_fab2(sch_1):page232_i108@mstr_discrete.ca~
p(chips)',
 P_PATH='@baseboard_fab2_lib.baseboard_fab2(sch_1):page232_i108@mstr_discrete.ca~
p(chips)',
 PATH='I108',
 DRAWING='@BASEBOARD_FAB2_LIB.BASEBOARD_FAB2(SCH_1):PAGE232',
 TOLERANCE='20%',
 MATERIAL='X6S',
 BOM_COST='MEM_VRD_PVPP_AB',
 PHYS_PAGE='232',
 XY='(-7500,875)',
 ROT='0',
 VER='1',
 VALUE='10UF',
 PACK_TYPE='0603LF',
 PART_NUMBER='E15431-001',
 LOCATION='C4L4',
 ROOM='PVPP_KLM_VR',
 GROUP='PWR_MLCC_CAP',
 CDS_LIB='mstr_discrete',
 CDS_PART_NAME='CAP_0603LF-10UF,4V,20%,X6S,E15A',
 VOLTAGE='4V',
 PRIM_FILE='./archive_libs/mstr_discrete/cap/chips/chips.prt';

PART_NAME
 C4L5 'CAPP_3018-470UF,2.5V,20%,ALUM,A':
 GROUP='PWR_BULK_CAP',
 ROOM='VDDQ_DEF_PWR_VR';

SECTION_NUMBER 1
 '@BASEBOARD_FAB2_LIB.BASEBOARD_FAB2(SCH_1):PAGE220_I78@MSTR_DISCRETE.CAPP(CHIPS)':
 C_PATH='@baseboard_fab2_lib.baseboard_fab2(sch_1):page220_i78@mstr_discrete.cap~
p(chips)',
 P_PATH='@baseboard_fab2_lib.baseboard_fab2(sch_1):page220_i78@mstr_discrete.cap~
p(chips)',
 PATH='I78',
 DRAWING='@BASEBOARD_FAB2_LIB.BASEBOARD_FAB2(SCH_1):PAGE220',
 TOLERANCE='20%',
 SEC_TYPE='3018',
 MATERIAL='ALUM',
 PHYS_PAGE='220',
 XY='(3800,-100)',
 ROT='0',
 VER='1',
 VALUE='470UF',
 PACK_TYPE='3018',
 PART_NUMBER='699013-049',
 LOCATION='C4L5',
 ROOM='VDDQ_DEF_PWR_VR',
 GROUP='PWR_BULK_CAP',
 SEC='1',
 CDS_LIB='mstr_discrete',
 CDS_PART_NAME='CAPP_3018-470UF,2.5V,20%,ALUM,A',
 VOLTAGE='2.5V',
 PRIM_FILE='./archive_libs/mstr_discrete/capp/chips/chips.prt';

PART_NAME
 C4M1 'CAPP_7343-220UF,4V,20%,POSCAP,A':
 GROUP='PWR_BULK_CAP';

SECTION_NUMBER 1
 '@BASEBOARD_FAB2_LIB.BASEBOARD_FAB2(SCH_1):PAGE232_I267@MSTR_DISCRETE.CAPP(CHIPS)':
 C_PATH='@baseboard_fab2_lib.baseboard_fab2(sch_1):page232_i267@mstr_discrete.ca~
pp(chips)',
 P_PATH='@baseboard_fab2_lib.baseboard_fab2(sch_1):page232_i267@mstr_discrete.ca~
pp(chips)',
 PATH='I267',
 DRAWING='@BASEBOARD_FAB2_LIB.BASEBOARD_FAB2(SCH_1):PAGE232',
 TOLERANCE='20%',
 SEC_TYPE='7343',
 MATERIAL='POSCAP',
 PHYS_PAGE='232',
 XY='(-1800,3650)',
 ROT='0',
 VER='1',
 VALUE='220UF',
 PACK_TYPE='7343',
 PART_NUMBER='724613-067',
 LOCATION='C4M1',
 GROUP='PWR_BULK_CAP',
 SEC='1',
 CDS_LIB='mstr_discrete',
 CDS_PART_NAME='CAPP_7343-220UF,4V,20%,POSCAP,A',
 VOLTAGE='4V',
 PRIM_FILE='./archive_libs/mstr_discrete/capp/chips/chips.prt';

PART_NAME
 C4M2 'CAP_A_0603V-47UF,4V,20%,X5R,60A':
 GROUP='PWR_MLCC_CAP';

SECTION_NUMBER 1
 '@BASEBOARD_FAB2_LIB.BASEBOARD_FAB2(SCH_1):PAGE220_I292@DEV_DISCRETE.CAP_A(CHIPS)':
 C_PATH='@baseboard_fab2_lib.baseboard_fab2(sch_1):page220_i292@dev_discrete.cap~
_a(chips)',
 P_PATH='@baseboard_fab2_lib.baseboard_fab2(sch_1):page220_i292@dev_discrete.cap~
_a(chips)',
 PATH='I292',
 DRAWING='@BASEBOARD_FAB2_LIB.BASEBOARD_FAB2(SCH_1):PAGE220',
 BOM_SS='E15431-004',
 TOLERANCE='20%',
 SEC_TYPE='0603V',
 MATERIAL='X5R',
 PHYS_PAGE='220',
 XY='(1950,-650)',
 ROT='0',
 VER='1',
 VALUE='47UF',
 PACK_TYPE='0603V',
 PART_NUMBER='602433-106',
 LOCATION='C4M2',
 GROUP='PWR_MLCC_CAP',
 SEC='1',
 CDS_LIB='dev_discrete',
 CDS_PART_NAME='CAP_A_0603V-47UF,4V,20%,X5R,60A',
 VOLTAGE='4V',
 PRIM_FILE='./archive_libs/discrete/cap_a/chips/chips.prt';

PART_NAME
 C4M3 'CAP_0603LF-10UF,4V,20%,X6S,E15A':
 GROUP='PWR_MLCC_CAP',
 ROOM='PVPP_KLM_VR';

SECTION_NUMBER 1
 '@BASEBOARD_FAB2_LIB.BASEBOARD_FAB2(SCH_1):PAGE232_I111@MSTR_DISCRETE.CAP(CHIPS)':
 C_PATH='@baseboard_fab2_lib.baseboard_fab2(sch_1):page232_i111@mstr_discrete.ca~
p(chips)',
 P_PATH='@baseboard_fab2_lib.baseboard_fab2(sch_1):page232_i111@mstr_discrete.ca~
p(chips)',
 PATH='I111',
 DRAWING='@BASEBOARD_FAB2_LIB.BASEBOARD_FAB2(SCH_1):PAGE232',
 TOLERANCE='20%',
 MATERIAL='X6S',
 BOM_COST='MEM_VRD_PVPP_AB',
 PHYS_PAGE='232',
 XY='(-6625,875)',
 ROT='0',
 VER='1',
 VALUE='10UF',
 PACK_TYPE='0603LF',
 PART_NUMBER='E15431-001',
 LOCATION='C4M3',
 ROOM='PVPP_KLM_VR',
 GROUP='PWR_MLCC_CAP',
 CDS_LIB='mstr_discrete',
 CDS_PART_NAME='CAP_0603LF-10UF,4V,20%,X6S,E15A',
 VOLTAGE='4V',
 PRIM_FILE='./archive_libs/mstr_discrete/cap/chips/chips.prt';

PART_NAME
 C4M4 'CAP_0603LF-10UF,4V,20%,X6S,E15A':
 GROUP='PWR_MLCC_CAP',
 ROOM='PVPP_KLM_VR';

SECTION_NUMBER 1
 '@BASEBOARD_FAB2_LIB.BASEBOARD_FAB2(SCH_1):PAGE232_I125@MSTR_DISCRETE.CAP(CHIPS)':
 C_PATH='@baseboard_fab2_lib.baseboard_fab2(sch_1):page232_i125@mstr_discrete.ca~
p(chips)',
 P_PATH='@baseboard_fab2_lib.baseboard_fab2(sch_1):page232_i125@mstr_discrete.ca~
p(chips)',
 PATH='I125',
 DRAWING='@BASEBOARD_FAB2_LIB.BASEBOARD_FAB2(SCH_1):PAGE232',
 TOLERANCE='20%',
 MATERIAL='X6S',
 BOM_COST='MEM_VRD_PVPP_AB',
 PHYS_PAGE='232',
 XY='(-6325,875)',
 ROT='0',
 VER='1',
 VALUE='10UF',
 PACK_TYPE='0603LF',
 PART_NUMBER='E15431-001',
 LOCATION='C4M4',
 ROOM='PVPP_KLM_VR',
 GROUP='PWR_MLCC_CAP',
 CDS_LIB='mstr_discrete',
 CDS_PART_NAME='CAP_0603LF-10UF,4V,20%,X6S,E15A',
 VOLTAGE='4V',
 PRIM_FILE='./archive_libs/mstr_discrete/cap/chips/chips.prt';

PART_NAME
 C4M5 'CAP_A_0603V-47UF,4V,20%,X5R,60A':
 GROUP='PWR_MLCC_CAP';

SECTION_NUMBER 1
 '@BASEBOARD_FAB2_LIB.BASEBOARD_FAB2(SCH_1):PAGE220_I196@DEV_DISCRETE.CAP_A(CHIPS)':
 C_PATH='@baseboard_fab2_lib.baseboard_fab2(sch_1):page220_i196@dev_discrete.cap~
_a(chips)',
 P_PATH='@baseboard_fab2_lib.baseboard_fab2(sch_1):page220_i196@dev_discrete.cap~
_a(chips)',
 PATH='I196',
 DRAWING='@BASEBOARD_FAB2_LIB.BASEBOARD_FAB2(SCH_1):PAGE220',
 BOM_SS='078.1061T.M001',
 TOLERANCE='20%',
 SEC_TYPE='0603V',
 MATERIAL='X5R',
 PHYS_PAGE='220',
 XY='(3775,1675)',
 ROT='0',
 VER='1',
 VALUE='47UF',
 PACK_TYPE='0603V',
 PART_NUMBER='602433-106',
 LOCATION='C4M5',
 GROUP='PWR_MLCC_CAP',
 SEC='1',
 CDS_LIB='dev_discrete',
 CDS_PART_NAME='CAP_A_0603V-47UF,4V,20%,X5R,60A',
 VOLTAGE='4V',
 PRIM_FILE='./archive_libs/discrete/cap_a/chips/chips.prt';

PART_NAME
 C4M6 'CAPP_3018-68UF,16V,20%,TANT,72A':;

SECTION_NUMBER 1
 '@BASEBOARD_FAB2_LIB.BASEBOARD_FAB2(SCH_1):PAGE195_I102@MSTR_DISCRETE.CAPP(CHIPS)':
 C_PATH='@baseboard_fab2_lib.baseboard_fab2(sch_1):page195_i102@mstr_discrete.ca~
pp(chips)',
 P_PATH='@baseboard_fab2_lib.baseboard_fab2(sch_1):page195_i102@mstr_discrete.ca~
pp(chips)',
 PATH='I102',
 DRAWING='@BASEBOARD_FAB2_LIB.BASEBOARD_FAB2(SCH_1):PAGE195',
 TOLERANCE='20%',
 SEC_TYPE='3018',
 MATERIAL='TANT',
 PHYS_PAGE='195',
 XY='(-4875,775)',
 ROT='0',
 VER='1',
 VALUE='68UF',
 PACK_TYPE='3018',
 PART_NUMBER='724613-112',
 LOCATION='C4M6',
 SEC='1',
 CDS_LIB='mstr_discrete',
 CDS_PART_NAME='CAPP_3018-68UF,16V,20%,TANT,72A',
 VOLTAGE='16V',
 PRIM_FILE='./archive_libs/mstr_discrete/capp/chips/chips.prt';

PART_NAME
 C4M7 'CAPP_3018-68UF,16V,20%,TANT,72A':;

SECTION_NUMBER 1
 '@BASEBOARD_FAB2_LIB.BASEBOARD_FAB2(SCH_1):PAGE195_I105@MSTR_DISCRETE.CAPP(CHIPS)':
 C_PATH='@baseboard_fab2_lib.baseboard_fab2(sch_1):page195_i105@mstr_discrete.ca~
pp(chips)',
 P_PATH='@baseboard_fab2_lib.baseboard_fab2(sch_1):page195_i105@mstr_discrete.ca~
pp(chips)',
 PATH='I105',
 DRAWING='@BASEBOARD_FAB2_LIB.BASEBOARD_FAB2(SCH_1):PAGE195',
 TOLERANCE='20%',
 SEC_TYPE='3018',
 MATERIAL='TANT',
 PHYS_PAGE='195',
 XY='(-4850,1950)',
 ROT='0',
 VER='1',
 VALUE='68UF',
 PACK_TYPE='3018',
 PART_NUMBER='724613-112',
 LOCATION='C4M7',
 SEC='1',
 CDS_LIB='mstr_discrete',
 CDS_PART_NAME='CAPP_3018-68UF,16V,20%,TANT,72A',
 VOLTAGE='16V',
 PRIM_FILE='./archive_libs/mstr_discrete/capp/chips/chips.prt';

PART_NAME
 C4P1 'CAP_0805-47UF,4V,20%,X6S,C9533A':
 GROUP='PWR_MLCC_CAP',
 ROOM='PVCCIN_CPU0_DECAP_VR';

SECTION_NUMBER 1
 '@BASEBOARD_FAB2_LIB.BASEBOARD_FAB2(SCH_1):PAGE42_I10@MSTR_DISCRETE.CAP(CHIPS)':
 C_PATH='@baseboard_fab2_lib.baseboard_fab2(sch_1):page42_i10@mstr_discrete.cap(~
chips)',
 P_PATH='@baseboard_fab2_lib.baseboard_fab2(sch_1):page42_i10@mstr_discrete.cap(~
chips)',
 PATH='I10',
 DRAWING='@BASEBOARD_FAB2_LIB.BASEBOARD_FAB2(SCH_1):PAGE42',
 TOLERANCE='20%',
 MATERIAL='X6S',
 BOM_COST='PROC_SOCKET',
 PHYS_PAGE='42',
 XY='(-2550,950)',
 ROT='0',
 VER='1',
 VALUE='47UF',
 PACK_TYPE='0805',
 PART_NUMBER='C95333-006',
 LOCATION='C4P1',
 ROOM='PVCCIN_CPU0_DECAP_VR',
 GROUP='PWR_MLCC_CAP',
 CDS_LIB='mstr_discrete',
 CDS_PART_NAME='CAP_0805-47UF,4V,20%,X6S,C9533A',
 VOLTAGE='4V',
 PRIM_FILE='./archive_libs/mstr_discrete/cap/chips/chips.prt';

PART_NAME
 C4P2 'CAP_0805-100UF,4V,20%,X5R,6024A':
 GROUP='PWR_MCP_CAP',
 ROOM='VDDQ_ABC_PWR_VR';

SECTION_NUMBER 1
 '@BASEBOARD_FAB2_LIB.BASEBOARD_FAB2(SCH_1):PAGE42_I230@MSTR_DISCRETE.CAP(CHIPS)':
 C_PATH='@baseboard_fab2_lib.baseboard_fab2(sch_1):page42_i230@mstr_discrete.cap~
(chips)',
 P_PATH='@baseboard_fab2_lib.baseboard_fab2(sch_1):page42_i230@mstr_discrete.cap~
(chips)',
 PATH='I230',
 DRAWING='@BASEBOARD_FAB2_LIB.BASEBOARD_FAB2(SCH_1):PAGE42',
 NEW_PN='078.1071T.M002',
 NEW_MATERIAL='X6S',
 TOLERANCE='20%',
 SEC_TYPE='0805',
 MATERIAL='X5R',
 BOM_COST='MEM_VRD_PVDDQ_CD',
 PHYS_PAGE='42',
 XY='(-2000,2225)',
 ROT='0',
 VER='1',
 VALUE='100UF',
 PACK_TYPE='0805',
 PART_NUMBER='602433-112',
 LOCATION='C4P2',
 ROOM='VDDQ_ABC_PWR_VR',
 GROUP='PWR_MCP_CAP',
 SEC='1',
 CDS_LIB='mstr_discrete',
 CDS_PART_NAME='CAP_0805-100UF,4V,20%,X5R,6024A',
 VOLTAGE='4V',
 PRIM_FILE='./archive_libs/mstr_discrete/cap/chips/chips.prt';

PART_NAME
 C4P3 'CAP_0805-100UF,4V,20%,X5R,6024A':
 GROUP='PWR_MCP_CAP',
 ROOM='VDDQ_ABC_PWR_VR';

SECTION_NUMBER 1
 '@BASEBOARD_FAB2_LIB.BASEBOARD_FAB2(SCH_1):PAGE42_I225@MSTR_DISCRETE.CAP(CHIPS)':
 C_PATH='@baseboard_fab2_lib.baseboard_fab2(sch_1):page42_i225@mstr_discrete.cap~
(chips)',
 P_PATH='@baseboard_fab2_lib.baseboard_fab2(sch_1):page42_i225@mstr_discrete.cap~
(chips)',
 PATH='I225',
 DRAWING='@BASEBOARD_FAB2_LIB.BASEBOARD_FAB2(SCH_1):PAGE42',
 NEW_PN='078.1071T.M002',
 NEW_MATERIAL='X6S',
 TOLERANCE='20%',
 SEC_TYPE='0805',
 MATERIAL='X5R',
 BOM_COST='MEM_VRD_PVDDQ_CD',
 PHYS_PAGE='42',
 XY='(-3500,2225)',
 ROT='0',
 VER='1',
 VALUE='100UF',
 PACK_TYPE='0805',
 PART_NUMBER='602433-112',
 LOCATION='C4P3',
 ROOM='VDDQ_ABC_PWR_VR',
 GROUP='PWR_MCP_CAP',
 SEC='1',
 CDS_LIB='mstr_discrete',
 CDS_PART_NAME='CAP_0805-100UF,4V,20%,X5R,6024A',
 VOLTAGE='4V',
 PRIM_FILE='./archive_libs/mstr_discrete/cap/chips/chips.prt';

PART_NAME
 C4P4 'CAP_0805-100UF,4V,20%,X5R,6024A':
 GROUP='PWR_MCP_CAP',
 ROOM='VDDQ_ABC_PWR_VR';

SECTION_NUMBER 1
 '@BASEBOARD_FAB2_LIB.BASEBOARD_FAB2(SCH_1):PAGE42_I223@MSTR_DISCRETE.CAP(CHIPS)':
 C_PATH='@baseboard_fab2_lib.baseboard_fab2(sch_1):page42_i223@mstr_discrete.cap~
(chips)',
 P_PATH='@baseboard_fab2_lib.baseboard_fab2(sch_1):page42_i223@mstr_discrete.cap~
(chips)',
 PATH='I223',
 DRAWING='@BASEBOARD_FAB2_LIB.BASEBOARD_FAB2(SCH_1):PAGE42',
 NEW_PN='078.1071T.M002',
 NEW_MATERIAL='X6S',
 TOLERANCE='20%',
 SEC_TYPE='0805',
 MATERIAL='X5R',
 BOM_COST='MEM_VRD_PVDDQ_CD',
 PHYS_PAGE='42',
 XY='(-4250,2225)',
 ROT='0',
 VER='1',
 VALUE='100UF',
 PACK_TYPE='0805',
 PART_NUMBER='602433-112',
 LOCATION='C4P4',
 ROOM='VDDQ_ABC_PWR_VR',
 GROUP='PWR_MCP_CAP',
 SEC='1',
 CDS_LIB='mstr_discrete',
 CDS_PART_NAME='CAP_0805-100UF,4V,20%,X5R,6024A',
 VOLTAGE='4V',
 PRIM_FILE='./archive_libs/mstr_discrete/cap/chips/chips.prt';

PART_NAME
 C4P5 'CAP_0805-100UF,4V,20%,X5R,6024A':
 GROUP='PWR_MCP_CAP',
 ROOM='VDDQ_ABC_PWR_VR';

SECTION_NUMBER 1
 '@BASEBOARD_FAB2_LIB.BASEBOARD_FAB2(SCH_1):PAGE42_I233@MSTR_DISCRETE.CAP(CHIPS)':
 C_PATH='@baseboard_fab2_lib.baseboard_fab2(sch_1):page42_i233@mstr_discrete.cap~
(chips)',
 P_PATH='@baseboard_fab2_lib.baseboard_fab2(sch_1):page42_i233@mstr_discrete.cap~
(chips)',
 PATH='I233',
 DRAWING='@BASEBOARD_FAB2_LIB.BASEBOARD_FAB2(SCH_1):PAGE42',
 NEW_PN='078.1071T.M002',
 NEW_MATERIAL='X6S',
 TOLERANCE='20%',
 SEC_TYPE='0805',
 MATERIAL='X5R',
 BOM_COST='MEM_VRD_PVDDQ_CD',
 PHYS_PAGE='42',
 XY='(-1750,2225)',
 ROT='0',
 VER='1',
 VALUE='100UF',
 PACK_TYPE='0805',
 PART_NUMBER='602433-112',
 LOCATION='C4P5',
 ROOM='VDDQ_ABC_PWR_VR',
 GROUP='PWR_MCP_CAP',
 SEC='1',
 CDS_LIB='mstr_discrete',
 CDS_PART_NAME='CAP_0805-100UF,4V,20%,X5R,6024A',
 VOLTAGE='4V',
 PRIM_FILE='./archive_libs/mstr_discrete/cap/chips/chips.prt';

PART_NAME
 C4P6 'CAP_A_0603V-22.0UF,4V,20%,X6S,A':
 GROUP='PWR_MLCC_CAP',
 ROOM='PVCCIN_CPU0_DECAP_VR';

SECTION_NUMBER 1
 '@BASEBOARD_FAB2_LIB.BASEBOARD_FAB2(SCH_1):PAGE42_I164@DEV_DISCRETE.CAP_A(CHIPS)':
 C_PATH='@baseboard_fab2_lib.baseboard_fab2(sch_1):page42_i164@dev_discrete.cap_~
a(chips)',
 P_PATH='@baseboard_fab2_lib.baseboard_fab2(sch_1):page42_i164@dev_discrete.cap_~
a(chips)',
 PATH='I164',
 DRAWING='@BASEBOARD_FAB2_LIB.BASEBOARD_FAB2(SCH_1):PAGE42',
 TOLERANCE='20%',
 MATERIAL='X6S',
 PHYS_PAGE='42',
 XY='(-2250,950)',
 ROT='0',
 VER='1',
 VALUE='22.0UF',
 PACK_TYPE='0603V',
 PART_NUMBER='E15431-004',
 LOCATION='C4P6',
 ROOM='PVCCIN_CPU0_DECAP_VR',
 GROUP='PWR_MLCC_CAP',
 CDS_LIB='dev_discrete',
 CDS_PART_NAME='CAP_A_0603V-22.0UF,4V,20%,X6S,A',
 VOLTAGE='4V',
 PRIM_FILE='./archive_libs/discrete/cap_a/chips/chips.prt';

PART_NAME
 C4P7 'CAP_0805-100UF,4V,20%,X5R,6024A':
 GROUP='PWR_MCP_CAP',
 ROOM='VDDQ_ABC_PWR_VR';

SECTION_NUMBER 1
 '@BASEBOARD_FAB2_LIB.BASEBOARD_FAB2(SCH_1):PAGE42_I224@MSTR_DISCRETE.CAP(CHIPS)':
 C_PATH='@baseboard_fab2_lib.baseboard_fab2(sch_1):page42_i224@mstr_discrete.cap~
(chips)',
 P_PATH='@baseboard_fab2_lib.baseboard_fab2(sch_1):page42_i224@mstr_discrete.cap~
(chips)',
 PATH='I224',
 DRAWING='@BASEBOARD_FAB2_LIB.BASEBOARD_FAB2(SCH_1):PAGE42',
 NEW_PN='078.1071T.M002',
 NEW_MATERIAL='X6S',
 TOLERANCE='20%',
 SEC_TYPE='0805',
 MATERIAL='X5R',
 BOM_COST='MEM_VRD_PVDDQ_CD',
 PHYS_PAGE='42',
 XY='(-3750,2225)',
 ROT='0',
 VER='1',
 VALUE='100UF',
 PACK_TYPE='0805',
 PART_NUMBER='602433-112',
 LOCATION='C4P7',
 ROOM='VDDQ_ABC_PWR_VR',
 GROUP='PWR_MCP_CAP',
 SEC='1',
 CDS_LIB='mstr_discrete',
 CDS_PART_NAME='CAP_0805-100UF,4V,20%,X5R,6024A',
 VOLTAGE='4V',
 PRIM_FILE='./archive_libs/mstr_discrete/cap/chips/chips.prt';

PART_NAME
 C4P8 'CAP_A_0603V-22.0UF,4V,20%,X6S,A':
 GROUP='PWR_MLCC_CAP',
 ROOM='PVCCIN_CPU0_DECAP_VR';

SECTION_NUMBER 1
 '@BASEBOARD_FAB2_LIB.BASEBOARD_FAB2(SCH_1):PAGE42_I178@DEV_DISCRETE.CAP_A(CHIPS)':
 C_PATH='@baseboard_fab2_lib.baseboard_fab2(sch_1):page42_i178@dev_discrete.cap_~
a(chips)',
 P_PATH='@baseboard_fab2_lib.baseboard_fab2(sch_1):page42_i178@dev_discrete.cap_~
a(chips)',
 PATH='I178',
 DRAWING='@BASEBOARD_FAB2_LIB.BASEBOARD_FAB2(SCH_1):PAGE42',
 TOLERANCE='20%',
 MATERIAL='X6S',
 PHYS_PAGE='42',
 XY='(-1950,950)',
 ROT='0',
 VER='1',
 VALUE='22.0UF',
 PACK_TYPE='0603V',
 PART_NUMBER='E15431-004',
 LOCATION='C4P8',
 ROOM='PVCCIN_CPU0_DECAP_VR',
 GROUP='PWR_MLCC_CAP',
 CDS_LIB='dev_discrete',
 CDS_PART_NAME='CAP_A_0603V-22.0UF,4V,20%,X6S,A',
 VOLTAGE='4V',
 PRIM_FILE='./archive_libs/discrete/cap_a/chips/chips.prt';

PART_NAME
 C4P9 'CAP_0805-47UF,4V,20%,X6S,C9533A':
 GROUP='PWR_MLCC_CAP',
 ROOM='PVCCIN_CPU0_DECAP_VR';

SECTION_NUMBER 1
 '@BASEBOARD_FAB2_LIB.BASEBOARD_FAB2(SCH_1):PAGE42_I12@MSTR_DISCRETE.CAP(CHIPS)':
 C_PATH='@baseboard_fab2_lib.baseboard_fab2(sch_1):page42_i12@mstr_discrete.cap(~
chips)',
 P_PATH='@baseboard_fab2_lib.baseboard_fab2(sch_1):page42_i12@mstr_discrete.cap(~
chips)',
 PATH='I12',
 DRAWING='@BASEBOARD_FAB2_LIB.BASEBOARD_FAB2(SCH_1):PAGE42',
 TOLERANCE='20%',
 MATERIAL='X6S',
 BOM_COST='PROC_SOCKET',
 PHYS_PAGE='42',
 XY='(-2850,950)',
 ROT='0',
 VER='1',
 VALUE='47UF',
 PACK_TYPE='0805',
 PART_NUMBER='C95333-006',
 LOCATION='C4P9',
 ROOM='PVCCIN_CPU0_DECAP_VR',
 GROUP='PWR_MLCC_CAP',
 CDS_LIB='mstr_discrete',
 CDS_PART_NAME='CAP_0805-47UF,4V,20%,X6S,C9533A',
 VOLTAGE='4V',
 PRIM_FILE='./archive_libs/mstr_discrete/cap/chips/chips.prt';

PART_NAME
 C4P10 'CAP_0805-47UF,4V,20%,X6S,C9533A':
 GROUP='PWR_MLCC_CAP',
 ROOM='PVCCIN_CPU0_DECAP_VR';

SECTION_NUMBER 1
 '@BASEBOARD_FAB2_LIB.BASEBOARD_FAB2(SCH_1):PAGE42_I17@MSTR_DISCRETE.CAP(CHIPS)':
 C_PATH='@baseboard_fab2_lib.baseboard_fab2(sch_1):page42_i17@mstr_discrete.cap(~
chips)',
 P_PATH='@baseboard_fab2_lib.baseboard_fab2(sch_1):page42_i17@mstr_discrete.cap(~
chips)',
 PATH='I17',
 DRAWING='@BASEBOARD_FAB2_LIB.BASEBOARD_FAB2(SCH_1):PAGE42',
 TOLERANCE='20%',
 MATERIAL='X6S',
 BOM_COST='PROC_SOCKET',
 PHYS_PAGE='42',
 XY='(-3200,950)',
 ROT='0',
 VER='1',
 VALUE='47UF',
 PACK_TYPE='0805',
 PART_NUMBER='C95333-006',
 LOCATION='C4P10',
 ROOM='PVCCIN_CPU0_DECAP_VR',
 GROUP='PWR_MLCC_CAP',
 CDS_LIB='mstr_discrete',
 CDS_PART_NAME='CAP_0805-47UF,4V,20%,X6S,C9533A',
 VOLTAGE='4V',
 PRIM_FILE='./archive_libs/mstr_discrete/cap/chips/chips.prt';

PART_NAME
 C4R1 'CAPP_3018-470UF,2.5V,20%,ALUM,A':
 GROUP='PWR_MCP_CAP',
 ROOM='PVMCP_MCP_CPU0_VR';

SECTION_NUMBER 1
 '@BASEBOARD_FAB2_LIB.BASEBOARD_FAB2(SCH_1):PAGE194_I29@MSTR_DISCRETE.CAPP(CHIPS)':
 C_PATH='@baseboard_fab2_lib.baseboard_fab2(sch_1):page194_i29@mstr_discrete.cap~
p(chips)',
 P_PATH='@baseboard_fab2_lib.baseboard_fab2(sch_1):page194_i29@mstr_discrete.cap~
p(chips)',
 PATH='I29',
 DRAWING='@BASEBOARD_FAB2_LIB.BASEBOARD_FAB2(SCH_1):PAGE194',
 TOLERANCE='20%',
 SEC_TYPE='3018',
 MATERIAL='ALUM',
 BOM_COST='PVMCP_MCP_CPU0_VR',
 PHYS_PAGE='194',
 XY='(-1600,2500)',
 ROT='0',
 VER='1',
 VALUE='470UF',
 PACK_TYPE='3018',
 PART_NUMBER='699013-049',
 LOCATION='C4R1',
 ROOM='PVMCP_MCP_CPU0_VR',
 GROUP='PWR_MCP_CAP',
 SEC='1',
 CDS_LIB='mstr_discrete',
 CDS_PART_NAME='CAPP_3018-470UF,2.5V,20%,ALUM,A',
 VOLTAGE='2.5V',
 PRIM_FILE='./archive_libs/mstr_discrete/capp/chips/chips.prt';

PART_NAME
 C4R2 'CAP_A_0402V-0.1UF,16V,10%,X7R,A':
 ROOM='DEBUG';

SECTION_NUMBER 1
 '@BASEBOARD_FAB2_LIB.BASEBOARD_FAB2(SCH_1):PAGE113_I246@DEV_DISCRETE.CAP_A(CHIPS)':
 C_PATH='@baseboard_fab2_lib.baseboard_fab2(sch_1):page113_i246@dev_discrete.cap~
_a(chips)',
 P_PATH='@baseboard_fab2_lib.baseboard_fab2(sch_1):page113_i246@dev_discrete.cap~
_a(chips)',
 PATH='I246',
 DRAWING='@BASEBOARD_FAB2_LIB.BASEBOARD_FAB2(SCH_1):PAGE113',
 POP='NOPOP',
 TOLERANCE='10%',
 SEC_TYPE='0402V',
 MATERIAL='X7R',
 PHYS_PAGE='113',
 XY='(2125,3200)',
 ROT='2',
 VER='1',
 VALUE='0.1UF',
 PACK_TYPE='0402V',
 PART_NUMBER='A36096-030',
 LOCATION='C4R2',
 ROOM='DEBUG',
 SEC='1',
 CDS_LIB='dev_discrete',
 CDS_PART_NAME='CAP_A_0402V-0.1UF,16V,10%,X7R,A',
 VOLTAGE='16V',
 PRIM_FILE='./archive_libs/discrete/cap_a/chips/chips.prt';

PART_NAME
 C4T1 'CAP_A_0402V-1.0UF,6.3V,10%,X6SA':
 GROUP='PWR_MCP_CAP',
 ROOM='P1V8_MCP_CPU0';

SECTION_NUMBER 1
 '@BASEBOARD_FAB2_LIB.BASEBOARD_FAB2(SCH_1):PAGE194_I16@DEV_DISCRETE.CAP_A(CHIPS)':
 C_PATH='@baseboard_fab2_lib.baseboard_fab2(sch_1):page194_i16@dev_discrete.cap_~
a(chips)',
 P_PATH='@baseboard_fab2_lib.baseboard_fab2(sch_1):page194_i16@dev_discrete.cap_~
a(chips)',
 PATH='I16',
 DRAWING='@BASEBOARD_FAB2_LIB.BASEBOARD_FAB2(SCH_1):PAGE194',
 TOLERANCE='10%',
 SEC_TYPE='0402V',
 MATERIAL='X6S',
 PHYS_PAGE='194',
 XY='(-1300,1850)',
 ROT='0',
 VER='1',
 VALUE='1.0UF',
 PACK_TYPE='0402V',
 PART_NUMBER='D97712-004',
 LOCATION='C4T1',
 ROOM='P1V8_MCP_CPU0',
 GROUP='PWR_MCP_CAP',
 SEC='1',
 CDS_LIB='dev_discrete',
 CDS_PART_NAME='CAP_A_0402V-1.0UF,6.3V,10%,X6SA',
 VOLTAGE='6.3V',
 PRIM_FILE='./archive_libs/discrete/cap_a/chips/chips.prt';

PART_NAME
 C4T2 'CAP_A_0402V-1.0UF,6.3V,10%,X6SA':
 GROUP='PWR_MCP_CAP',
 ROOM='P1V8_MCP_CPU0';

SECTION_NUMBER 1
 '@BASEBOARD_FAB2_LIB.BASEBOARD_FAB2(SCH_1):PAGE194_I9@DEV_DISCRETE.CAP_A(CHIPS)':
 C_PATH='@baseboard_fab2_lib.baseboard_fab2(sch_1):page194_i9@dev_discrete.cap_a~
(chips)',
 P_PATH='@baseboard_fab2_lib.baseboard_fab2(sch_1):page194_i9@dev_discrete.cap_a~
(chips)',
 PATH='I9',
 DRAWING='@BASEBOARD_FAB2_LIB.BASEBOARD_FAB2(SCH_1):PAGE194',
 TOLERANCE='10%',
 SEC_TYPE='0402V',
 MATERIAL='X6S',
 PHYS_PAGE='194',
 XY='(-1000,1850)',
 ROT='0',
 VER='1',
 VALUE='1.0UF',
 PACK_TYPE='0402V',
 PART_NUMBER='D97712-004',
 LOCATION='C4T2',
 ROOM='P1V8_MCP_CPU0',
 GROUP='PWR_MCP_CAP',
 SEC='1',
 CDS_LIB='dev_discrete',
 CDS_PART_NAME='CAP_A_0402V-1.0UF,6.3V,10%,X6SA',
 VOLTAGE='6.3V',
 PRIM_FILE='./archive_libs/discrete/cap_a/chips/chips.prt';

PART_NAME
 C4T3 'CAPP_7343-220UF,4V,20%,POSCAP,A':
 GROUP='PWR_BULK_CAP';

SECTION_NUMBER 1
 '@BASEBOARD_FAB2_LIB.BASEBOARD_FAB2(SCH_1):PAGE231_I217@MSTR_DISCRETE.CAPP(CHIPS)':
 C_PATH='@baseboard_fab2_lib.baseboard_fab2(sch_1):page231_i217@mstr_discrete.ca~
pp(chips)',
 P_PATH='@baseboard_fab2_lib.baseboard_fab2(sch_1):page231_i217@mstr_discrete.ca~
pp(chips)',
 PATH='I217',
 DRAWING='@BASEBOARD_FAB2_LIB.BASEBOARD_FAB2(SCH_1):PAGE231',
 TOLERANCE='20%',
 SEC_TYPE='7343',
 MATERIAL='POSCAP',
 PHYS_PAGE='231',
 XY='(-1100,3900)',
 ROT='0',
 VER='1',
 VALUE='220UF',
 PACK_TYPE='7343',
 PART_NUMBER='724613-067',
 LOCATION='C4T3',
 GROUP='PWR_BULK_CAP',
 SEC='1',
 CDS_LIB='mstr_discrete',
 CDS_PART_NAME='CAPP_7343-220UF,4V,20%,POSCAP,A',
 VOLTAGE='4V',
 PRIM_FILE='./archive_libs/mstr_discrete/capp/chips/chips.prt';

PART_NAME
 C4T4 'CAP_0805-100UF,4V,20%,X5R,6024A':
 GROUP='PWR_MLCC_CAP',
 ROOM='VDDQ_ABC_PWR_VR';

SECTION_NUMBER 1
 '@BASEBOARD_FAB2_LIB.BASEBOARD_FAB2(SCH_1):PAGE217_I319@MSTR_DISCRETE.CAP(CHIPS)':
 C_PATH='@baseboard_fab2_lib.baseboard_fab2(sch_1):page217_i319@mstr_discrete.ca~
p(chips)',
 P_PATH='@baseboard_fab2_lib.baseboard_fab2(sch_1):page217_i319@mstr_discrete.ca~
p(chips)',
 PATH='I319',
 DRAWING='@BASEBOARD_FAB2_LIB.BASEBOARD_FAB2(SCH_1):PAGE217',
 NEW_PN='078.1071T.M002',
 NEW_MATERIAL='X6S',
 BOM_SS='NOPOP',
 TOLERANCE='20%',
 SEC_TYPE='0805',
 MATERIAL='X5R',
 BOM_COST='MEM_VRD_PVDDQ_CD',
 PHYS_PAGE='217',
 XY='(3625,2850)',
 ROT='0',
 VER='1',
 VALUE='100UF',
 PACK_TYPE='0805',
 PART_NUMBER='602433-112',
 LOCATION='C4T4',
 ROOM='VDDQ_ABC_PWR_VR',
 GROUP='PWR_MLCC_CAP',
 SEC='1',
 CDS_LIB='mstr_discrete',
 CDS_PART_NAME='CAP_0805-100UF,4V,20%,X5R,6024A',
 VOLTAGE='4V',
 PRIM_FILE='./archive_libs/mstr_discrete/cap/chips/chips.prt';

PART_NAME
 C4T5 'CAP_0603LF-10UF,4V,20%,X6S,E15A':
 GROUP='PWR_MLCC_CAP',
 ROOM='PVPP_KLM_VR';

SECTION_NUMBER 1
 '@BASEBOARD_FAB2_LIB.BASEBOARD_FAB2(SCH_1):PAGE231_I125@MSTR_DISCRETE.CAP(CHIPS)':
 C_PATH='@baseboard_fab2_lib.baseboard_fab2(sch_1):page231_i125@mstr_discrete.ca~
p(chips)',
 P_PATH='@baseboard_fab2_lib.baseboard_fab2(sch_1):page231_i125@mstr_discrete.ca~
p(chips)',
 PATH='I125',
 DRAWING='@BASEBOARD_FAB2_LIB.BASEBOARD_FAB2(SCH_1):PAGE231',
 TOLERANCE='20%',
 MATERIAL='X6S',
 BOM_COST='MEM_VRD_PVPP_AB',
 PHYS_PAGE='231',
 XY='(-7350,1000)',
 ROT='0',
 VER='1',
 VALUE='10UF',
 PACK_TYPE='0603LF',
 PART_NUMBER='E15431-001',
 LOCATION='C4T5',
 ROOM='PVPP_KLM_VR',
 GROUP='PWR_MLCC_CAP',
 CDS_LIB='mstr_discrete',
 CDS_PART_NAME='CAP_0603LF-10UF,4V,20%,X6S,E15A',
 VOLTAGE='4V',
 PRIM_FILE='./archive_libs/mstr_discrete/cap/chips/chips.prt';

PART_NAME
 C4T6 'CAP_0603LF-10UF,4V,20%,X6S,E15A':
 GROUP='PWR_MLCC_CAP',
 ROOM='PVPP_KLM_VR';

SECTION_NUMBER 1
 '@BASEBOARD_FAB2_LIB.BASEBOARD_FAB2(SCH_1):PAGE231_I124@MSTR_DISCRETE.CAP(CHIPS)':
 C_PATH='@baseboard_fab2_lib.baseboard_fab2(sch_1):page231_i124@mstr_discrete.ca~
p(chips)',
 P_PATH='@baseboard_fab2_lib.baseboard_fab2(sch_1):page231_i124@mstr_discrete.ca~
p(chips)',
 PATH='I124',
 DRAWING='@BASEBOARD_FAB2_LIB.BASEBOARD_FAB2(SCH_1):PAGE231',
 TOLERANCE='20%',
 MATERIAL='X6S',
 BOM_COST='MEM_VRD_PVPP_AB',
 PHYS_PAGE='231',
 XY='(-7625,1000)',
 ROT='0',
 VER='1',
 VALUE='10UF',
 PACK_TYPE='0603LF',
 PART_NUMBER='E15431-001',
 LOCATION='C4T6',
 ROOM='PVPP_KLM_VR',
 GROUP='PWR_MLCC_CAP',
 CDS_LIB='mstr_discrete',
 CDS_PART_NAME='CAP_0603LF-10UF,4V,20%,X6S,E15A',
 VOLTAGE='4V',
 PRIM_FILE='./archive_libs/mstr_discrete/cap/chips/chips.prt';

PART_NAME
 C4U1 'CAP_0603LF-10UF,4V,20%,X6S,E15A':
 GROUP='PWR_MLCC_CAP',
 ROOM='PVPP_KLM_VR';

SECTION_NUMBER 1
 '@BASEBOARD_FAB2_LIB.BASEBOARD_FAB2(SCH_1):PAGE231_I130@MSTR_DISCRETE.CAP(CHIPS)':
 C_PATH='@baseboard_fab2_lib.baseboard_fab2(sch_1):page231_i130@mstr_discrete.ca~
p(chips)',
 P_PATH='@baseboard_fab2_lib.baseboard_fab2(sch_1):page231_i130@mstr_discrete.ca~
p(chips)',
 PATH='I130',
 DRAWING='@BASEBOARD_FAB2_LIB.BASEBOARD_FAB2(SCH_1):PAGE231',
 TOLERANCE='20%',
 MATERIAL='X6S',
 BOM_COST='MEM_VRD_PVPP_AB',
 PHYS_PAGE='231',
 XY='(-6225,1000)',
 ROT='0',
 VER='1',
 VALUE='10UF',
 PACK_TYPE='0603LF',
 PART_NUMBER='E15431-001',
 LOCATION='C4U1',
 ROOM='PVPP_KLM_VR',
 GROUP='PWR_MLCC_CAP',
 CDS_LIB='mstr_discrete',
 CDS_PART_NAME='CAP_0603LF-10UF,4V,20%,X6S,E15A',
 VOLTAGE='4V',
 PRIM_FILE='./archive_libs/mstr_discrete/cap/chips/chips.prt';

PART_NAME
 C4U2 'CAP_0603LF-10UF,4V,20%,X6S,E15A':
 GROUP='PWR_MLCC_CAP',
 ROOM='PVPP_KLM_VR';

SECTION_NUMBER 1
 '@BASEBOARD_FAB2_LIB.BASEBOARD_FAB2(SCH_1):PAGE231_I129@MSTR_DISCRETE.CAP(CHIPS)':
 C_PATH='@baseboard_fab2_lib.baseboard_fab2(sch_1):page231_i129@mstr_discrete.ca~
p(chips)',
 P_PATH='@baseboard_fab2_lib.baseboard_fab2(sch_1):page231_i129@mstr_discrete.ca~
p(chips)',
 PATH='I129',
 DRAWING='@BASEBOARD_FAB2_LIB.BASEBOARD_FAB2(SCH_1):PAGE231',
 TOLERANCE='20%',
 MATERIAL='X6S',
 BOM_COST='MEM_VRD_PVPP_AB',
 PHYS_PAGE='231',
 XY='(-6500,1000)',
 ROT='0',
 VER='1',
 VALUE='10UF',
 PACK_TYPE='0603LF',
 PART_NUMBER='E15431-001',
 LOCATION='C4U2',
 ROOM='PVPP_KLM_VR',
 GROUP='PWR_MLCC_CAP',
 CDS_LIB='mstr_discrete',
 CDS_PART_NAME='CAP_0603LF-10UF,4V,20%,X6S,E15A',
 VOLTAGE='4V',
 PRIM_FILE='./archive_libs/mstr_discrete/cap/chips/chips.prt';

PART_NAME
 C4U3 'CAP_0603LF-10UF,4V,20%,X6S,E15A':
 GROUP='PWR_MLCC_CAP',
 ROOM='PVPP_KLM_VR';

SECTION_NUMBER 1
 '@BASEBOARD_FAB2_LIB.BASEBOARD_FAB2(SCH_1):PAGE231_I148@MSTR_DISCRETE.CAP(CHIPS)':
 C_PATH='@baseboard_fab2_lib.baseboard_fab2(sch_1):page231_i148@mstr_discrete.ca~
p(chips)',
 P_PATH='@baseboard_fab2_lib.baseboard_fab2(sch_1):page231_i148@mstr_discrete.ca~
p(chips)',
 PATH='I148',
 DRAWING='@BASEBOARD_FAB2_LIB.BASEBOARD_FAB2(SCH_1):PAGE231',
 TOLERANCE='20%',
 MATERIAL='X6S',
 BOM_COST='MEM_VRD_PVPP_AB',
 PHYS_PAGE='231',
 XY='(-5075,975)',
 ROT='0',
 VER='1',
 VALUE='10UF',
 PACK_TYPE='0603LF',
 PART_NUMBER='E15431-001',
 LOCATION='C4U3',
 ROOM='PVPP_KLM_VR',
 GROUP='PWR_MLCC_CAP',
 CDS_LIB='mstr_discrete',
 CDS_PART_NAME='CAP_0603LF-10UF,4V,20%,X6S,E15A',
 VOLTAGE='4V',
 PRIM_FILE='./archive_libs/mstr_discrete/cap/chips/chips.prt';

PART_NAME
 C4U4 'CAP_0603LF-10UF,4V,20%,X6S,E15A':
 GROUP='PWR_MLCC_CAP',
 ROOM='PVPP_KLM_VR';

SECTION_NUMBER 1
 '@BASEBOARD_FAB2_LIB.BASEBOARD_FAB2(SCH_1):PAGE231_I146@MSTR_DISCRETE.CAP(CHIPS)':
 C_PATH='@baseboard_fab2_lib.baseboard_fab2(sch_1):page231_i146@mstr_discrete.ca~
p(chips)',
 P_PATH='@baseboard_fab2_lib.baseboard_fab2(sch_1):page231_i146@mstr_discrete.ca~
p(chips)',
 PATH='I146',
 DRAWING='@BASEBOARD_FAB2_LIB.BASEBOARD_FAB2(SCH_1):PAGE231',
 TOLERANCE='20%',
 MATERIAL='X6S',
 BOM_COST='MEM_VRD_PVPP_AB',
 PHYS_PAGE='231',
 XY='(-5350,975)',
 ROT='0',
 VER='1',
 VALUE='10UF',
 PACK_TYPE='0603LF',
 PART_NUMBER='E15431-001',
 LOCATION='C4U4',
 ROOM='PVPP_KLM_VR',
 GROUP='PWR_MLCC_CAP',
 CDS_LIB='mstr_discrete',
 CDS_PART_NAME='CAP_0603LF-10UF,4V,20%,X6S,E15A',
 VOLTAGE='4V',
 PRIM_FILE='./archive_libs/mstr_discrete/cap/chips/chips.prt';

PART_NAME
 C4W1 'CAP_0402LF-220PF,50V,10%,X7R,AA':
 ROOM='PVCCIN_CPU0_VR';

SECTION_NUMBER 1
 '@BASEBOARD_FAB2_LIB.BASEBOARD_FAB2(SCH_1):PAGE211_I97@MSTR_DISCRETE.CAP(CHIPS)':
 C_PATH='@baseboard_fab2_lib.baseboard_fab2(sch_1):page211_i97@mstr_discrete.cap~
(chips)',
 P_PATH='@baseboard_fab2_lib.baseboard_fab2(sch_1):page211_i97@mstr_discrete.cap~
(chips)',
 PATH='I97',
 DRAWING='@BASEBOARD_FAB2_LIB.BASEBOARD_FAB2(SCH_1):PAGE211',
 TOLERANCE='10%',
 SEC_TYPE='0402LF',
 MATERIAL='X7R',
 PHYS_PAGE='211',
 XY='(-2250,2750)',
 ROT='0',
 VER='1',
 VALUE='220PF',
 PACK_TYPE='0402LF',
 PART_NUMBER='A36096-050',
 LOCATION='C4W1',
 ROOM='PVCCIN_CPU0_VR',
 SEC='1',
 CDS_LIB='mstr_discrete',
 CDS_PART_NAME='CAP_0402LF-220PF,50V,10%,X7R,AA',
 VOLTAGE='50V',
 PRIM_FILE='./archive_libs/mstr_discrete/cap/chips/chips.prt';

PART_NAME
 C4W2 'CAP_0402LF-220PF,50V,10%,X7R,AA':
 ROOM='PVCCIN_CPU0_VR';

SECTION_NUMBER 1
 '@BASEBOARD_FAB2_LIB.BASEBOARD_FAB2(SCH_1):PAGE213_I101@MSTR_DISCRETE.CAP(CHIPS)':
 C_PATH='@baseboard_fab2_lib.baseboard_fab2(sch_1):page213_i101@mstr_discrete.ca~
p(chips)',
 P_PATH='@baseboard_fab2_lib.baseboard_fab2(sch_1):page213_i101@mstr_discrete.ca~
p(chips)',
 PATH='I101',
 DRAWING='@BASEBOARD_FAB2_LIB.BASEBOARD_FAB2(SCH_1):PAGE213',
 TOLERANCE='10%',
 SEC_TYPE='0402LF',
 MATERIAL='X7R',
 PHYS_PAGE='213',
 XY='(-2100,2750)',
 ROT='0',
 VER='1',
 VALUE='220PF',
 PACK_TYPE='0402LF',
 PART_NUMBER='A36096-050',
 LOCATION='C4W2',
 ROOM='PVCCIN_CPU0_VR',
 SEC='1',
 CDS_LIB='mstr_discrete',
 CDS_PART_NAME='CAP_0402LF-220PF,50V,10%,X7R,AA',
 VOLTAGE='50V',
 PRIM_FILE='./archive_libs/mstr_discrete/cap/chips/chips.prt';

PART_NAME
 C4W3 'CAP_0402LF-220PF,50V,10%,X7R,AA':
 ROOM='PVCCIN_CPU0_VR';

SECTION_NUMBER 1
 '@BASEBOARD_FAB2_LIB.BASEBOARD_FAB2(SCH_1):PAGE235_I244@MSTR_DISCRETE.CAP(CHIPS)':
 C_PATH='@baseboard_fab2_lib.baseboard_fab2(sch_1):page235_i244@mstr_discrete.ca~
p(chips)',
 P_PATH='@baseboard_fab2_lib.baseboard_fab2(sch_1):page235_i244@mstr_discrete.ca~
p(chips)',
 PATH='I244',
 DRAWING='@BASEBOARD_FAB2_LIB.BASEBOARD_FAB2(SCH_1):PAGE235',
 TOLERANCE='10%',
 SEC_TYPE='0402LF',
 MATERIAL='X7R',
 PHYS_PAGE='235',
 XY='(-12200,3700)',
 ROT='0',
 VER='1',
 VALUE='220PF',
 PACK_TYPE='0402LF',
 PART_NUMBER='A36096-050',
 LOCATION='C4W3',
 ROOM='PVCCIN_CPU0_VR',
 SEC='1',
 CDS_LIB='mstr_discrete',
 CDS_PART_NAME='CAP_0402LF-220PF,50V,10%,X7R,AA',
 VOLTAGE='50V',
 PRIM_FILE='./archive_libs/mstr_discrete/cap/chips/chips.prt';

PART_NAME
 C4W4 'CAP_0402LF-220PF,50V,10%,X7R,AA':
 ROOM='PVCCIN_CPU0_VR';

SECTION_NUMBER 1
 '@BASEBOARD_FAB2_LIB.BASEBOARD_FAB2(SCH_1):PAGE235_I246@MSTR_DISCRETE.CAP(CHIPS)':
 C_PATH='@baseboard_fab2_lib.baseboard_fab2(sch_1):page235_i246@mstr_discrete.ca~
p(chips)',
 P_PATH='@baseboard_fab2_lib.baseboard_fab2(sch_1):page235_i246@mstr_discrete.ca~
p(chips)',
 PATH='I246',
 DRAWING='@BASEBOARD_FAB2_LIB.BASEBOARD_FAB2(SCH_1):PAGE235',
 TOLERANCE='10%',
 SEC_TYPE='0402LF',
 MATERIAL='X7R',
 PHYS_PAGE='235',
 XY='(-10000,2350)',
 ROT='0',
 VER='1',
 VALUE='220PF',
 PACK_TYPE='0402LF',
 PART_NUMBER='A36096-050',
 LOCATION='C4W4',
 ROOM='PVCCIN_CPU0_VR',
 SEC='1',
 CDS_LIB='mstr_discrete',
 CDS_PART_NAME='CAP_0402LF-220PF,50V,10%,X7R,AA',
 VOLTAGE='50V',
 PRIM_FILE='./archive_libs/mstr_discrete/cap/chips/chips.prt';

PART_NAME
 C4W5 'CAP_0805-100UF,4V,20%,X5R,6024A':
 GROUP='PWR_MLCC_CAP',
 ROOM='VDDQ_ABC_PWR_VR';

SECTION_NUMBER 1
 '@BASEBOARD_FAB2_LIB.BASEBOARD_FAB2(SCH_1):PAGE222_I46@MSTR_DISCRETE.CAP(CHIPS)':
 C_PATH='@baseboard_fab2_lib.baseboard_fab2(sch_1):page222_i46@mstr_discrete.cap~
(chips)',
 P_PATH='@baseboard_fab2_lib.baseboard_fab2(sch_1):page222_i46@mstr_discrete.cap~
(chips)',
 PATH='I46',
 DRAWING='@BASEBOARD_FAB2_LIB.BASEBOARD_FAB2(SCH_1):PAGE222',
 NEW_PN='078.1071T.M002',
 NEW_MATERIAL='X6S',
 TOLERANCE='20%',
 SEC_TYPE='0805',
 MATERIAL='X5R',
 BOM_COST='MEM_VRD_PVDDQ_CD',
 PHYS_PAGE='222',
 XY='(4100,575)',
 ROT='0',
 VER='1',
 VALUE='100UF',
 PACK_TYPE='0805',
 PART_NUMBER='602433-112',
 LOCATION='C4W5',
 ROOM='VDDQ_ABC_PWR_VR',
 GROUP='PWR_MLCC_CAP',
 SEC='1',
 CDS_LIB='mstr_discrete',
 CDS_PART_NAME='CAP_0805-100UF,4V,20%,X5R,6024A',
 VOLTAGE='4V',
 PRIM_FILE='./archive_libs/mstr_discrete/cap/chips/chips.prt';

PART_NAME
 C5A1 'CAP_A_0603V-47UF,4V,20%,X5R,60A':
 GROUP='PWR_MLCC_CAP';

SECTION_NUMBER 1
 '@BASEBOARD_FAB2_LIB.BASEBOARD_FAB2(SCH_1):PAGE220_I262@DEV_DISCRETE.CAP_A(CHIPS)':
 C_PATH='@baseboard_fab2_lib.baseboard_fab2(sch_1):page220_i262@dev_discrete.cap~
_a(chips)',
 P_PATH='@baseboard_fab2_lib.baseboard_fab2(sch_1):page220_i262@dev_discrete.cap~
_a(chips)',
 PATH='I262',
 DRAWING='@BASEBOARD_FAB2_LIB.BASEBOARD_FAB2(SCH_1):PAGE220',
 BOM_SS='E15431-004',
 TOLERANCE='20%',
 SEC_TYPE='0603V',
 MATERIAL='X5R',
 PHYS_PAGE='220',
 XY='(-2150,100)',
 ROT='0',
 VER='1',
 VALUE='47UF',
 PACK_TYPE='0603V',
 PART_NUMBER='602433-106',
 LOCATION='C5A1',
 GROUP='PWR_MLCC_CAP',
 SEC='1',
 CDS_LIB='dev_discrete',
 CDS_PART_NAME='CAP_A_0603V-47UF,4V,20%,X5R,60A',
 VOLTAGE='4V',
 PRIM_FILE='./archive_libs/discrete/cap_a/chips/chips.prt';

PART_NAME
 C5A2 'CAP_A_0603V-47UF,4V,20%,X5R,60A':
 GROUP='PWR_MLCC_CAP';

SECTION_NUMBER 1
 '@BASEBOARD_FAB2_LIB.BASEBOARD_FAB2(SCH_1):PAGE220_I266@DEV_DISCRETE.CAP_A(CHIPS)':
 C_PATH='@baseboard_fab2_lib.baseboard_fab2(sch_1):page220_i266@dev_discrete.cap~
_a(chips)',
 P_PATH='@baseboard_fab2_lib.baseboard_fab2(sch_1):page220_i266@dev_discrete.cap~
_a(chips)',
 PATH='I266',
 DRAWING='@BASEBOARD_FAB2_LIB.BASEBOARD_FAB2(SCH_1):PAGE220',
 BOM_SS='E15431-004',
 TOLERANCE='20%',
 SEC_TYPE='0603V',
 MATERIAL='X5R',
 PHYS_PAGE='220',
 XY='(-1000,100)',
 ROT='0',
 VER='1',
 VALUE='47UF',
 PACK_TYPE='0603V',
 PART_NUMBER='602433-106',
 LOCATION='C5A2',
 GROUP='PWR_MLCC_CAP',
 SEC='1',
 CDS_LIB='dev_discrete',
 CDS_PART_NAME='CAP_A_0603V-47UF,4V,20%,X5R,60A',
 VOLTAGE='4V',
 PRIM_FILE='./archive_libs/discrete/cap_a/chips/chips.prt';

PART_NAME
 C5A3 'CAP_A_0603V-47UF,4V,20%,X5R,60A':
 GROUP='PWR_MLCC_CAP';

SECTION_NUMBER 1
 '@BASEBOARD_FAB2_LIB.BASEBOARD_FAB2(SCH_1):PAGE220_I270@DEV_DISCRETE.CAP_A(CHIPS)':
 C_PATH='@baseboard_fab2_lib.baseboard_fab2(sch_1):page220_i270@dev_discrete.cap~
_a(chips)',
 P_PATH='@baseboard_fab2_lib.baseboard_fab2(sch_1):page220_i270@dev_discrete.cap~
_a(chips)',
 PATH='I270',
 DRAWING='@BASEBOARD_FAB2_LIB.BASEBOARD_FAB2(SCH_1):PAGE220',
 BOM_SS='E15431-004',
 TOLERANCE='20%',
 SEC_TYPE='0603V',
 MATERIAL='X5R',
 PHYS_PAGE='220',
 XY='(200,100)',
 ROT='0',
 VER='1',
 VALUE='47UF',
 PACK_TYPE='0603V',
 PART_NUMBER='602433-106',
 LOCATION='C5A3',
 GROUP='PWR_MLCC_CAP',
 SEC='1',
 CDS_LIB='dev_discrete',
 CDS_PART_NAME='CAP_A_0603V-47UF,4V,20%,X5R,60A',
 VOLTAGE='4V',
 PRIM_FILE='./archive_libs/discrete/cap_a/chips/chips.prt';

PART_NAME
 C5A4 'CAP_A_0603V-47UF,4V,20%,X5R,60A':
 GROUP='PWR_MLCC_CAP';

SECTION_NUMBER 1
 '@BASEBOARD_FAB2_LIB.BASEBOARD_FAB2(SCH_1):PAGE220_I274@DEV_DISCRETE.CAP_A(CHIPS)':
 C_PATH='@baseboard_fab2_lib.baseboard_fab2(sch_1):page220_i274@dev_discrete.cap~
_a(chips)',
 P_PATH='@baseboard_fab2_lib.baseboard_fab2(sch_1):page220_i274@dev_discrete.cap~
_a(chips)',
 PATH='I274',
 DRAWING='@BASEBOARD_FAB2_LIB.BASEBOARD_FAB2(SCH_1):PAGE220',
 BOM_SS='E15431-004',
 TOLERANCE='20%',
 SEC_TYPE='0603V',
 MATERIAL='X5R',
 PHYS_PAGE='220',
 XY='(1350,100)',
 ROT='0',
 VER='1',
 VALUE='47UF',
 PACK_TYPE='0603V',
 PART_NUMBER='602433-106',
 LOCATION='C5A4',
 GROUP='PWR_MLCC_CAP',
 SEC='1',
 CDS_LIB='dev_discrete',
 CDS_PART_NAME='CAP_A_0603V-47UF,4V,20%,X5R,60A',
 VOLTAGE='4V',
 PRIM_FILE='./archive_libs/discrete/cap_a/chips/chips.prt';

PART_NAME
 C5A5 'CAP_A_0603V-47UF,4V,20%,X5R,60A':
 GROUP='PWR_MLCC_CAP';

SECTION_NUMBER 1
 '@BASEBOARD_FAB2_LIB.BASEBOARD_FAB2(SCH_1):PAGE220_I193@DEV_DISCRETE.CAP_A(CHIPS)':
 C_PATH='@baseboard_fab2_lib.baseboard_fab2(sch_1):page220_i193@dev_discrete.cap~
_a(chips)',
 P_PATH='@baseboard_fab2_lib.baseboard_fab2(sch_1):page220_i193@dev_discrete.cap~
_a(chips)',
 PATH='I193',
 DRAWING='@BASEBOARD_FAB2_LIB.BASEBOARD_FAB2(SCH_1):PAGE220',
 BOM_SS='NOPOP',
 TOLERANCE='20%',
 SEC_TYPE='0603V',
 MATERIAL='X5R',
 PHYS_PAGE='220',
 XY='(3000,950)',
 ROT='0',
 VER='1',
 VALUE='47UF',
 PACK_TYPE='0603V',
 PART_NUMBER='602433-106',
 LOCATION='C5A5',
 GROUP='PWR_MLCC_CAP',
 SEC='1',
 CDS_LIB='dev_discrete',
 CDS_PART_NAME='CAP_A_0603V-47UF,4V,20%,X5R,60A',
 VOLTAGE='4V',
 PRIM_FILE='./archive_libs/discrete/cap_a/chips/chips.prt';

PART_NAME
 C5A6 'CAP_A_0603V-47UF,4V,20%,X5R,60A':
 GROUP='PWR_MLCC_CAP';

SECTION_NUMBER 1
 '@BASEBOARD_FAB2_LIB.BASEBOARD_FAB2(SCH_1):PAGE220_I268@DEV_DISCRETE.CAP_A(CHIPS)':
 C_PATH='@baseboard_fab2_lib.baseboard_fab2(sch_1):page220_i268@dev_discrete.cap~
_a(chips)',
 P_PATH='@baseboard_fab2_lib.baseboard_fab2(sch_1):page220_i268@dev_discrete.cap~
_a(chips)',
 PATH='I268',
 DRAWING='@BASEBOARD_FAB2_LIB.BASEBOARD_FAB2(SCH_1):PAGE220',
 BOM_SS='E15431-004',
 TOLERANCE='20%',
 SEC_TYPE='0603V',
 MATERIAL='X5R',
 PHYS_PAGE='220',
 XY='(-400,100)',
 ROT='0',
 VER='1',
 VALUE='47UF',
 PACK_TYPE='0603V',
 PART_NUMBER='602433-106',
 LOCATION='C5A6',
 GROUP='PWR_MLCC_CAP',
 SEC='1',
 CDS_LIB='dev_discrete',
 CDS_PART_NAME='CAP_A_0603V-47UF,4V,20%,X5R,60A',
 VOLTAGE='4V',
 PRIM_FILE='./archive_libs/discrete/cap_a/chips/chips.prt';

PART_NAME
 C5A7 'CAP_A_0603V-47UF,4V,20%,X5R,60A':
 GROUP='PWR_MLCC_CAP';

SECTION_NUMBER 1
 '@BASEBOARD_FAB2_LIB.BASEBOARD_FAB2(SCH_1):PAGE220_I269@DEV_DISCRETE.CAP_A(CHIPS)':
 C_PATH='@baseboard_fab2_lib.baseboard_fab2(sch_1):page220_i269@dev_discrete.cap~
_a(chips)',
 P_PATH='@baseboard_fab2_lib.baseboard_fab2(sch_1):page220_i269@dev_discrete.cap~
_a(chips)',
 PATH='I269',
 DRAWING='@BASEBOARD_FAB2_LIB.BASEBOARD_FAB2(SCH_1):PAGE220',
 BOM_SS='E15431-004',
 TOLERANCE='20%',
 SEC_TYPE='0603V',
 MATERIAL='X5R',
 PHYS_PAGE='220',
 XY='(-125,100)',
 ROT='0',
 VER='1',
 VALUE='47UF',
 PACK_TYPE='0603V',
 PART_NUMBER='602433-106',
 LOCATION='C5A7',
 GROUP='PWR_MLCC_CAP',
 SEC='1',
 CDS_LIB='dev_discrete',
 CDS_PART_NAME='CAP_A_0603V-47UF,4V,20%,X5R,60A',
 VOLTAGE='4V',
 PRIM_FILE='./archive_libs/discrete/cap_a/chips/chips.prt';

PART_NAME
 C5A8 'CAP_A_0603V-47UF,4V,20%,X5R,60A':
 GROUP='PWR_MLCC_CAP';

SECTION_NUMBER 1
 '@BASEBOARD_FAB2_LIB.BASEBOARD_FAB2(SCH_1):PAGE220_I271@DEV_DISCRETE.CAP_A(CHIPS)':
 C_PATH='@baseboard_fab2_lib.baseboard_fab2(sch_1):page220_i271@dev_discrete.cap~
_a(chips)',
 P_PATH='@baseboard_fab2_lib.baseboard_fab2(sch_1):page220_i271@dev_discrete.cap~
_a(chips)',
 PATH='I271',
 DRAWING='@BASEBOARD_FAB2_LIB.BASEBOARD_FAB2(SCH_1):PAGE220',
 BOM_SS='E15431-004',
 TOLERANCE='20%',
 SEC_TYPE='0603V',
 MATERIAL='X5R',
 PHYS_PAGE='220',
 XY='(500,100)',
 ROT='0',
 VER='1',
 VALUE='47UF',
 PACK_TYPE='0603V',
 PART_NUMBER='602433-106',
 LOCATION='C5A8',
 GROUP='PWR_MLCC_CAP',
 SEC='1',
 CDS_LIB='dev_discrete',
 CDS_PART_NAME='CAP_A_0603V-47UF,4V,20%,X5R,60A',
 VOLTAGE='4V',
 PRIM_FILE='./archive_libs/discrete/cap_a/chips/chips.prt';

PART_NAME
 C5A9 'CAP_A_0603V-47UF,4V,20%,X5R,60A':
 GROUP='PWR_MLCC_CAP';

SECTION_NUMBER 1
 '@BASEBOARD_FAB2_LIB.BASEBOARD_FAB2(SCH_1):PAGE220_I272@DEV_DISCRETE.CAP_A(CHIPS)':
 C_PATH='@baseboard_fab2_lib.baseboard_fab2(sch_1):page220_i272@dev_discrete.cap~
_a(chips)',
 P_PATH='@baseboard_fab2_lib.baseboard_fab2(sch_1):page220_i272@dev_discrete.cap~
_a(chips)',
 PATH='I272',
 DRAWING='@BASEBOARD_FAB2_LIB.BASEBOARD_FAB2(SCH_1):PAGE220',
 BOM_SS='E15431-004',
 TOLERANCE='20%',
 SEC_TYPE='0603V',
 MATERIAL='X5R',
 PHYS_PAGE='220',
 XY='(800,100)',
 ROT='0',
 VER='1',
 VALUE='47UF',
 PACK_TYPE='0603V',
 PART_NUMBER='602433-106',
 LOCATION='C5A9',
 GROUP='PWR_MLCC_CAP',
 SEC='1',
 CDS_LIB='dev_discrete',
 CDS_PART_NAME='CAP_A_0603V-47UF,4V,20%,X5R,60A',
 VOLTAGE='4V',
 PRIM_FILE='./archive_libs/discrete/cap_a/chips/chips.prt';

PART_NAME
 C5A10 'CAP_0805-100UF,4V,20%,X5R,6024A':
 GROUP='PWR_MLCC_CAP',
 ROOM='VDDQ_ABC_PWR_VR';

SECTION_NUMBER 1
 '@BASEBOARD_FAB2_LIB.BASEBOARD_FAB2(SCH_1):PAGE220_I321@MSTR_DISCRETE.CAP(CHIPS)':
 C_PATH='@baseboard_fab2_lib.baseboard_fab2(sch_1):page220_i321@mstr_discrete.ca~
p(chips)',
 P_PATH='@baseboard_fab2_lib.baseboard_fab2(sch_1):page220_i321@mstr_discrete.ca~
p(chips)',
 PATH='I321',
 DRAWING='@BASEBOARD_FAB2_LIB.BASEBOARD_FAB2(SCH_1):PAGE220',
 NEW_PN='078.1071T.M002',
 NEW_MATERIAL='X6S',
 BOM_SS='NOPOP',
 TOLERANCE='20%',
 SEC_TYPE='0805',
 MATERIAL='X5R',
 BOM_COST='MEM_VRD_PVDDQ_CD',
 PHYS_PAGE='220',
 XY='(2400,2825)',
 ROT='0',
 VER='1',
 VALUE='100UF',
 PACK_TYPE='0805',
 PART_NUMBER='602433-112',
 LOCATION='C5A10',
 ROOM='VDDQ_ABC_PWR_VR',
 GROUP='PWR_MLCC_CAP',
 SEC='1',
 CDS_LIB='mstr_discrete',
 CDS_PART_NAME='CAP_0805-100UF,4V,20%,X5R,6024A',
 VOLTAGE='4V',
 PRIM_FILE='./archive_libs/mstr_discrete/cap/chips/chips.prt';

PART_NAME
 C5A11 'CAP_A_0603V-47UF,4V,20%,X5R,60A':
 GROUP='PWR_MLCC_CAP';

SECTION_NUMBER 1
 '@BASEBOARD_FAB2_LIB.BASEBOARD_FAB2(SCH_1):PAGE220_I293@DEV_DISCRETE.CAP_A(CHIPS)':
 C_PATH='@baseboard_fab2_lib.baseboard_fab2(sch_1):page220_i293@dev_discrete.cap~
_a(chips)',
 P_PATH='@baseboard_fab2_lib.baseboard_fab2(sch_1):page220_i293@dev_discrete.cap~
_a(chips)',
 PATH='I293',
 DRAWING='@BASEBOARD_FAB2_LIB.BASEBOARD_FAB2(SCH_1):PAGE220',
 BOM_SS='E15431-004',
 TOLERANCE='20%',
 SEC_TYPE='0603V',
 MATERIAL='X5R',
 PHYS_PAGE='220',
 XY='(2225,-650)',
 ROT='0',
 VER='1',
 VALUE='47UF',
 PACK_TYPE='0603V',
 PART_NUMBER='602433-106',
 LOCATION='C5A11',
 GROUP='PWR_MLCC_CAP',
 SEC='1',
 CDS_LIB='dev_discrete',
 CDS_PART_NAME='CAP_A_0603V-47UF,4V,20%,X5R,60A',
 VOLTAGE='4V',
 PRIM_FILE='./archive_libs/discrete/cap_a/chips/chips.prt';

PART_NAME
 C5A12 'CAP_A_0603V-47UF,4V,20%,X5R,60A':
 GROUP='PWR_MLCC_CAP';

SECTION_NUMBER 1
 '@BASEBOARD_FAB2_LIB.BASEBOARD_FAB2(SCH_1):PAGE220_I264@DEV_DISCRETE.CAP_A(CHIPS)':
 C_PATH='@baseboard_fab2_lib.baseboard_fab2(sch_1):page220_i264@dev_discrete.cap~
_a(chips)',
 P_PATH='@baseboard_fab2_lib.baseboard_fab2(sch_1):page220_i264@dev_discrete.cap~
_a(chips)',
 PATH='I264',
 DRAWING='@BASEBOARD_FAB2_LIB.BASEBOARD_FAB2(SCH_1):PAGE220',
 BOM_SS='E15431-004',
 TOLERANCE='20%',
 SEC_TYPE='0603V',
 MATERIAL='X5R',
 PHYS_PAGE='220',
 XY='(-1550,100)',
 ROT='0',
 VER='1',
 VALUE='47UF',
 PACK_TYPE='0603V',
 PART_NUMBER='602433-106',
 LOCATION='C5A12',
 GROUP='PWR_MLCC_CAP',
 SEC='1',
 CDS_LIB='dev_discrete',
 CDS_PART_NAME='CAP_A_0603V-47UF,4V,20%,X5R,60A',
 VOLTAGE='4V',
 PRIM_FILE='./archive_libs/discrete/cap_a/chips/chips.prt';

PART_NAME
 C5A13 'CAP_A_0603V-47UF,4V,20%,X5R,60A':
 GROUP='PWR_MLCC_CAP';

SECTION_NUMBER 1
 '@BASEBOARD_FAB2_LIB.BASEBOARD_FAB2(SCH_1):PAGE220_I265@DEV_DISCRETE.CAP_A(CHIPS)':
 C_PATH='@baseboard_fab2_lib.baseboard_fab2(sch_1):page220_i265@dev_discrete.cap~
_a(chips)',
 P_PATH='@baseboard_fab2_lib.baseboard_fab2(sch_1):page220_i265@dev_discrete.cap~
_a(chips)',
 PATH='I265',
 DRAWING='@BASEBOARD_FAB2_LIB.BASEBOARD_FAB2(SCH_1):PAGE220',
 BOM_SS='E15431-004',
 TOLERANCE='20%',
 SEC_TYPE='0603V',
 MATERIAL='X5R',
 PHYS_PAGE='220',
 XY='(-1275,100)',
 ROT='0',
 VER='1',
 VALUE='47UF',
 PACK_TYPE='0603V',
 PART_NUMBER='602433-106',
 LOCATION='C5A13',
 GROUP='PWR_MLCC_CAP',
 SEC='1',
 CDS_LIB='dev_discrete',
 CDS_PART_NAME='CAP_A_0603V-47UF,4V,20%,X5R,60A',
 VOLTAGE='4V',
 PRIM_FILE='./archive_libs/discrete/cap_a/chips/chips.prt';

PART_NAME
 C5A14 'CAP_A_0603V-47UF,4V,20%,X5R,60A':
 GROUP='PWR_MLCC_CAP';

SECTION_NUMBER 1
 '@BASEBOARD_FAB2_LIB.BASEBOARD_FAB2(SCH_1):PAGE220_I267@DEV_DISCRETE.CAP_A(CHIPS)':
 C_PATH='@baseboard_fab2_lib.baseboard_fab2(sch_1):page220_i267@dev_discrete.cap~
_a(chips)',
 P_PATH='@baseboard_fab2_lib.baseboard_fab2(sch_1):page220_i267@dev_discrete.cap~
_a(chips)',
 PATH='I267',
 DRAWING='@BASEBOARD_FAB2_LIB.BASEBOARD_FAB2(SCH_1):PAGE220',
 BOM_SS='E15431-004',
 TOLERANCE='20%',
 SEC_TYPE='0603V',
 MATERIAL='X5R',
 PHYS_PAGE='220',
 XY='(-700,100)',
 ROT='0',
 VER='1',
 VALUE='47UF',
 PACK_TYPE='0603V',
 PART_NUMBER='602433-106',
 LOCATION='C5A14',
 GROUP='PWR_MLCC_CAP',
 SEC='1',
 CDS_LIB='dev_discrete',
 CDS_PART_NAME='CAP_A_0603V-47UF,4V,20%,X5R,60A',
 VOLTAGE='4V',
 PRIM_FILE='./archive_libs/discrete/cap_a/chips/chips.prt';

PART_NAME
 C5A15 'CAP_A_0603V-47UF,4V,20%,X5R,60A':
 GROUP='PWR_MLCC_CAP';

SECTION_NUMBER 1
 '@BASEBOARD_FAB2_LIB.BASEBOARD_FAB2(SCH_1):PAGE220_I263@DEV_DISCRETE.CAP_A(CHIPS)':
 C_PATH='@baseboard_fab2_lib.baseboard_fab2(sch_1):page220_i263@dev_discrete.cap~
_a(chips)',
 P_PATH='@baseboard_fab2_lib.baseboard_fab2(sch_1):page220_i263@dev_discrete.cap~
_a(chips)',
 PATH='I263',
 DRAWING='@BASEBOARD_FAB2_LIB.BASEBOARD_FAB2(SCH_1):PAGE220',
 BOM_SS='E15431-004',
 TOLERANCE='20%',
 SEC_TYPE='0603V',
 MATERIAL='X5R',
 PHYS_PAGE='220',
 XY='(-1850,100)',
 ROT='0',
 VER='1',
 VALUE='47UF',
 PACK_TYPE='0603V',
 PART_NUMBER='602433-106',
 LOCATION='C5A15',
 GROUP='PWR_MLCC_CAP',
 SEC='1',
 CDS_LIB='dev_discrete',
 CDS_PART_NAME='CAP_A_0603V-47UF,4V,20%,X5R,60A',
 VOLTAGE='4V',
 PRIM_FILE='./archive_libs/discrete/cap_a/chips/chips.prt';

PART_NAME
 C5A16 'CAP_A_0603V-47UF,4V,20%,X5R,60A':
 GROUP='PWR_MLCC_CAP';

SECTION_NUMBER 1
 '@BASEBOARD_FAB2_LIB.BASEBOARD_FAB2(SCH_1):PAGE220_I273@DEV_DISCRETE.CAP_A(CHIPS)':
 C_PATH='@baseboard_fab2_lib.baseboard_fab2(sch_1):page220_i273@dev_discrete.cap~
_a(chips)',
 P_PATH='@baseboard_fab2_lib.baseboard_fab2(sch_1):page220_i273@dev_discrete.cap~
_a(chips)',
 PATH='I273',
 DRAWING='@BASEBOARD_FAB2_LIB.BASEBOARD_FAB2(SCH_1):PAGE220',
 BOM_SS='E15431-004',
 TOLERANCE='20%',
 SEC_TYPE='0603V',
 MATERIAL='X5R',
 PHYS_PAGE='220',
 XY='(1075,100)',
 ROT='0',
 VER='1',
 VALUE='47UF',
 PACK_TYPE='0603V',
 PART_NUMBER='602433-106',
 LOCATION='C5A16',
 GROUP='PWR_MLCC_CAP',
 SEC='1',
 CDS_LIB='dev_discrete',
 CDS_PART_NAME='CAP_A_0603V-47UF,4V,20%,X5R,60A',
 VOLTAGE='4V',
 PRIM_FILE='./archive_libs/discrete/cap_a/chips/chips.prt';

PART_NAME
 C5A17 'CAP_A_0603V-47UF,4V,20%,X5R,60A':
 GROUP='PWR_MLCC_CAP';

SECTION_NUMBER 1
 '@BASEBOARD_FAB2_LIB.BASEBOARD_FAB2(SCH_1):PAGE220_I275@DEV_DISCRETE.CAP_A(CHIPS)':
 C_PATH='@baseboard_fab2_lib.baseboard_fab2(sch_1):page220_i275@dev_discrete.cap~
_a(chips)',
 P_PATH='@baseboard_fab2_lib.baseboard_fab2(sch_1):page220_i275@dev_discrete.cap~
_a(chips)',
 PATH='I275',
 DRAWING='@BASEBOARD_FAB2_LIB.BASEBOARD_FAB2(SCH_1):PAGE220',
 BOM_SS='E15431-004',
 TOLERANCE='20%',
 SEC_TYPE='0603V',
 MATERIAL='X5R',
 PHYS_PAGE='220',
 XY='(1650,100)',
 ROT='0',
 VER='1',
 VALUE='47UF',
 PACK_TYPE='0603V',
 PART_NUMBER='602433-106',
 LOCATION='C5A17',
 GROUP='PWR_MLCC_CAP',
 SEC='1',
 CDS_LIB='dev_discrete',
 CDS_PART_NAME='CAP_A_0603V-47UF,4V,20%,X5R,60A',
 VOLTAGE='4V',
 PRIM_FILE='./archive_libs/discrete/cap_a/chips/chips.prt';

PART_NAME
 C5A18 'CAP_A_0603V-47UF,4V,20%,X5R,60A':
 GROUP='PWR_MLCC_CAP';

SECTION_NUMBER 1
 '@BASEBOARD_FAB2_LIB.BASEBOARD_FAB2(SCH_1):PAGE220_I276@DEV_DISCRETE.CAP_A(CHIPS)':
 C_PATH='@baseboard_fab2_lib.baseboard_fab2(sch_1):page220_i276@dev_discrete.cap~
_a(chips)',
 P_PATH='@baseboard_fab2_lib.baseboard_fab2(sch_1):page220_i276@dev_discrete.cap~
_a(chips)',
 PATH='I276',
 DRAWING='@BASEBOARD_FAB2_LIB.BASEBOARD_FAB2(SCH_1):PAGE220',
 BOM_SS='E15431-004',
 TOLERANCE='20%',
 SEC_TYPE='0603V',
 MATERIAL='X5R',
 PHYS_PAGE='220',
 XY='(1950,100)',
 ROT='0',
 VER='1',
 VALUE='47UF',
 PACK_TYPE='0603V',
 PART_NUMBER='602433-106',
 LOCATION='C5A18',
 GROUP='PWR_MLCC_CAP',
 SEC='1',
 CDS_LIB='dev_discrete',
 CDS_PART_NAME='CAP_A_0603V-47UF,4V,20%,X5R,60A',
 VOLTAGE='4V',
 PRIM_FILE='./archive_libs/discrete/cap_a/chips/chips.prt';

PART_NAME
 C5A19 'CAP_A_0603V-47UF,4V,20%,X5R,60A':
 GROUP='PWR_MLCC_CAP';

SECTION_NUMBER 1
 '@BASEBOARD_FAB2_LIB.BASEBOARD_FAB2(SCH_1):PAGE220_I277@DEV_DISCRETE.CAP_A(CHIPS)':
 C_PATH='@baseboard_fab2_lib.baseboard_fab2(sch_1):page220_i277@dev_discrete.cap~
_a(chips)',
 P_PATH='@baseboard_fab2_lib.baseboard_fab2(sch_1):page220_i277@dev_discrete.cap~
_a(chips)',
 PATH='I277',
 DRAWING='@BASEBOARD_FAB2_LIB.BASEBOARD_FAB2(SCH_1):PAGE220',
 BOM_SS='E15431-004',
 TOLERANCE='20%',
 SEC_TYPE='0603V',
 MATERIAL='X5R',
 PHYS_PAGE='220',
 XY='(2225,100)',
 ROT='0',
 VER='1',
 VALUE='47UF',
 PACK_TYPE='0603V',
 PART_NUMBER='602433-106',
 LOCATION='C5A19',
 GROUP='PWR_MLCC_CAP',
 SEC='1',
 CDS_LIB='dev_discrete',
 CDS_PART_NAME='CAP_A_0603V-47UF,4V,20%,X5R,60A',
 VOLTAGE='4V',
 PRIM_FILE='./archive_libs/discrete/cap_a/chips/chips.prt';

PART_NAME
 C5A20 'CAP_0805-100UF,4V,20%,X5R,6024A':
 GROUP='PWR_MLCC_CAP',
 ROOM='VDDQ_ABC_PWR_VR';

SECTION_NUMBER 1
 '@BASEBOARD_FAB2_LIB.BASEBOARD_FAB2(SCH_1):PAGE220_I308@MSTR_DISCRETE.CAP(CHIPS)':
 C_PATH='@baseboard_fab2_lib.baseboard_fab2(sch_1):page220_i308@mstr_discrete.ca~
p(chips)',
 P_PATH='@baseboard_fab2_lib.baseboard_fab2(sch_1):page220_i308@mstr_discrete.ca~
p(chips)',
 PATH='I308',
 DRAWING='@BASEBOARD_FAB2_LIB.BASEBOARD_FAB2(SCH_1):PAGE220',
 NEW_PN='078.1071T.M002',
 NEW_MATERIAL='X6S',
 BOM_SS='NOPOP',
 TOLERANCE='20%',
 SEC_TYPE='0805',
 MATERIAL='X5R',
 BOM_COST='MEM_VRD_PVDDQ_CD',
 PHYS_PAGE='220',
 XY='(2750,2825)',
 ROT='0',
 VER='1',
 VALUE='100UF',
 PACK_TYPE='0805',
 PART_NUMBER='602433-112',
 LOCATION='C5A20',
 ROOM='VDDQ_ABC_PWR_VR',
 GROUP='PWR_MLCC_CAP',
 SEC='1',
 CDS_LIB='mstr_discrete',
 CDS_PART_NAME='CAP_0805-100UF,4V,20%,X5R,6024A',
 VOLTAGE='4V',
 PRIM_FILE='./archive_libs/mstr_discrete/cap/chips/chips.prt';

PART_NAME
 C5B1 'CAP_A_0603V-47UF,4V,20%,X5R,60A':
 GROUP='PWR_MLCC_CAP';

SECTION_NUMBER 1
 '@BASEBOARD_FAB2_LIB.BASEBOARD_FAB2(SCH_1):PAGE220_I194@DEV_DISCRETE.CAP_A(CHIPS)':
 C_PATH='@baseboard_fab2_lib.baseboard_fab2(sch_1):page220_i194@dev_discrete.cap~
_a(chips)',
 P_PATH='@baseboard_fab2_lib.baseboard_fab2(sch_1):page220_i194@dev_discrete.cap~
_a(chips)',
 PATH='I194',
 DRAWING='@BASEBOARD_FAB2_LIB.BASEBOARD_FAB2(SCH_1):PAGE220',
 BOM_SS='NOPOP',
 TOLERANCE='20%',
 SEC_TYPE='0603V',
 MATERIAL='X5R',
 PHYS_PAGE='220',
 XY='(3400,950)',
 ROT='0',
 VER='1',
 VALUE='47UF',
 PACK_TYPE='0603V',
 PART_NUMBER='602433-106',
 LOCATION='C5B1',
 GROUP='PWR_MLCC_CAP',
 SEC='1',
 CDS_LIB='dev_discrete',
 CDS_PART_NAME='CAP_A_0603V-47UF,4V,20%,X5R,60A',
 VOLTAGE='4V',
 PRIM_FILE='./archive_libs/discrete/cap_a/chips/chips.prt';

PART_NAME
 C5B2 'CAP_A_0603V-47UF,4V,20%,X5R,60A':
 GROUP='PWR_MLCC_CAP';

SECTION_NUMBER 1
 '@BASEBOARD_FAB2_LIB.BASEBOARD_FAB2(SCH_1):PAGE220_I197@DEV_DISCRETE.CAP_A(CHIPS)':
 C_PATH='@baseboard_fab2_lib.baseboard_fab2(sch_1):page220_i197@dev_discrete.cap~
_a(chips)',
 P_PATH='@baseboard_fab2_lib.baseboard_fab2(sch_1):page220_i197@dev_discrete.cap~
_a(chips)',
 PATH='I197',
 DRAWING='@BASEBOARD_FAB2_LIB.BASEBOARD_FAB2(SCH_1):PAGE220',
 BOM_SS='NOPOP',
 TOLERANCE='20%',
 SEC_TYPE='0603V',
 MATERIAL='X5R',
 PHYS_PAGE='220',
 XY='(2675,1675)',
 ROT='0',
 VER='1',
 VALUE='47UF',
 PACK_TYPE='0603V',
 PART_NUMBER='602433-106',
 LOCATION='C5B2',
 GROUP='PWR_MLCC_CAP',
 SEC='1',
 CDS_LIB='dev_discrete',
 CDS_PART_NAME='CAP_A_0603V-47UF,4V,20%,X5R,60A',
 VOLTAGE='4V',
 PRIM_FILE='./archive_libs/discrete/cap_a/chips/chips.prt';

PART_NAME
 C5D1 'CAP_A_0603V-22.0UF,4V,20%,X6S,A':
 GROUP='PWR_MLCC_CAP',
 ROOM='PVCCIN_CPU0_DECAP_VR';

SECTION_NUMBER 1
 '@BASEBOARD_FAB2_LIB.BASEBOARD_FAB2(SCH_1):PAGE220_I252@DEV_DISCRETE.CAP_A(CHIPS)':
 C_PATH='@baseboard_fab2_lib.baseboard_fab2(sch_1):page220_i252@dev_discrete.cap~
_a(chips)',
 P_PATH='@baseboard_fab2_lib.baseboard_fab2(sch_1):page220_i252@dev_discrete.cap~
_a(chips)',
 PATH='I252',
 DRAWING='@BASEBOARD_FAB2_LIB.BASEBOARD_FAB2(SCH_1):PAGE220',
 TOLERANCE='20%',
 MATERIAL='X6S',
 BOM_COST='PROC_SOCKET',
 PHYS_PAGE='220',
 XY='(500,2050)',
 ROT='0',
 VER='1',
 VALUE='22.0UF',
 PACK_TYPE='0603V',
 PART_NUMBER='E15431-004',
 LOCATION='C5D1',
 ROOM='PVCCIN_CPU0_DECAP_VR',
 GROUP='PWR_MLCC_CAP',
 CDS_LIB='dev_discrete',
 CDS_PART_NAME='CAP_A_0603V-22.0UF,4V,20%,X6S,A',
 VOLTAGE='4V',
 PRIM_FILE='./archive_libs/discrete/cap_a/chips/chips.prt';

PART_NAME
 C5D2 'CAP_A_0603V-22.0UF,4V,20%,X6S,A':
 GROUP='PWR_MLCC_CAP',
 ROOM='PVCCIN_CPU0_DECAP_VR';

SECTION_NUMBER 1
 '@BASEBOARD_FAB2_LIB.BASEBOARD_FAB2(SCH_1):PAGE220_I251@DEV_DISCRETE.CAP_A(CHIPS)':
 C_PATH='@baseboard_fab2_lib.baseboard_fab2(sch_1):page220_i251@dev_discrete.cap~
_a(chips)',
 P_PATH='@baseboard_fab2_lib.baseboard_fab2(sch_1):page220_i251@dev_discrete.cap~
_a(chips)',
 PATH='I251',
 DRAWING='@BASEBOARD_FAB2_LIB.BASEBOARD_FAB2(SCH_1):PAGE220',
 TOLERANCE='20%',
 MATERIAL='X6S',
 BOM_COST='PROC_SOCKET',
 PHYS_PAGE='220',
 XY='(850,2050)',
 ROT='0',
 VER='1',
 VALUE='22.0UF',
 PACK_TYPE='0603V',
 PART_NUMBER='E15431-004',
 LOCATION='C5D2',
 ROOM='PVCCIN_CPU0_DECAP_VR',
 GROUP='PWR_MLCC_CAP',
 CDS_LIB='dev_discrete',
 CDS_PART_NAME='CAP_A_0603V-22.0UF,4V,20%,X6S,A',
 VOLTAGE='4V',
 PRIM_FILE='./archive_libs/discrete/cap_a/chips/chips.prt';

PART_NAME
 C5D3 'CAP_A_0603V-22.0UF,4V,20%,X6S,A':
 GROUP='PWR_MLCC_CAP',
 ROOM='PVCCIN_CPU0_DECAP_VR';

SECTION_NUMBER 1
 '@BASEBOARD_FAB2_LIB.BASEBOARD_FAB2(SCH_1):PAGE220_I250@DEV_DISCRETE.CAP_A(CHIPS)':
 C_PATH='@baseboard_fab2_lib.baseboard_fab2(sch_1):page220_i250@dev_discrete.cap~
_a(chips)',
 P_PATH='@baseboard_fab2_lib.baseboard_fab2(sch_1):page220_i250@dev_discrete.cap~
_a(chips)',
 PATH='I250',
 DRAWING='@BASEBOARD_FAB2_LIB.BASEBOARD_FAB2(SCH_1):PAGE220',
 TOLERANCE='20%',
 MATERIAL='X6S',
 BOM_COST='PROC_SOCKET',
 PHYS_PAGE='220',
 XY='(1200,2050)',
 ROT='0',
 VER='1',
 VALUE='22.0UF',
 PACK_TYPE='0603V',
 PART_NUMBER='E15431-004',
 LOCATION='C5D3',
 ROOM='PVCCIN_CPU0_DECAP_VR',
 GROUP='PWR_MLCC_CAP',
 CDS_LIB='dev_discrete',
 CDS_PART_NAME='CAP_A_0603V-22.0UF,4V,20%,X6S,A',
 VOLTAGE='4V',
 PRIM_FILE='./archive_libs/discrete/cap_a/chips/chips.prt';

PART_NAME
 C5D4 'CAP_A_0603V-22.0UF,4V,20%,X6S,A':
 GROUP='PWR_MLCC_CAP',
 ROOM='PVCCIN_CPU0_DECAP_VR';

SECTION_NUMBER 1
 '@BASEBOARD_FAB2_LIB.BASEBOARD_FAB2(SCH_1):PAGE220_I249@DEV_DISCRETE.CAP_A(CHIPS)':
 C_PATH='@baseboard_fab2_lib.baseboard_fab2(sch_1):page220_i249@dev_discrete.cap~
_a(chips)',
 P_PATH='@baseboard_fab2_lib.baseboard_fab2(sch_1):page220_i249@dev_discrete.cap~
_a(chips)',
 PATH='I249',
 DRAWING='@BASEBOARD_FAB2_LIB.BASEBOARD_FAB2(SCH_1):PAGE220',
 TOLERANCE='20%',
 MATERIAL='X6S',
 BOM_COST='PROC_SOCKET',
 PHYS_PAGE='220',
 XY='(1550,2050)',
 ROT='0',
 VER='1',
 VALUE='22.0UF',
 PACK_TYPE='0603V',
 PART_NUMBER='E15431-004',
 LOCATION='C5D4',
 ROOM='PVCCIN_CPU0_DECAP_VR',
 GROUP='PWR_MLCC_CAP',
 CDS_LIB='dev_discrete',
 CDS_PART_NAME='CAP_A_0603V-22.0UF,4V,20%,X6S,A',
 VOLTAGE='4V',
 PRIM_FILE='./archive_libs/discrete/cap_a/chips/chips.prt';

PART_NAME
 C5D5 'CAP_A_0603V-22.0UF,4V,20%,X6S,A':
 GROUP='PWR_MLCC_CAP',
 ROOM='PVCCIN_CPU0_DECAP_VR';

SECTION_NUMBER 1
 '@BASEBOARD_FAB2_LIB.BASEBOARD_FAB2(SCH_1):PAGE42_I125@DEV_DISCRETE.CAP_A(CHIPS)':
 C_PATH='@baseboard_fab2_lib.baseboard_fab2(sch_1):page42_i125@dev_discrete.cap_~
a(chips)',
 P_PATH='@baseboard_fab2_lib.baseboard_fab2(sch_1):page42_i125@dev_discrete.cap_~
a(chips)',
 PATH='I125',
 DRAWING='@BASEBOARD_FAB2_LIB.BASEBOARD_FAB2(SCH_1):PAGE42',
 TOLERANCE='20%',
 MATERIAL='X6S',
 BOM_COST='PROC_SOCKET',
 PHYS_PAGE='42',
 XY='(-7050,4500)',
 ROT='0',
 VER='1',
 VALUE='22.0UF',
 PACK_TYPE='0603V',
 PART_NUMBER='E15431-004',
 LOCATION='C5D5',
 ROOM='PVCCIN_CPU0_DECAP_VR',
 GROUP='PWR_MLCC_CAP',
 CDS_LIB='dev_discrete',
 CDS_PART_NAME='CAP_A_0603V-22.0UF,4V,20%,X6S,A',
 VOLTAGE='4V',
 PRIM_FILE='./archive_libs/discrete/cap_a/chips/chips.prt';

PART_NAME
 C5D6 'CAP_A_0603V-22.0UF,4V,20%,X6S,A':
 GROUP='PWR_MLCC_CAP',
 ROOM='PVCCIN_CPU0_DECAP_VR';

SECTION_NUMBER 1
 '@BASEBOARD_FAB2_LIB.BASEBOARD_FAB2(SCH_1):PAGE220_I259@DEV_DISCRETE.CAP_A(CHIPS)':
 C_PATH='@baseboard_fab2_lib.baseboard_fab2(sch_1):page220_i259@dev_discrete.cap~
_a(chips)',
 P_PATH='@baseboard_fab2_lib.baseboard_fab2(sch_1):page220_i259@dev_discrete.cap~
_a(chips)',
 PATH='I259',
 DRAWING='@BASEBOARD_FAB2_LIB.BASEBOARD_FAB2(SCH_1):PAGE220',
 TOLERANCE='20%',
 MATERIAL='X6S',
 BOM_COST='PROC_SOCKET',
 PHYS_PAGE='220',
 XY='(-1100,2975)',
 ROT='0',
 VER='1',
 VALUE='22.0UF',
 PACK_TYPE='0603V',
 PART_NUMBER='E15431-004',
 LOCATION='C5D6',
 ROOM='PVCCIN_CPU0_DECAP_VR',
 GROUP='PWR_MLCC_CAP',
 CDS_LIB='dev_discrete',
 CDS_PART_NAME='CAP_A_0603V-22.0UF,4V,20%,X6S,A',
 VOLTAGE='4V',
 PRIM_FILE='./archive_libs/discrete/cap_a/chips/chips.prt';

PART_NAME
 C5D7 'CAP_A_0603V-22.0UF,4V,20%,X6S,A':
 GROUP='PWR_MLCC_CAP',
 ROOM='PVCCIN_CPU0_DECAP_VR';

SECTION_NUMBER 1
 '@BASEBOARD_FAB2_LIB.BASEBOARD_FAB2(SCH_1):PAGE220_I260@DEV_DISCRETE.CAP_A(CHIPS)':
 C_PATH='@baseboard_fab2_lib.baseboard_fab2(sch_1):page220_i260@dev_discrete.cap~
_a(chips)',
 P_PATH='@baseboard_fab2_lib.baseboard_fab2(sch_1):page220_i260@dev_discrete.cap~
_a(chips)',
 PATH='I260',
 DRAWING='@BASEBOARD_FAB2_LIB.BASEBOARD_FAB2(SCH_1):PAGE220',
 TOLERANCE='20%',
 MATERIAL='X6S',
 BOM_COST='PROC_SOCKET',
 PHYS_PAGE='220',
 XY='(-750,2975)',
 ROT='0',
 VER='1',
 VALUE='22.0UF',
 PACK_TYPE='0603V',
 PART_NUMBER='E15431-004',
 LOCATION='C5D7',
 ROOM='PVCCIN_CPU0_DECAP_VR',
 GROUP='PWR_MLCC_CAP',
 CDS_LIB='dev_discrete',
 CDS_PART_NAME='CAP_A_0603V-22.0UF,4V,20%,X6S,A',
 VOLTAGE='4V',
 PRIM_FILE='./archive_libs/discrete/cap_a/chips/chips.prt';

PART_NAME
 C5D8 'CAP_A_0603V-22.0UF,4V,20%,X6S,A':
 GROUP='PWR_MLCC_CAP',
 ROOM='PVCCIN_CPU0_DECAP_VR';

SECTION_NUMBER 1
 '@BASEBOARD_FAB2_LIB.BASEBOARD_FAB2(SCH_1):PAGE220_I261@DEV_DISCRETE.CAP_A(CHIPS)':
 C_PATH='@baseboard_fab2_lib.baseboard_fab2(sch_1):page220_i261@dev_discrete.cap~
_a(chips)',
 P_PATH='@baseboard_fab2_lib.baseboard_fab2(sch_1):page220_i261@dev_discrete.cap~
_a(chips)',
 PATH='I261',
 DRAWING='@BASEBOARD_FAB2_LIB.BASEBOARD_FAB2(SCH_1):PAGE220',
 TOLERANCE='20%',
 MATERIAL='X6S',
 BOM_COST='PROC_SOCKET',
 PHYS_PAGE='220',
 XY='(-400,2975)',
 ROT='0',
 VER='1',
 VALUE='22.0UF',
 PACK_TYPE='0603V',
 PART_NUMBER='E15431-004',
 LOCATION='C5D8',
 ROOM='PVCCIN_CPU0_DECAP_VR',
 GROUP='PWR_MLCC_CAP',
 CDS_LIB='dev_discrete',
 CDS_PART_NAME='CAP_A_0603V-22.0UF,4V,20%,X6S,A',
 VOLTAGE='4V',
 PRIM_FILE='./archive_libs/discrete/cap_a/chips/chips.prt';

PART_NAME
 C5D9 'CAP_A_0603V-22.0UF,4V,20%,X6S,A':
 GROUP='PWR_MLCC_CAP',
 ROOM='PVCCIN_CPU0_DECAP_VR';

SECTION_NUMBER 1
 '@BASEBOARD_FAB2_LIB.BASEBOARD_FAB2(SCH_1):PAGE220_I258@DEV_DISCRETE.CAP_A(CHIPS)':
 C_PATH='@baseboard_fab2_lib.baseboard_fab2(sch_1):page220_i258@dev_discrete.cap~
_a(chips)',
 P_PATH='@baseboard_fab2_lib.baseboard_fab2(sch_1):page220_i258@dev_discrete.cap~
_a(chips)',
 PATH='I258',
 DRAWING='@BASEBOARD_FAB2_LIB.BASEBOARD_FAB2(SCH_1):PAGE220',
 TOLERANCE='20%',
 MATERIAL='X6S',
 BOM_COST='PROC_SOCKET',
 PHYS_PAGE='220',
 XY='(-1450,2975)',
 ROT='0',
 VER='1',
 VALUE='22.0UF',
 PACK_TYPE='0603V',
 PART_NUMBER='E15431-004',
 LOCATION='C5D9',
 ROOM='PVCCIN_CPU0_DECAP_VR',
 GROUP='PWR_MLCC_CAP',
 CDS_LIB='dev_discrete',
 CDS_PART_NAME='CAP_A_0603V-22.0UF,4V,20%,X6S,A',
 VOLTAGE='4V',
 PRIM_FILE='./archive_libs/discrete/cap_a/chips/chips.prt';

PART_NAME
 C5D10 'CAP_0603LF-10UF,4V,20%,X6S,E15A':
 GROUP='PWR_MLCC_CAP',
 ROOM='PVCCIN_CPU0_DECAP_VR';

SECTION_NUMBER 1
 '@BASEBOARD_FAB2_LIB.BASEBOARD_FAB2(SCH_1):PAGE42_I108@MSTR_DISCRETE.CAP(CHIPS)':
 C_PATH='@baseboard_fab2_lib.baseboard_fab2(sch_1):page42_i108@mstr_discrete.cap~
(chips)',
 P_PATH='@baseboard_fab2_lib.baseboard_fab2(sch_1):page42_i108@mstr_discrete.cap~
(chips)',
 PATH='I108',
 DRAWING='@BASEBOARD_FAB2_LIB.BASEBOARD_FAB2(SCH_1):PAGE42',
 TOLERANCE='20%',
 MATERIAL='X6S',
 BOM_COST='PROC_SOCKET',
 PHYS_PAGE='42',
 XY='(-4100,3150)',
 ROT='0',
 VER='1',
 VALUE='10UF',
 PACK_TYPE='0603LF',
 PART_NUMBER='E15431-001',
 LOCATION='C5D10',
 ROOM='PVCCIN_CPU0_DECAP_VR',
 GROUP='PWR_MLCC_CAP',
 CDS_LIB='mstr_discrete',
 CDS_PART_NAME='CAP_0603LF-10UF,4V,20%,X6S,E15A',
 VOLTAGE='4V',
 PRIM_FILE='./archive_libs/mstr_discrete/cap/chips/chips.prt';

PART_NAME
 C5D11 'CAP_0603LF-10UF,4V,20%,X6S,E15A':
 GROUP='PWR_MLCC_CAP',
 ROOM='PVCCIN_CPU0_DECAP_VR';

SECTION_NUMBER 1
 '@BASEBOARD_FAB2_LIB.BASEBOARD_FAB2(SCH_1):PAGE42_I93@MSTR_DISCRETE.CAP(CHIPS)':
 C_PATH='@baseboard_fab2_lib.baseboard_fab2(sch_1):page42_i93@mstr_discrete.cap(~
chips)',
 P_PATH='@baseboard_fab2_lib.baseboard_fab2(sch_1):page42_i93@mstr_discrete.cap(~
chips)',
 PATH='I93',
 DRAWING='@BASEBOARD_FAB2_LIB.BASEBOARD_FAB2(SCH_1):PAGE42',
 TOLERANCE='20%',
 MATERIAL='X6S',
 BOM_COST='PROC_SOCKET',
 PHYS_PAGE='42',
 XY='(-3500,3150)',
 ROT='0',
 VER='1',
 VALUE='10UF',
 PACK_TYPE='0603LF',
 PART_NUMBER='E15431-001',
 LOCATION='C5D11',
 ROOM='PVCCIN_CPU0_DECAP_VR',
 GROUP='PWR_MLCC_CAP',
 CDS_LIB='mstr_discrete',
 CDS_PART_NAME='CAP_0603LF-10UF,4V,20%,X6S,E15A',
 VOLTAGE='4V',
 PRIM_FILE='./archive_libs/mstr_discrete/cap/chips/chips.prt';

PART_NAME
 C5D12 'CAP_0603LF-10UF,4V,20%,X6S,E15A':
 GROUP='PWR_MLCC_CAP',
 ROOM='PVCCIN_CPU0_DECAP_VR';

SECTION_NUMBER 1
 '@BASEBOARD_FAB2_LIB.BASEBOARD_FAB2(SCH_1):PAGE42_I94@MSTR_DISCRETE.CAP(CHIPS)':
 C_PATH='@baseboard_fab2_lib.baseboard_fab2(sch_1):page42_i94@mstr_discrete.cap(~
chips)',
 P_PATH='@baseboard_fab2_lib.baseboard_fab2(sch_1):page42_i94@mstr_discrete.cap(~
chips)',
 PATH='I94',
 DRAWING='@BASEBOARD_FAB2_LIB.BASEBOARD_FAB2(SCH_1):PAGE42',
 TOLERANCE='20%',
 MATERIAL='X6S',
 BOM_COST='PROC_SOCKET',
 PHYS_PAGE='42',
 XY='(-3800,3150)',
 ROT='0',
 VER='1',
 VALUE='10UF',
 PACK_TYPE='0603LF',
 PART_NUMBER='E15431-001',
 LOCATION='C5D12',
 ROOM='PVCCIN_CPU0_DECAP_VR',
 GROUP='PWR_MLCC_CAP',
 CDS_LIB='mstr_discrete',
 CDS_PART_NAME='CAP_0603LF-10UF,4V,20%,X6S,E15A',
 VOLTAGE='4V',
 PRIM_FILE='./archive_libs/mstr_discrete/cap/chips/chips.prt';

PART_NAME
 C5D13 'CAP_0603LF-10UF,4V,20%,X6S,E15A':
 GROUP='PWR_MLCC_CAP',
 ROOM='PVCCIN_CPU0_DECAP_VR';

SECTION_NUMBER 1
 '@BASEBOARD_FAB2_LIB.BASEBOARD_FAB2(SCH_1):PAGE42_I91@MSTR_DISCRETE.CAP(CHIPS)':
 C_PATH='@baseboard_fab2_lib.baseboard_fab2(sch_1):page42_i91@mstr_discrete.cap(~
chips)',
 P_PATH='@baseboard_fab2_lib.baseboard_fab2(sch_1):page42_i91@mstr_discrete.cap(~
chips)',
 PATH='I91',
 DRAWING='@BASEBOARD_FAB2_LIB.BASEBOARD_FAB2(SCH_1):PAGE42',
 TOLERANCE='20%',
 MATERIAL='X6S',
 BOM_COST='PROC_SOCKET',
 PHYS_PAGE='42',
 XY='(-3200,3150)',
 ROT='0',
 VER='1',
 VALUE='10UF',
 PACK_TYPE='0603LF',
 PART_NUMBER='E15431-001',
 LOCATION='C5D13',
 ROOM='PVCCIN_CPU0_DECAP_VR',
 GROUP='PWR_MLCC_CAP',
 CDS_LIB='mstr_discrete',
 CDS_PART_NAME='CAP_0603LF-10UF,4V,20%,X6S,E15A',
 VOLTAGE='4V',
 PRIM_FILE='./archive_libs/mstr_discrete/cap/chips/chips.prt';

PART_NAME
 C5D14 'CAP_A_0603V-22.0UF,4V,20%,X6S,A':
 GROUP='PWR_MLCC_CAP',
 ROOM='PVCCIN_CPU0_DECAP_VR';

SECTION_NUMBER 1
 '@BASEBOARD_FAB2_LIB.BASEBOARD_FAB2(SCH_1):PAGE42_I117@DEV_DISCRETE.CAP_A(CHIPS)':
 C_PATH='@baseboard_fab2_lib.baseboard_fab2(sch_1):page42_i117@dev_discrete.cap_~
a(chips)',
 P_PATH='@baseboard_fab2_lib.baseboard_fab2(sch_1):page42_i117@dev_discrete.cap_~
a(chips)',
 PATH='I117',
 DRAWING='@BASEBOARD_FAB2_LIB.BASEBOARD_FAB2(SCH_1):PAGE42',
 TOLERANCE='20%',
 MATERIAL='X6S',
 BOM_COST='PROC_SOCKET',
 PHYS_PAGE='42',
 XY='(-5950,4500)',
 ROT='0',
 VER='1',
 VALUE='22.0UF',
 PACK_TYPE='0603V',
 PART_NUMBER='E15431-004',
 LOCATION='C5D14',
 ROOM='PVCCIN_CPU0_DECAP_VR',
 GROUP='PWR_MLCC_CAP',
 CDS_LIB='dev_discrete',
 CDS_PART_NAME='CAP_A_0603V-22.0UF,4V,20%,X6S,A',
 VOLTAGE='4V',
 PRIM_FILE='./archive_libs/discrete/cap_a/chips/chips.prt';

PART_NAME
 C5D15 'CAP_A_0603V-22.0UF,4V,20%,X6S,A':
 GROUP='PWR_MLCC_CAP',
 ROOM='PVCCIN_CPU0_DECAP_VR';

SECTION_NUMBER 1
 '@BASEBOARD_FAB2_LIB.BASEBOARD_FAB2(SCH_1):PAGE42_I132@DEV_DISCRETE.CAP_A(CHIPS)':
 C_PATH='@baseboard_fab2_lib.baseboard_fab2(sch_1):page42_i132@dev_discrete.cap_~
a(chips)',
 P_PATH='@baseboard_fab2_lib.baseboard_fab2(sch_1):page42_i132@dev_discrete.cap_~
a(chips)',
 PATH='I132',
 DRAWING='@BASEBOARD_FAB2_LIB.BASEBOARD_FAB2(SCH_1):PAGE42',
 TOLERANCE='20%',
 MATERIAL='X6S',
 BOM_COST='PROC_SOCKET',
 PHYS_PAGE='42',
 XY='(-6650,3100)',
 ROT='0',
 VER='1',
 VALUE='22.0UF',
 PACK_TYPE='0603V',
 PART_NUMBER='E15431-004',
 LOCATION='C5D15',
 ROOM='PVCCIN_CPU0_DECAP_VR',
 GROUP='PWR_MLCC_CAP',
 CDS_LIB='dev_discrete',
 CDS_PART_NAME='CAP_A_0603V-22.0UF,4V,20%,X6S,A',
 VOLTAGE='4V',
 PRIM_FILE='./archive_libs/discrete/cap_a/chips/chips.prt';

PART_NAME
 C5D16 'CAP_A_0603V-22.0UF,4V,20%,X6S,A':
 GROUP='PWR_MLCC_CAP',
 ROOM='PVCCIN_CPU0_DECAP_VR';

SECTION_NUMBER 1
 '@BASEBOARD_FAB2_LIB.BASEBOARD_FAB2(SCH_1):PAGE42_I123@DEV_DISCRETE.CAP_A(CHIPS)':
 C_PATH='@baseboard_fab2_lib.baseboard_fab2(sch_1):page42_i123@dev_discrete.cap_~
a(chips)',
 P_PATH='@baseboard_fab2_lib.baseboard_fab2(sch_1):page42_i123@dev_discrete.cap_~
a(chips)',
 PATH='I123',
 DRAWING='@BASEBOARD_FAB2_LIB.BASEBOARD_FAB2(SCH_1):PAGE42',
 TOLERANCE='20%',
 MATERIAL='X6S',
 BOM_COST='PROC_SOCKET',
 PHYS_PAGE='42',
 XY='(-6750,3800)',
 ROT='0',
 VER='1',
 VALUE='22.0UF',
 PACK_TYPE='0603V',
 PART_NUMBER='E15431-004',
 LOCATION='C5D16',
 ROOM='PVCCIN_CPU0_DECAP_VR',
 GROUP='PWR_MLCC_CAP',
 CDS_LIB='dev_discrete',
 CDS_PART_NAME='CAP_A_0603V-22.0UF,4V,20%,X6S,A',
 VOLTAGE='4V',
 PRIM_FILE='./archive_libs/discrete/cap_a/chips/chips.prt';

PART_NAME
 C5D17 'CAP_A_0603V-22.0UF,4V,20%,X6S,A':
 GROUP='PWR_MLCC_CAP',
 ROOM='PVCCIN_CPU0_DECAP_VR';

SECTION_NUMBER 1
 '@BASEBOARD_FAB2_LIB.BASEBOARD_FAB2(SCH_1):PAGE42_I118@DEV_DISCRETE.CAP_A(CHIPS)':
 C_PATH='@baseboard_fab2_lib.baseboard_fab2(sch_1):page42_i118@dev_discrete.cap_~
a(chips)',
 P_PATH='@baseboard_fab2_lib.baseboard_fab2(sch_1):page42_i118@dev_discrete.cap_~
a(chips)',
 PATH='I118',
 DRAWING='@BASEBOARD_FAB2_LIB.BASEBOARD_FAB2(SCH_1):PAGE42',
 TOLERANCE='20%',
 MATERIAL='X6S',
 BOM_COST='PROC_SOCKET',
 PHYS_PAGE='42',
 XY='(-6750,4500)',
 ROT='0',
 VER='1',
 VALUE='22.0UF',
 PACK_TYPE='0603V',
 PART_NUMBER='E15431-004',
 LOCATION='C5D17',
 ROOM='PVCCIN_CPU0_DECAP_VR',
 GROUP='PWR_MLCC_CAP',
 CDS_LIB='dev_discrete',
 CDS_PART_NAME='CAP_A_0603V-22.0UF,4V,20%,X6S,A',
 VOLTAGE='4V',
 PRIM_FILE='./archive_libs/discrete/cap_a/chips/chips.prt';

PART_NAME
 C5D18 'CAP_A_0603V-22.0UF,4V,20%,X6S,A':
 GROUP='PWR_MLCC_CAP',
 ROOM='PVCCIN_CPU0_DECAP_VR';

SECTION_NUMBER 1
 '@BASEBOARD_FAB2_LIB.BASEBOARD_FAB2(SCH_1):PAGE42_I134@DEV_DISCRETE.CAP_A(CHIPS)':
 C_PATH='@baseboard_fab2_lib.baseboard_fab2(sch_1):page42_i134@dev_discrete.cap_~
a(chips)',
 P_PATH='@baseboard_fab2_lib.baseboard_fab2(sch_1):page42_i134@dev_discrete.cap_~
a(chips)',
 PATH='I134',
 DRAWING='@BASEBOARD_FAB2_LIB.BASEBOARD_FAB2(SCH_1):PAGE42',
 TOLERANCE='20%',
 MATERIAL='X6S',
 BOM_COST='PROC_SOCKET',
 PHYS_PAGE='42',
 XY='(-6950,3100)',
 ROT='0',
 VER='1',
 VALUE='22.0UF',
 PACK_TYPE='0603V',
 PART_NUMBER='E15431-004',
 LOCATION='C5D18',
 ROOM='PVCCIN_CPU0_DECAP_VR',
 GROUP='PWR_MLCC_CAP',
 CDS_LIB='dev_discrete',
 CDS_PART_NAME='CAP_A_0603V-22.0UF,4V,20%,X6S,A',
 VOLTAGE='4V',
 PRIM_FILE='./archive_libs/discrete/cap_a/chips/chips.prt';

PART_NAME
 C5D19 'CAP_A_0603V-22.0UF,4V,20%,X6S,A':
 GROUP='PWR_MLCC_CAP',
 ROOM='PVCCIN_CPU0_DECAP_VR';

SECTION_NUMBER 1
 '@BASEBOARD_FAB2_LIB.BASEBOARD_FAB2(SCH_1):PAGE42_I128@DEV_DISCRETE.CAP_A(CHIPS)':
 C_PATH='@baseboard_fab2_lib.baseboard_fab2(sch_1):page42_i128@dev_discrete.cap_~
a(chips)',
 P_PATH='@baseboard_fab2_lib.baseboard_fab2(sch_1):page42_i128@dev_discrete.cap_~
a(chips)',
 PATH='I128',
 DRAWING='@BASEBOARD_FAB2_LIB.BASEBOARD_FAB2(SCH_1):PAGE42',
 TOLERANCE='20%',
 MATERIAL='X6S',
 BOM_COST='PROC_SOCKET',
 PHYS_PAGE='42',
 XY='(-7050,3800)',
 ROT='0',
 VER='1',
 VALUE='22.0UF',
 PACK_TYPE='0603V',
 PART_NUMBER='E15431-004',
 LOCATION='C5D19',
 ROOM='PVCCIN_CPU0_DECAP_VR',
 GROUP='PWR_MLCC_CAP',
 CDS_LIB='dev_discrete',
 CDS_PART_NAME='CAP_A_0603V-22.0UF,4V,20%,X6S,A',
 VOLTAGE='4V',
 PRIM_FILE='./archive_libs/discrete/cap_a/chips/chips.prt';

PART_NAME
 C5D20 'CAP_A_0603V-22.0UF,4V,20%,X6S,A':
 GROUP='PWR_MCP_CAP',
 ROOM='PVCCIN_CPU0_DECAP_VR';

SECTION_NUMBER 1
 '@BASEBOARD_FAB2_LIB.BASEBOARD_FAB2(SCH_1):PAGE42_I173@DEV_DISCRETE.CAP_A(CHIPS)':
 C_PATH='@baseboard_fab2_lib.baseboard_fab2(sch_1):page42_i173@dev_discrete.cap_~
a(chips)',
 P_PATH='@baseboard_fab2_lib.baseboard_fab2(sch_1):page42_i173@dev_discrete.cap_~
a(chips)',
 PATH='I173',
 DRAWING='@BASEBOARD_FAB2_LIB.BASEBOARD_FAB2(SCH_1):PAGE42',
 TOLERANCE='20%',
 MATERIAL='X6S',
 BOM_COST='PROC_SOCKET',
 PHYS_PAGE='42',
 XY='(-1050,3850)',
 ROT='0',
 VER='1',
 VALUE='22.0UF',
 PACK_TYPE='0603V',
 PART_NUMBER='E15431-004',
 LOCATION='C5D20',
 ROOM='PVCCIN_CPU0_DECAP_VR',
 GROUP='PWR_MCP_CAP',
 CDS_LIB='dev_discrete',
 CDS_PART_NAME='CAP_A_0603V-22.0UF,4V,20%,X6S,A',
 VOLTAGE='4V',
 PRIM_FILE='./archive_libs/discrete/cap_a/chips/chips.prt';

PART_NAME
 C5D21 'CAP_A_0603V-22.0UF,4V,20%,X6S,A':
 GROUP='PWR_MCP_CAP',
 ROOM='PVCCIN_CPU0_DECAP_VR';

SECTION_NUMBER 1
 '@BASEBOARD_FAB2_LIB.BASEBOARD_FAB2(SCH_1):PAGE42_I88@DEV_DISCRETE.CAP_A(CHIPS)':
 C_PATH='@baseboard_fab2_lib.baseboard_fab2(sch_1):page42_i88@dev_discrete.cap_a~
(chips)',
 P_PATH='@baseboard_fab2_lib.baseboard_fab2(sch_1):page42_i88@dev_discrete.cap_a~
(chips)',
 PATH='I88',
 DRAWING='@BASEBOARD_FAB2_LIB.BASEBOARD_FAB2(SCH_1):PAGE42',
 TOLERANCE='20%',
 MATERIAL='X6S',
 BOM_COST='PROC_SOCKET',
 PHYS_PAGE='42',
 XY='(-2800,4500)',
 ROT='0',
 VER='1',
 VALUE='22.0UF',
 PACK_TYPE='0603V',
 PART_NUMBER='E15431-004',
 LOCATION='C5D21',
 ROOM='PVCCIN_CPU0_DECAP_VR',
 GROUP='PWR_MCP_CAP',
 CDS_LIB='dev_discrete',
 CDS_PART_NAME='CAP_A_0603V-22.0UF,4V,20%,X6S,A',
 VOLTAGE='4V',
 PRIM_FILE='./archive_libs/discrete/cap_a/chips/chips.prt';

PART_NAME
 C5D22 'CAP_A_0603V-22.0UF,4V,20%,X6S,A':
 GROUP='PWR_MCP_CAP',
 ROOM='PVCCIN_CPU0_DECAP_VR';

SECTION_NUMBER 1
 '@BASEBOARD_FAB2_LIB.BASEBOARD_FAB2(SCH_1):PAGE42_I153@DEV_DISCRETE.CAP_A(CHIPS)':
 C_PATH='@baseboard_fab2_lib.baseboard_fab2(sch_1):page42_i153@dev_discrete.cap_~
a(chips)',
 P_PATH='@baseboard_fab2_lib.baseboard_fab2(sch_1):page42_i153@dev_discrete.cap_~
a(chips)',
 PATH='I153',
 DRAWING='@BASEBOARD_FAB2_LIB.BASEBOARD_FAB2(SCH_1):PAGE42',
 TOLERANCE='20%',
 MATERIAL='X6S',
 BOM_COST='PROC_SOCKET',
 PHYS_PAGE='42',
 XY='(-550,4500)',
 ROT='0',
 VER='1',
 VALUE='22.0UF',
 PACK_TYPE='0603V',
 PART_NUMBER='E15431-004',
 LOCATION='C5D22',
 ROOM='PVCCIN_CPU0_DECAP_VR',
 GROUP='PWR_MCP_CAP',
 CDS_LIB='dev_discrete',
 CDS_PART_NAME='CAP_A_0603V-22.0UF,4V,20%,X6S,A',
 VOLTAGE='4V',
 PRIM_FILE='./archive_libs/discrete/cap_a/chips/chips.prt';

PART_NAME
 C5D23 'CAP_A_0603V-22.0UF,4V,20%,X6S,A':
 GROUP='PWR_MCP_CAP',
 ROOM='PVCCIN_CPU0_DECAP_VR';

SECTION_NUMBER 1
 '@BASEBOARD_FAB2_LIB.BASEBOARD_FAB2(SCH_1):PAGE42_I98@DEV_DISCRETE.CAP_A(CHIPS)':
 C_PATH='@baseboard_fab2_lib.baseboard_fab2(sch_1):page42_i98@dev_discrete.cap_a~
(chips)',
 P_PATH='@baseboard_fab2_lib.baseboard_fab2(sch_1):page42_i98@dev_discrete.cap_a~
(chips)',
 PATH='I98',
 DRAWING='@BASEBOARD_FAB2_LIB.BASEBOARD_FAB2(SCH_1):PAGE42',
 TOLERANCE='20%',
 MATERIAL='X6S',
 BOM_COST='PROC_SOCKET',
 PHYS_PAGE='42',
 XY='(-3550,4500)',
 ROT='0',
 VER='1',
 VALUE='22.0UF',
 PACK_TYPE='0603V',
 PART_NUMBER='E15431-004',
 LOCATION='C5D23',
 ROOM='PVCCIN_CPU0_DECAP_VR',
 GROUP='PWR_MCP_CAP',
 CDS_LIB='dev_discrete',
 CDS_PART_NAME='CAP_A_0603V-22.0UF,4V,20%,X6S,A',
 VOLTAGE='4V',
 PRIM_FILE='./archive_libs/discrete/cap_a/chips/chips.prt';

PART_NAME
 C5D24 'CAP_A_0603V-22.0UF,4V,20%,X6S,A':
 GROUP='PWR_MLCC_CAP',
 ROOM='PVCCIN_CPU0_DECAP_VR';

SECTION_NUMBER 1
 '@BASEBOARD_FAB2_LIB.BASEBOARD_FAB2(SCH_1):PAGE42_I138@DEV_DISCRETE.CAP_A(CHIPS)':
 C_PATH='@baseboard_fab2_lib.baseboard_fab2(sch_1):page42_i138@dev_discrete.cap_~
a(chips)',
 P_PATH='@baseboard_fab2_lib.baseboard_fab2(sch_1):page42_i138@dev_discrete.cap_~
a(chips)',
 PATH='I138',
 DRAWING='@BASEBOARD_FAB2_LIB.BASEBOARD_FAB2(SCH_1):PAGE42',
 TOLERANCE='20%',
 MATERIAL='X6S',
 BOM_COST='PROC_SOCKET',
 PHYS_PAGE='42',
 XY='(-7750,4500)',
 ROT='0',
 VER='1',
 VALUE='22.0UF',
 PACK_TYPE='0603V',
 PART_NUMBER='E15431-004',
 LOCATION='C5D24',
 ROOM='PVCCIN_CPU0_DECAP_VR',
 GROUP='PWR_MLCC_CAP',
 CDS_LIB='dev_discrete',
 CDS_PART_NAME='CAP_A_0603V-22.0UF,4V,20%,X6S,A',
 VOLTAGE='4V',
 PRIM_FILE='./archive_libs/discrete/cap_a/chips/chips.prt';

PART_NAME
 C5D25 'CAP_A_0603V-22.0UF,4V,20%,X6S,A':
 GROUP='PWR_MLCC_CAP',
 ROOM='PVCCIN_CPU0_DECAP_VR';

SECTION_NUMBER 1
 '@BASEBOARD_FAB2_LIB.BASEBOARD_FAB2(SCH_1):PAGE42_I155@DEV_DISCRETE.CAP_A(CHIPS)':
 C_PATH='@baseboard_fab2_lib.baseboard_fab2(sch_1):page42_i155@dev_discrete.cap_~
a(chips)',
 P_PATH='@baseboard_fab2_lib.baseboard_fab2(sch_1):page42_i155@dev_discrete.cap_~
a(chips)',
 PATH='I155',
 DRAWING='@BASEBOARD_FAB2_LIB.BASEBOARD_FAB2(SCH_1):PAGE42',
 TOLERANCE='20%',
 MATERIAL='X6S',
 BOM_COST='PROC_SOCKET',
 PHYS_PAGE='42',
 XY='(-4600,3800)',
 ROT='0',
 VER='1',
 VALUE='22.0UF',
 PACK_TYPE='0603V',
 PART_NUMBER='E15431-004',
 LOCATION='C5D25',
 ROOM='PVCCIN_CPU0_DECAP_VR',
 GROUP='PWR_MLCC_CAP',
 CDS_LIB='dev_discrete',
 CDS_PART_NAME='CAP_A_0603V-22.0UF,4V,20%,X6S,A',
 VOLTAGE='4V',
 PRIM_FILE='./archive_libs/discrete/cap_a/chips/chips.prt';

PART_NAME
 C5D26 'CAP_A_0603V-22.0UF,4V,20%,X6S,A':
 GROUP='PWR_MLCC_CAP',
 ROOM='PVCCIN_CPU0_DECAP_VR';

SECTION_NUMBER 1
 '@BASEBOARD_FAB2_LIB.BASEBOARD_FAB2(SCH_1):PAGE42_I154@DEV_DISCRETE.CAP_A(CHIPS)':
 C_PATH='@baseboard_fab2_lib.baseboard_fab2(sch_1):page42_i154@dev_discrete.cap_~
a(chips)',
 P_PATH='@baseboard_fab2_lib.baseboard_fab2(sch_1):page42_i154@dev_discrete.cap_~
a(chips)',
 PATH='I154',
 DRAWING='@BASEBOARD_FAB2_LIB.BASEBOARD_FAB2(SCH_1):PAGE42',
 TOLERANCE='20%',
 MATERIAL='X6S',
 BOM_COST='PROC_SOCKET',
 PHYS_PAGE='42',
 XY='(-4450,4500)',
 ROT='0',
 VER='1',
 VALUE='22.0UF',
 PACK_TYPE='0603V',
 PART_NUMBER='E15431-004',
 LOCATION='C5D26',
 ROOM='PVCCIN_CPU0_DECAP_VR',
 GROUP='PWR_MLCC_CAP',
 CDS_LIB='dev_discrete',
 CDS_PART_NAME='CAP_A_0603V-22.0UF,4V,20%,X6S,A',
 VOLTAGE='4V',
 PRIM_FILE='./archive_libs/discrete/cap_a/chips/chips.prt';

PART_NAME
 C5D27 'CAP_A_0603V-22.0UF,4V,20%,X6S,A':
 GROUP='PWR_MLCC_CAP',
 ROOM='PVCCIN_CPU0_DECAP_VR';

SECTION_NUMBER 1
 '@BASEBOARD_FAB2_LIB.BASEBOARD_FAB2(SCH_1):PAGE42_I109@DEV_DISCRETE.CAP_A(CHIPS)':
 C_PATH='@baseboard_fab2_lib.baseboard_fab2(sch_1):page42_i109@dev_discrete.cap_~
a(chips)',
 P_PATH='@baseboard_fab2_lib.baseboard_fab2(sch_1):page42_i109@dev_discrete.cap_~
a(chips)',
 PATH='I109',
 DRAWING='@BASEBOARD_FAB2_LIB.BASEBOARD_FAB2(SCH_1):PAGE42',
 TOLERANCE='20%',
 MATERIAL='X6S',
 BOM_COST='PROC_SOCKET',
 PHYS_PAGE='42',
 XY='(-5000,3150)',
 ROT='0',
 VER='1',
 VALUE='22.0UF',
 PACK_TYPE='0603V',
 PART_NUMBER='E15431-004',
 LOCATION='C5D27',
 ROOM='PVCCIN_CPU0_DECAP_VR',
 GROUP='PWR_MLCC_CAP',
 CDS_LIB='dev_discrete',
 CDS_PART_NAME='CAP_A_0603V-22.0UF,4V,20%,X6S,A',
 VOLTAGE='4V',
 PRIM_FILE='./archive_libs/discrete/cap_a/chips/chips.prt';

PART_NAME
 C5D28 'CAP_A_0603V-22.0UF,4V,20%,X6S,A':
 GROUP='PWR_MLCC_CAP',
 ROOM='PVCCIN_CPU0_DECAP_VR';

SECTION_NUMBER 1
 '@BASEBOARD_FAB2_LIB.BASEBOARD_FAB2(SCH_1):PAGE42_I100@DEV_DISCRETE.CAP_A(CHIPS)':
 C_PATH='@baseboard_fab2_lib.baseboard_fab2(sch_1):page42_i100@dev_discrete.cap_~
a(chips)',
 P_PATH='@baseboard_fab2_lib.baseboard_fab2(sch_1):page42_i100@dev_discrete.cap_~
a(chips)',
 PATH='I100',
 DRAWING='@BASEBOARD_FAB2_LIB.BASEBOARD_FAB2(SCH_1):PAGE42',
 TOLERANCE='20%',
 MATERIAL='X6S',
 BOM_COST='PROC_SOCKET',
 PHYS_PAGE='42',
 XY='(-4900,3800)',
 ROT='0',
 VER='1',
 VALUE='22.0UF',
 PACK_TYPE='0603V',
 PART_NUMBER='E15431-004',
 LOCATION='C5D28',
 ROOM='PVCCIN_CPU0_DECAP_VR',
 GROUP='PWR_MLCC_CAP',
 CDS_LIB='dev_discrete',
 CDS_PART_NAME='CAP_A_0603V-22.0UF,4V,20%,X6S,A',
 VOLTAGE='4V',
 PRIM_FILE='./archive_libs/discrete/cap_a/chips/chips.prt';

PART_NAME
 C5D29 'CAP_A_0603V-22.0UF,4V,20%,X6S,A':
 GROUP='PWR_MLCC_CAP',
 ROOM='PVCCIN_CPU0_DECAP_VR';

SECTION_NUMBER 1
 '@BASEBOARD_FAB2_LIB.BASEBOARD_FAB2(SCH_1):PAGE42_I102@DEV_DISCRETE.CAP_A(CHIPS)':
 C_PATH='@baseboard_fab2_lib.baseboard_fab2(sch_1):page42_i102@dev_discrete.cap_~
a(chips)',
 P_PATH='@baseboard_fab2_lib.baseboard_fab2(sch_1):page42_i102@dev_discrete.cap_~
a(chips)',
 PATH='I102',
 DRAWING='@BASEBOARD_FAB2_LIB.BASEBOARD_FAB2(SCH_1):PAGE42',
 TOLERANCE='20%',
 MATERIAL='X6S',
 BOM_COST='PROC_SOCKET',
 PHYS_PAGE='42',
 XY='(-4750,4500)',
 ROT='0',
 VER='1',
 VALUE='22.0UF',
 PACK_TYPE='0603V',
 PART_NUMBER='E15431-004',
 LOCATION='C5D29',
 ROOM='PVCCIN_CPU0_DECAP_VR',
 GROUP='PWR_MLCC_CAP',
 CDS_LIB='dev_discrete',
 CDS_PART_NAME='CAP_A_0603V-22.0UF,4V,20%,X6S,A',
 VOLTAGE='4V',
 PRIM_FILE='./archive_libs/discrete/cap_a/chips/chips.prt';

PART_NAME
 C5D30 'CAP_A_0603V-22.0UF,4V,20%,X6S,A':
 GROUP='PWR_MLCC_CAP',
 ROOM='PVCCIN_CPU0_DECAP_VR';

SECTION_NUMBER 1
 '@BASEBOARD_FAB2_LIB.BASEBOARD_FAB2(SCH_1):PAGE42_I111@DEV_DISCRETE.CAP_A(CHIPS)':
 C_PATH='@baseboard_fab2_lib.baseboard_fab2(sch_1):page42_i111@dev_discrete.cap_~
a(chips)',
 P_PATH='@baseboard_fab2_lib.baseboard_fab2(sch_1):page42_i111@dev_discrete.cap_~
a(chips)',
 PATH='I111',
 DRAWING='@BASEBOARD_FAB2_LIB.BASEBOARD_FAB2(SCH_1):PAGE42',
 TOLERANCE='20%',
 MATERIAL='X6S',
 BOM_COST='PROC_SOCKET',
 PHYS_PAGE='42',
 XY='(-5300,3150)',
 ROT='0',
 VER='1',
 VALUE='22.0UF',
 PACK_TYPE='0603V',
 PART_NUMBER='E15431-004',
 LOCATION='C5D30',
 ROOM='PVCCIN_CPU0_DECAP_VR',
 GROUP='PWR_MLCC_CAP',
 CDS_LIB='dev_discrete',
 CDS_PART_NAME='CAP_A_0603V-22.0UF,4V,20%,X6S,A',
 VOLTAGE='4V',
 PRIM_FILE='./archive_libs/discrete/cap_a/chips/chips.prt';

PART_NAME
 C5D31 'CAP_A_0603V-22.0UF,4V,20%,X6S,A':
 GROUP='PWR_MLCC_CAP',
 ROOM='PVCCIN_CPU0_DECAP_VR';

SECTION_NUMBER 1
 '@BASEBOARD_FAB2_LIB.BASEBOARD_FAB2(SCH_1):PAGE42_I106@DEV_DISCRETE.CAP_A(CHIPS)':
 C_PATH='@baseboard_fab2_lib.baseboard_fab2(sch_1):page42_i106@dev_discrete.cap_~
a(chips)',
 P_PATH='@baseboard_fab2_lib.baseboard_fab2(sch_1):page42_i106@dev_discrete.cap_~
a(chips)',
 PATH='I106',
 DRAWING='@BASEBOARD_FAB2_LIB.BASEBOARD_FAB2(SCH_1):PAGE42',
 TOLERANCE='20%',
 MATERIAL='X6S',
 BOM_COST='PROC_SOCKET',
 PHYS_PAGE='42',
 XY='(-5200,3800)',
 ROT='0',
 VER='1',
 VALUE='22.0UF',
 PACK_TYPE='0603V',
 PART_NUMBER='E15431-004',
 LOCATION='C5D31',
 ROOM='PVCCIN_CPU0_DECAP_VR',
 GROUP='PWR_MLCC_CAP',
 CDS_LIB='dev_discrete',
 CDS_PART_NAME='CAP_A_0603V-22.0UF,4V,20%,X6S,A',
 VOLTAGE='4V',
 PRIM_FILE='./archive_libs/discrete/cap_a/chips/chips.prt';

PART_NAME
 C5D32 'CAP_A_0603V-22.0UF,4V,20%,X6S,A':
 GROUP='PWR_MLCC_CAP',
 ROOM='PVCCIN_CPU0_DECAP_VR';

SECTION_NUMBER 1
 '@BASEBOARD_FAB2_LIB.BASEBOARD_FAB2(SCH_1):PAGE42_I103@DEV_DISCRETE.CAP_A(CHIPS)':
 C_PATH='@baseboard_fab2_lib.baseboard_fab2(sch_1):page42_i103@dev_discrete.cap_~
a(chips)',
 P_PATH='@baseboard_fab2_lib.baseboard_fab2(sch_1):page42_i103@dev_discrete.cap_~
a(chips)',
 PATH='I103',
 DRAWING='@BASEBOARD_FAB2_LIB.BASEBOARD_FAB2(SCH_1):PAGE42',
 TOLERANCE='20%',
 MATERIAL='X6S',
 BOM_COST='PROC_SOCKET',
 PHYS_PAGE='42',
 XY='(-5050,4500)',
 ROT='0',
 VER='1',
 VALUE='22.0UF',
 PACK_TYPE='0603V',
 PART_NUMBER='E15431-004',
 LOCATION='C5D32',
 ROOM='PVCCIN_CPU0_DECAP_VR',
 GROUP='PWR_MLCC_CAP',
 CDS_LIB='dev_discrete',
 CDS_PART_NAME='CAP_A_0603V-22.0UF,4V,20%,X6S,A',
 VOLTAGE='4V',
 PRIM_FILE='./archive_libs/discrete/cap_a/chips/chips.prt';

PART_NAME
 C5D33 'CAP_A_0603V-22.0UF,4V,20%,X6S,A':
 GROUP='PWR_MCP_CAP',
 ROOM='PVCCIN_CPU0_DECAP_VR';

SECTION_NUMBER 1
 '@BASEBOARD_FAB2_LIB.BASEBOARD_FAB2(SCH_1):PAGE42_I174@DEV_DISCRETE.CAP_A(CHIPS)':
 C_PATH='@baseboard_fab2_lib.baseboard_fab2(sch_1):page42_i174@dev_discrete.cap_~
a(chips)',
 P_PATH='@baseboard_fab2_lib.baseboard_fab2(sch_1):page42_i174@dev_discrete.cap_~
a(chips)',
 PATH='I174',
 DRAWING='@BASEBOARD_FAB2_LIB.BASEBOARD_FAB2(SCH_1):PAGE42',
 TOLERANCE='20%',
 MATERIAL='X6S',
 BOM_COST='PROC_SOCKET',
 PHYS_PAGE='42',
 XY='(-800,3850)',
 ROT='0',
 VER='1',
 VALUE='22.0UF',
 PACK_TYPE='0603V',
 PART_NUMBER='E15431-004',
 LOCATION='C5D33',
 ROOM='PVCCIN_CPU0_DECAP_VR',
 GROUP='PWR_MCP_CAP',
 CDS_LIB='dev_discrete',
 CDS_PART_NAME='CAP_A_0603V-22.0UF,4V,20%,X6S,A',
 VOLTAGE='4V',
 PRIM_FILE='./archive_libs/discrete/cap_a/chips/chips.prt';

PART_NAME
 C5D34 'CAP_A_0603V-22.0UF,4V,20%,X6S,A':
 GROUP='PWR_MCP_CAP',
 ROOM='PVCCIN_CPU0_DECAP_VR';

SECTION_NUMBER 1
 '@BASEBOARD_FAB2_LIB.BASEBOARD_FAB2(SCH_1):PAGE42_I175@DEV_DISCRETE.CAP_A(CHIPS)':
 C_PATH='@baseboard_fab2_lib.baseboard_fab2(sch_1):page42_i175@dev_discrete.cap_~
a(chips)',
 P_PATH='@baseboard_fab2_lib.baseboard_fab2(sch_1):page42_i175@dev_discrete.cap_~
a(chips)',
 PATH='I175',
 DRAWING='@BASEBOARD_FAB2_LIB.BASEBOARD_FAB2(SCH_1):PAGE42',
 TOLERANCE='20%',
 MATERIAL='X6S',
 BOM_COST='PROC_SOCKET',
 PHYS_PAGE='42',
 XY='(-550,3850)',
 ROT='0',
 VER='1',
 VALUE='22.0UF',
 PACK_TYPE='0603V',
 PART_NUMBER='E15431-004',
 LOCATION='C5D34',
 ROOM='PVCCIN_CPU0_DECAP_VR',
 GROUP='PWR_MCP_CAP',
 CDS_LIB='dev_discrete',
 CDS_PART_NAME='CAP_A_0603V-22.0UF,4V,20%,X6S,A',
 VOLTAGE='4V',
 PRIM_FILE='./archive_libs/discrete/cap_a/chips/chips.prt';

PART_NAME
 C5D35 'CAP_A_0603V-22.0UF,4V,20%,X6S,A':
 GROUP='PWR_MCP_CAP',
 ROOM='PVCCIN_CPU0_DECAP_VR';

SECTION_NUMBER 1
 '@BASEBOARD_FAB2_LIB.BASEBOARD_FAB2(SCH_1):PAGE42_I176@DEV_DISCRETE.CAP_A(CHIPS)':
 C_PATH='@baseboard_fab2_lib.baseboard_fab2(sch_1):page42_i176@dev_discrete.cap_~
a(chips)',
 P_PATH='@baseboard_fab2_lib.baseboard_fab2(sch_1):page42_i176@dev_discrete.cap_~
a(chips)',
 PATH='I176',
 DRAWING='@BASEBOARD_FAB2_LIB.BASEBOARD_FAB2(SCH_1):PAGE42',
 TOLERANCE='20%',
 MATERIAL='X6S',
 BOM_COST='PROC_SOCKET',
 PHYS_PAGE='42',
 XY='(-1300,3850)',
 ROT='0',
 VER='1',
 VALUE='22.0UF',
 PACK_TYPE='0603V',
 PART_NUMBER='E15431-004',
 LOCATION='C5D35',
 ROOM='PVCCIN_CPU0_DECAP_VR',
 GROUP='PWR_MCP_CAP',
 CDS_LIB='dev_discrete',
 CDS_PART_NAME='CAP_A_0603V-22.0UF,4V,20%,X6S,A',
 VOLTAGE='4V',
 PRIM_FILE='./archive_libs/discrete/cap_a/chips/chips.prt';

PART_NAME
 C5D36 'CAP_A_0603V-22.0UF,4V,20%,X6S,A':
 GROUP='PWR_MCP_CAP',
 ROOM='PVCCIN_CPU0_DECAP_VR';

SECTION_NUMBER 1
 '@BASEBOARD_FAB2_LIB.BASEBOARD_FAB2(SCH_1):PAGE42_I151@DEV_DISCRETE.CAP_A(CHIPS)':
 C_PATH='@baseboard_fab2_lib.baseboard_fab2(sch_1):page42_i151@dev_discrete.cap_~
a(chips)',
 P_PATH='@baseboard_fab2_lib.baseboard_fab2(sch_1):page42_i151@dev_discrete.cap_~
a(chips)',
 PATH='I151',
 DRAWING='@BASEBOARD_FAB2_LIB.BASEBOARD_FAB2(SCH_1):PAGE42',
 TOLERANCE='20%',
 MATERIAL='X6S',
 BOM_COST='PROC_SOCKET',
 PHYS_PAGE='42',
 XY='(-2300,4500)',
 ROT='0',
 VER='1',
 VALUE='22.0UF',
 PACK_TYPE='0603V',
 PART_NUMBER='E15431-004',
 LOCATION='C5D36',
 ROOM='PVCCIN_CPU0_DECAP_VR',
 GROUP='PWR_MCP_CAP',
 CDS_LIB='dev_discrete',
 CDS_PART_NAME='CAP_A_0603V-22.0UF,4V,20%,X6S,A',
 VOLTAGE='4V',
 PRIM_FILE='./archive_libs/discrete/cap_a/chips/chips.prt';

PART_NAME
 C5D37 'CAP_A_0603V-22.0UF,4V,20%,X6S,A':
 GROUP='PWR_MCP_CAP',
 ROOM='PVCCIN_CPU0_DECAP_VR';

SECTION_NUMBER 1
 '@BASEBOARD_FAB2_LIB.BASEBOARD_FAB2(SCH_1):PAGE42_I70@DEV_DISCRETE.CAP_A(CHIPS)':
 C_PATH='@baseboard_fab2_lib.baseboard_fab2(sch_1):page42_i70@dev_discrete.cap_a~
(chips)',
 P_PATH='@baseboard_fab2_lib.baseboard_fab2(sch_1):page42_i70@dev_discrete.cap_a~
(chips)',
 PATH='I70',
 DRAWING='@BASEBOARD_FAB2_LIB.BASEBOARD_FAB2(SCH_1):PAGE42',
 TOLERANCE='20%',
 MATERIAL='X6S',
 BOM_COST='PROC_SOCKET',
 PHYS_PAGE='42',
 XY='(-1300,4500)',
 ROT='0',
 VER='1',
 VALUE='22.0UF',
 PACK_TYPE='0603V',
 PART_NUMBER='E15431-004',
 LOCATION='C5D37',
 ROOM='PVCCIN_CPU0_DECAP_VR',
 GROUP='PWR_MCP_CAP',
 CDS_LIB='dev_discrete',
 CDS_PART_NAME='CAP_A_0603V-22.0UF,4V,20%,X6S,A',
 VOLTAGE='4V',
 PRIM_FILE='./archive_libs/discrete/cap_a/chips/chips.prt';

PART_NAME
 C5D38 'CAP_A_0603V-22.0UF,4V,20%,X6S,A':
 GROUP='PWR_MCP_CAP',
 ROOM='PVCCIN_CPU0_DECAP_VR';

SECTION_NUMBER 1
 '@BASEBOARD_FAB2_LIB.BASEBOARD_FAB2(SCH_1):PAGE42_I69@DEV_DISCRETE.CAP_A(CHIPS)':
 C_PATH='@baseboard_fab2_lib.baseboard_fab2(sch_1):page42_i69@dev_discrete.cap_a~
(chips)',
 P_PATH='@baseboard_fab2_lib.baseboard_fab2(sch_1):page42_i69@dev_discrete.cap_a~
(chips)',
 PATH='I69',
 DRAWING='@BASEBOARD_FAB2_LIB.BASEBOARD_FAB2(SCH_1):PAGE42',
 TOLERANCE='20%',
 MATERIAL='X6S',
 BOM_COST='PROC_SOCKET',
 PHYS_PAGE='42',
 XY='(-1050,4500)',
 ROT='0',
 VER='1',
 VALUE='22.0UF',
 PACK_TYPE='0603V',
 PART_NUMBER='E15431-004',
 LOCATION='C5D38',
 ROOM='PVCCIN_CPU0_DECAP_VR',
 GROUP='PWR_MCP_CAP',
 CDS_LIB='dev_discrete',
 CDS_PART_NAME='CAP_A_0603V-22.0UF,4V,20%,X6S,A',
 VOLTAGE='4V',
 PRIM_FILE='./archive_libs/discrete/cap_a/chips/chips.prt';

PART_NAME
 C5D39 'CAP_A_0603V-22.0UF,4V,20%,X6S,A':
 GROUP='PWR_MLCC_CAP',
 ROOM='PVCCIN_CPU0_DECAP_VR';

SECTION_NUMBER 1
 '@BASEBOARD_FAB2_LIB.BASEBOARD_FAB2(SCH_1):PAGE42_I140@DEV_DISCRETE.CAP_A(CHIPS)':
 C_PATH='@baseboard_fab2_lib.baseboard_fab2(sch_1):page42_i140@dev_discrete.cap_~
a(chips)',
 P_PATH='@baseboard_fab2_lib.baseboard_fab2(sch_1):page42_i140@dev_discrete.cap_~
a(chips)',
 PATH='I140',
 DRAWING='@BASEBOARD_FAB2_LIB.BASEBOARD_FAB2(SCH_1):PAGE42',
 TOLERANCE='20%',
 MATERIAL='X6S',
 BOM_COST='PROC_SOCKET',
 PHYS_PAGE='42',
 XY='(-7750,3800)',
 ROT='0',
 VER='1',
 VALUE='22.0UF',
 PACK_TYPE='0603V',
 PART_NUMBER='E15431-004',
 LOCATION='C5D39',
 ROOM='PVCCIN_CPU0_DECAP_VR',
 GROUP='PWR_MLCC_CAP',
 CDS_LIB='dev_discrete',
 CDS_PART_NAME='CAP_A_0603V-22.0UF,4V,20%,X6S,A',
 VOLTAGE='4V',
 PRIM_FILE='./archive_libs/discrete/cap_a/chips/chips.prt';

PART_NAME
 C5D40 'CAP_A_0603V-22.0UF,4V,20%,X6S,A':
 GROUP='PWR_MLCC_CAP',
 ROOM='PVCCIN_CPU0_DECAP_VR';

SECTION_NUMBER 1
 '@BASEBOARD_FAB2_LIB.BASEBOARD_FAB2(SCH_1):PAGE42_I115@DEV_DISCRETE.CAP_A(CHIPS)':
 C_PATH='@baseboard_fab2_lib.baseboard_fab2(sch_1):page42_i115@dev_discrete.cap_~
a(chips)',
 P_PATH='@baseboard_fab2_lib.baseboard_fab2(sch_1):page42_i115@dev_discrete.cap_~
a(chips)',
 PATH='I115',
 DRAWING='@BASEBOARD_FAB2_LIB.BASEBOARD_FAB2(SCH_1):PAGE42',
 TOLERANCE='20%',
 MATERIAL='X6S',
 BOM_COST='PROC_SOCKET',
 PHYS_PAGE='42',
 XY='(-5650,4500)',
 ROT='0',
 VER='1',
 VALUE='22.0UF',
 PACK_TYPE='0603V',
 PART_NUMBER='E15431-004',
 LOCATION='C5D40',
 ROOM='PVCCIN_CPU0_DECAP_VR',
 GROUP='PWR_MLCC_CAP',
 CDS_LIB='dev_discrete',
 CDS_PART_NAME='CAP_A_0603V-22.0UF,4V,20%,X6S,A',
 VOLTAGE='4V',
 PRIM_FILE='./archive_libs/discrete/cap_a/chips/chips.prt';

PART_NAME
 C5D41 'CAP_A_0603V-22.0UF,4V,20%,X6S,A':
 GROUP='PWR_MLCC_CAP',
 ROOM='PVCCIN_CPU0_DECAP_VR';

SECTION_NUMBER 1
 '@BASEBOARD_FAB2_LIB.BASEBOARD_FAB2(SCH_1):PAGE42_I114@DEV_DISCRETE.CAP_A(CHIPS)':
 C_PATH='@baseboard_fab2_lib.baseboard_fab2(sch_1):page42_i114@dev_discrete.cap_~
a(chips)',
 P_PATH='@baseboard_fab2_lib.baseboard_fab2(sch_1):page42_i114@dev_discrete.cap_~
a(chips)',
 PATH='I114',
 DRAWING='@BASEBOARD_FAB2_LIB.BASEBOARD_FAB2(SCH_1):PAGE42',
 TOLERANCE='20%',
 MATERIAL='X6S',
 BOM_COST='PROC_SOCKET',
 PHYS_PAGE='42',
 XY='(-5800,3800)',
 ROT='0',
 VER='1',
 VALUE='22.0UF',
 PACK_TYPE='0603V',
 PART_NUMBER='E15431-004',
 LOCATION='C5D41',
 ROOM='PVCCIN_CPU0_DECAP_VR',
 GROUP='PWR_MLCC_CAP',
 CDS_LIB='dev_discrete',
 CDS_PART_NAME='CAP_A_0603V-22.0UF,4V,20%,X6S,A',
 VOLTAGE='4V',
 PRIM_FILE='./archive_libs/discrete/cap_a/chips/chips.prt';

PART_NAME
 C5D42 'CAP_A_0603V-22.0UF,4V,20%,X6S,A':
 GROUP='PWR_MLCC_CAP',
 ROOM='PVCCIN_CPU0_DECAP_VR';

SECTION_NUMBER 1
 '@BASEBOARD_FAB2_LIB.BASEBOARD_FAB2(SCH_1):PAGE42_I135@DEV_DISCRETE.CAP_A(CHIPS)':
 C_PATH='@baseboard_fab2_lib.baseboard_fab2(sch_1):page42_i135@dev_discrete.cap_~
a(chips)',
 P_PATH='@baseboard_fab2_lib.baseboard_fab2(sch_1):page42_i135@dev_discrete.cap_~
a(chips)',
 PATH='I135',
 DRAWING='@BASEBOARD_FAB2_LIB.BASEBOARD_FAB2(SCH_1):PAGE42',
 TOLERANCE='20%',
 MATERIAL='X6S',
 BOM_COST='PROC_SOCKET',
 PHYS_PAGE='42',
 XY='(-7250,3100)',
 ROT='0',
 VER='1',
 VALUE='22.0UF',
 PACK_TYPE='0603V',
 PART_NUMBER='E15431-004',
 LOCATION='C5D42',
 ROOM='PVCCIN_CPU0_DECAP_VR',
 GROUP='PWR_MLCC_CAP',
 CDS_LIB='dev_discrete',
 CDS_PART_NAME='CAP_A_0603V-22.0UF,4V,20%,X6S,A',
 VOLTAGE='4V',
 PRIM_FILE='./archive_libs/discrete/cap_a/chips/chips.prt';

PART_NAME
 C5D43 'CAP_A_0603V-22.0UF,4V,20%,X6S,A':
 GROUP='PWR_MLCC_CAP',
 ROOM='PVCCIN_CPU0_DECAP_VR';

SECTION_NUMBER 1
 '@BASEBOARD_FAB2_LIB.BASEBOARD_FAB2(SCH_1):PAGE42_I131@DEV_DISCRETE.CAP_A(CHIPS)':
 C_PATH='@baseboard_fab2_lib.baseboard_fab2(sch_1):page42_i131@dev_discrete.cap_~
a(chips)',
 P_PATH='@baseboard_fab2_lib.baseboard_fab2(sch_1):page42_i131@dev_discrete.cap_~
a(chips)',
 PATH='I131',
 DRAWING='@BASEBOARD_FAB2_LIB.BASEBOARD_FAB2(SCH_1):PAGE42',
 TOLERANCE='20%',
 MATERIAL='X6S',
 BOM_COST='PROC_SOCKET',
 PHYS_PAGE='42',
 XY='(-5950,3150)',
 ROT='0',
 VER='1',
 VALUE='22.0UF',
 PACK_TYPE='0603V',
 PART_NUMBER='E15431-004',
 LOCATION='C5D43',
 ROOM='PVCCIN_CPU0_DECAP_VR',
 GROUP='PWR_MLCC_CAP',
 CDS_LIB='dev_discrete',
 CDS_PART_NAME='CAP_A_0603V-22.0UF,4V,20%,X6S,A',
 VOLTAGE='4V',
 PRIM_FILE='./archive_libs/discrete/cap_a/chips/chips.prt';

PART_NAME
 C5D44 'CAP_A_0603V-22.0UF,4V,20%,X6S,A':
 GROUP='PWR_MLCC_CAP',
 ROOM='PVCCIN_CPU0_DECAP_VR';

SECTION_NUMBER 1
 '@BASEBOARD_FAB2_LIB.BASEBOARD_FAB2(SCH_1):PAGE42_I142@DEV_DISCRETE.CAP_A(CHIPS)':
 C_PATH='@baseboard_fab2_lib.baseboard_fab2(sch_1):page42_i142@dev_discrete.cap_~
a(chips)',
 P_PATH='@baseboard_fab2_lib.baseboard_fab2(sch_1):page42_i142@dev_discrete.cap_~
a(chips)',
 PATH='I142',
 DRAWING='@BASEBOARD_FAB2_LIB.BASEBOARD_FAB2(SCH_1):PAGE42',
 TOLERANCE='20%',
 MATERIAL='X6S',
 BOM_COST='PROC_SOCKET',
 PHYS_PAGE='42',
 XY='(-7750,3100)',
 ROT='0',
 VER='1',
 VALUE='22.0UF',
 PACK_TYPE='0603V',
 PART_NUMBER='E15431-004',
 LOCATION='C5D44',
 ROOM='PVCCIN_CPU0_DECAP_VR',
 GROUP='PWR_MLCC_CAP',
 CDS_LIB='dev_discrete',
 CDS_PART_NAME='CAP_A_0603V-22.0UF,4V,20%,X6S,A',
 VOLTAGE='4V',
 PRIM_FILE='./archive_libs/discrete/cap_a/chips/chips.prt';

PART_NAME
 C5D45 'CAP_A_0603V-22.0UF,4V,20%,X6S,A':
 GROUP='PWR_MLCC_CAP',
 ROOM='PVCCIN_CPU0_DECAP_VR';

SECTION_NUMBER 1
 '@BASEBOARD_FAB2_LIB.BASEBOARD_FAB2(SCH_1):PAGE42_I156@DEV_DISCRETE.CAP_A(CHIPS)':
 C_PATH='@baseboard_fab2_lib.baseboard_fab2(sch_1):page42_i156@dev_discrete.cap_~
a(chips)',
 P_PATH='@baseboard_fab2_lib.baseboard_fab2(sch_1):page42_i156@dev_discrete.cap_~
a(chips)',
 PATH='I156',
 DRAWING='@BASEBOARD_FAB2_LIB.BASEBOARD_FAB2(SCH_1):PAGE42',
 TOLERANCE='20%',
 MATERIAL='X6S',
 BOM_COST='PROC_SOCKET',
 PHYS_PAGE='42',
 XY='(-4700,3150)',
 ROT='0',
 VER='1',
 VALUE='22.0UF',
 PACK_TYPE='0603V',
 PART_NUMBER='E15431-004',
 LOCATION='C5D45',
 ROOM='PVCCIN_CPU0_DECAP_VR',
 GROUP='PWR_MLCC_CAP',
 CDS_LIB='dev_discrete',
 CDS_PART_NAME='CAP_A_0603V-22.0UF,4V,20%,X6S,A',
 VOLTAGE='4V',
 PRIM_FILE='./archive_libs/discrete/cap_a/chips/chips.prt';

PART_NAME
 C5D46 'CAP_A_0603V-22.0UF,4V,20%,X6S,A':
 GROUP='PWR_MLCC_CAP',
 ROOM='PVCCIN_CPU0_DECAP_VR';

SECTION_NUMBER 1
 '@BASEBOARD_FAB2_LIB.BASEBOARD_FAB2(SCH_1):PAGE42_I107@DEV_DISCRETE.CAP_A(CHIPS)':
 C_PATH='@baseboard_fab2_lib.baseboard_fab2(sch_1):page42_i107@dev_discrete.cap_~
a(chips)',
 P_PATH='@baseboard_fab2_lib.baseboard_fab2(sch_1):page42_i107@dev_discrete.cap_~
a(chips)',
 PATH='I107',
 DRAWING='@BASEBOARD_FAB2_LIB.BASEBOARD_FAB2(SCH_1):PAGE42',
 TOLERANCE='20%',
 MATERIAL='X6S',
 BOM_COST='PROC_SOCKET',
 PHYS_PAGE='42',
 XY='(-5500,3800)',
 ROT='0',
 VER='1',
 VALUE='22.0UF',
 PACK_TYPE='0603V',
 PART_NUMBER='E15431-004',
 LOCATION='C5D46',
 ROOM='PVCCIN_CPU0_DECAP_VR',
 GROUP='PWR_MLCC_CAP',
 CDS_LIB='dev_discrete',
 CDS_PART_NAME='CAP_A_0603V-22.0UF,4V,20%,X6S,A',
 VOLTAGE='4V',
 PRIM_FILE='./archive_libs/discrete/cap_a/chips/chips.prt';

PART_NAME
 C5D47 'CAP_A_0603V-22.0UF,4V,20%,X6S,A':
 GROUP='PWR_MLCC_CAP',
 ROOM='PVCCIN_CPU0_DECAP_VR';

SECTION_NUMBER 1
 '@BASEBOARD_FAB2_LIB.BASEBOARD_FAB2(SCH_1):PAGE42_I104@DEV_DISCRETE.CAP_A(CHIPS)':
 C_PATH='@baseboard_fab2_lib.baseboard_fab2(sch_1):page42_i104@dev_discrete.cap_~
a(chips)',
 P_PATH='@baseboard_fab2_lib.baseboard_fab2(sch_1):page42_i104@dev_discrete.cap_~
a(chips)',
 PATH='I104',
 DRAWING='@BASEBOARD_FAB2_LIB.BASEBOARD_FAB2(SCH_1):PAGE42',
 TOLERANCE='20%',
 MATERIAL='X6S',
 BOM_COST='PROC_SOCKET',
 PHYS_PAGE='42',
 XY='(-5350,4500)',
 ROT='0',
 VER='1',
 VALUE='22.0UF',
 PACK_TYPE='0603V',
 PART_NUMBER='E15431-004',
 LOCATION='C5D47',
 ROOM='PVCCIN_CPU0_DECAP_VR',
 GROUP='PWR_MLCC_CAP',
 CDS_LIB='dev_discrete',
 CDS_PART_NAME='CAP_A_0603V-22.0UF,4V,20%,X6S,A',
 VOLTAGE='4V',
 PRIM_FILE='./archive_libs/discrete/cap_a/chips/chips.prt';

PART_NAME
 C5D48 'CAP_A_0603V-22.0UF,4V,20%,X6S,A':
 GROUP='PWR_MCP_CAP',
 ROOM='PVCCIN_CPU0_DECAP_VR';

SECTION_NUMBER 1
 '@BASEBOARD_FAB2_LIB.BASEBOARD_FAB2(SCH_1):PAGE42_I90@DEV_DISCRETE.CAP_A(CHIPS)':
 C_PATH='@baseboard_fab2_lib.baseboard_fab2(sch_1):page42_i90@dev_discrete.cap_a~
(chips)',
 P_PATH='@baseboard_fab2_lib.baseboard_fab2(sch_1):page42_i90@dev_discrete.cap_a~
(chips)',
 PATH='I90',
 DRAWING='@BASEBOARD_FAB2_LIB.BASEBOARD_FAB2(SCH_1):PAGE42',
 TOLERANCE='20%',
 MATERIAL='X6S',
 BOM_COST='PROC_SOCKET',
 PHYS_PAGE='42',
 XY='(-3300,4500)',
 ROT='0',
 VER='1',
 VALUE='22.0UF',
 PACK_TYPE='0603V',
 PART_NUMBER='E15431-004',
 LOCATION='C5D48',
 ROOM='PVCCIN_CPU0_DECAP_VR',
 GROUP='PWR_MCP_CAP',
 CDS_LIB='dev_discrete',
 CDS_PART_NAME='CAP_A_0603V-22.0UF,4V,20%,X6S,A',
 VOLTAGE='4V',
 PRIM_FILE='./archive_libs/discrete/cap_a/chips/chips.prt';

PART_NAME
 C5D49 'CAP_A_0603V-22.0UF,4V,20%,X6S,A':
 GROUP='PWR_MCP_CAP',
 ROOM='PVCCIN_CPU0_DECAP_VR';

SECTION_NUMBER 1
 '@BASEBOARD_FAB2_LIB.BASEBOARD_FAB2(SCH_1):PAGE42_I152@DEV_DISCRETE.CAP_A(CHIPS)':
 C_PATH='@baseboard_fab2_lib.baseboard_fab2(sch_1):page42_i152@dev_discrete.cap_~
a(chips)',
 P_PATH='@baseboard_fab2_lib.baseboard_fab2(sch_1):page42_i152@dev_discrete.cap_~
a(chips)',
 PATH='I152',
 DRAWING='@BASEBOARD_FAB2_LIB.BASEBOARD_FAB2(SCH_1):PAGE42',
 TOLERANCE='20%',
 MATERIAL='X6S',
 BOM_COST='PROC_SOCKET',
 PHYS_PAGE='42',
 XY='(-2050,4500)',
 ROT='0',
 VER='1',
 VALUE='22.0UF',
 PACK_TYPE='0603V',
 PART_NUMBER='E15431-004',
 LOCATION='C5D49',
 ROOM='PVCCIN_CPU0_DECAP_VR',
 GROUP='PWR_MCP_CAP',
 CDS_LIB='dev_discrete',
 CDS_PART_NAME='CAP_A_0603V-22.0UF,4V,20%,X6S,A',
 VOLTAGE='4V',
 PRIM_FILE='./archive_libs/discrete/cap_a/chips/chips.prt';

PART_NAME
 C5D50 'CAP_A_0603V-22.0UF,4V,20%,X6S,A':
 GROUP='PWR_MCP_CAP',
 ROOM='PVCCIN_CPU0_DECAP_VR';

SECTION_NUMBER 1
 '@BASEBOARD_FAB2_LIB.BASEBOARD_FAB2(SCH_1):PAGE42_I89@DEV_DISCRETE.CAP_A(CHIPS)':
 C_PATH='@baseboard_fab2_lib.baseboard_fab2(sch_1):page42_i89@dev_discrete.cap_a~
(chips)',
 P_PATH='@baseboard_fab2_lib.baseboard_fab2(sch_1):page42_i89@dev_discrete.cap_a~
(chips)',
 PATH='I89',
 DRAWING='@BASEBOARD_FAB2_LIB.BASEBOARD_FAB2(SCH_1):PAGE42',
 TOLERANCE='20%',
 MATERIAL='X6S',
 BOM_COST='PROC_SOCKET',
 PHYS_PAGE='42',
 XY='(-3050,4500)',
 ROT='0',
 VER='1',
 VALUE='22.0UF',
 PACK_TYPE='0603V',
 PART_NUMBER='E15431-004',
 LOCATION='C5D50',
 ROOM='PVCCIN_CPU0_DECAP_VR',
 GROUP='PWR_MCP_CAP',
 CDS_LIB='dev_discrete',
 CDS_PART_NAME='CAP_A_0603V-22.0UF,4V,20%,X6S,A',
 VOLTAGE='4V',
 PRIM_FILE='./archive_libs/discrete/cap_a/chips/chips.prt';

PART_NAME
 C5D51 'CAP_A_0603V-22.0UF,4V,20%,X6S,A':
 GROUP='PWR_MCP_CAP',
 ROOM='PVCCIN_CPU0_DECAP_VR';

SECTION_NUMBER 1
 '@BASEBOARD_FAB2_LIB.BASEBOARD_FAB2(SCH_1):PAGE42_I83@DEV_DISCRETE.CAP_A(CHIPS)':
 C_PATH='@baseboard_fab2_lib.baseboard_fab2(sch_1):page42_i83@dev_discrete.cap_a~
(chips)',
 P_PATH='@baseboard_fab2_lib.baseboard_fab2(sch_1):page42_i83@dev_discrete.cap_a~
(chips)',
 PATH='I83',
 DRAWING='@BASEBOARD_FAB2_LIB.BASEBOARD_FAB2(SCH_1):PAGE42',
 TOLERANCE='20%',
 MATERIAL='X6S',
 BOM_COST='PROC_SOCKET',
 PHYS_PAGE='42',
 XY='(-2550,4500)',
 ROT='0',
 VER='1',
 VALUE='22.0UF',
 PACK_TYPE='0603V',
 PART_NUMBER='E15431-004',
 LOCATION='C5D51',
 ROOM='PVCCIN_CPU0_DECAP_VR',
 GROUP='PWR_MCP_CAP',
 CDS_LIB='dev_discrete',
 CDS_PART_NAME='CAP_A_0603V-22.0UF,4V,20%,X6S,A',
 VOLTAGE='4V',
 PRIM_FILE='./archive_libs/discrete/cap_a/chips/chips.prt';

PART_NAME
 C5D52 'CAP_A_0603V-22.0UF,4V,20%,X6S,A':
 GROUP='PWR_MCP_CAP',
 ROOM='PVCCIN_CPU0_DECAP_VR';

SECTION_NUMBER 1
 '@BASEBOARD_FAB2_LIB.BASEBOARD_FAB2(SCH_1):PAGE42_I180@DEV_DISCRETE.CAP_A(CHIPS)':
 C_PATH='@baseboard_fab2_lib.baseboard_fab2(sch_1):page42_i180@dev_discrete.cap_~
a(chips)',
 P_PATH='@baseboard_fab2_lib.baseboard_fab2(sch_1):page42_i180@dev_discrete.cap_~
a(chips)',
 PATH='I180',
 DRAWING='@BASEBOARD_FAB2_LIB.BASEBOARD_FAB2(SCH_1):PAGE42',
 TOLERANCE='20%',
 MATERIAL='X6S',
 PHYS_PAGE='42',
 XY='(-1800,3850)',
 ROT='0',
 VER='1',
 VALUE='22.0UF',
 PACK_TYPE='0603V',
 PART_NUMBER='E15431-004',
 LOCATION='C5D52',
 ROOM='PVCCIN_CPU0_DECAP_VR',
 GROUP='PWR_MCP_CAP',
 CDS_LIB='dev_discrete',
 CDS_PART_NAME='CAP_A_0603V-22.0UF,4V,20%,X6S,A',
 VOLTAGE='4V',
 PRIM_FILE='./archive_libs/discrete/cap_a/chips/chips.prt';

PART_NAME
 C5D53 'CAP_A_0603V-22.0UF,4V,20%,X6S,A':
 GROUP='PWR_MCP_CAP',
 ROOM='PVCCIN_CPU0_DECAP_VR';

SECTION_NUMBER 1
 '@BASEBOARD_FAB2_LIB.BASEBOARD_FAB2(SCH_1):PAGE42_I179@DEV_DISCRETE.CAP_A(CHIPS)':
 C_PATH='@baseboard_fab2_lib.baseboard_fab2(sch_1):page42_i179@dev_discrete.cap_~
a(chips)',
 P_PATH='@baseboard_fab2_lib.baseboard_fab2(sch_1):page42_i179@dev_discrete.cap_~
a(chips)',
 PATH='I179',
 DRAWING='@BASEBOARD_FAB2_LIB.BASEBOARD_FAB2(SCH_1):PAGE42',
 TOLERANCE='20%',
 MATERIAL='X6S',
 PHYS_PAGE='42',
 XY='(-1550,3850)',
 ROT='0',
 VER='1',
 VALUE='22.0UF',
 PACK_TYPE='0603V',
 PART_NUMBER='E15431-004',
 LOCATION='C5D53',
 ROOM='PVCCIN_CPU0_DECAP_VR',
 GROUP='PWR_MCP_CAP',
 CDS_LIB='dev_discrete',
 CDS_PART_NAME='CAP_A_0603V-22.0UF,4V,20%,X6S,A',
 VOLTAGE='4V',
 PRIM_FILE='./archive_libs/discrete/cap_a/chips/chips.prt';

PART_NAME
 C5D54 'CAP_A_0603V-22.0UF,4V,20%,X6S,A':
 GROUP='PWR_MLCC_CAP',
 ROOM='PVCCIN_CPU0_DECAP_VR';

SECTION_NUMBER 1
 '@BASEBOARD_FAB2_LIB.BASEBOARD_FAB2(SCH_1):PAGE217_I279@DEV_DISCRETE.CAP_A(CHIPS)':
 C_PATH='@baseboard_fab2_lib.baseboard_fab2(sch_1):page217_i279@dev_discrete.cap~
_a(chips)',
 P_PATH='@baseboard_fab2_lib.baseboard_fab2(sch_1):page217_i279@dev_discrete.cap~
_a(chips)',
 PATH='I279',
 DRAWING='@BASEBOARD_FAB2_LIB.BASEBOARD_FAB2(SCH_1):PAGE217',
 TOLERANCE='20%',
 MATERIAL='X6S',
 BOM_COST='PROC_SOCKET',
 PHYS_PAGE='217',
 XY='(-900,2850)',
 ROT='0',
 VER='1',
 VALUE='22.0UF',
 PACK_TYPE='0603V',
 PART_NUMBER='E15431-004',
 LOCATION='C5D54',
 ROOM='PVCCIN_CPU0_DECAP_VR',
 GROUP='PWR_MLCC_CAP',
 CDS_LIB='dev_discrete',
 CDS_PART_NAME='CAP_A_0603V-22.0UF,4V,20%,X6S,A',
 VOLTAGE='4V',
 PRIM_FILE='./archive_libs/discrete/cap_a/chips/chips.prt';

PART_NAME
 C5D55 'CAP_A_0603V-22.0UF,4V,20%,X6S,A':
 GROUP='PWR_MLCC_CAP',
 ROOM='PVCCIN_CPU0_DECAP_VR';

SECTION_NUMBER 1
 '@BASEBOARD_FAB2_LIB.BASEBOARD_FAB2(SCH_1):PAGE217_I280@DEV_DISCRETE.CAP_A(CHIPS)':
 C_PATH='@baseboard_fab2_lib.baseboard_fab2(sch_1):page217_i280@dev_discrete.cap~
_a(chips)',
 P_PATH='@baseboard_fab2_lib.baseboard_fab2(sch_1):page217_i280@dev_discrete.cap~
_a(chips)',
 PATH='I280',
 DRAWING='@BASEBOARD_FAB2_LIB.BASEBOARD_FAB2(SCH_1):PAGE217',
 TOLERANCE='20%',
 MATERIAL='X6S',
 BOM_COST='PROC_SOCKET',
 PHYS_PAGE='217',
 XY='(-550,2850)',
 ROT='0',
 VER='1',
 VALUE='22.0UF',
 PACK_TYPE='0603V',
 PART_NUMBER='E15431-004',
 LOCATION='C5D55',
 ROOM='PVCCIN_CPU0_DECAP_VR',
 GROUP='PWR_MLCC_CAP',
 CDS_LIB='dev_discrete',
 CDS_PART_NAME='CAP_A_0603V-22.0UF,4V,20%,X6S,A',
 VOLTAGE='4V',
 PRIM_FILE='./archive_libs/discrete/cap_a/chips/chips.prt';

PART_NAME
 C5D56 'CAP_A_0603V-22.0UF,4V,20%,X6S,A':
 GROUP='PWR_MLCC_CAP',
 ROOM='PVCCIN_CPU0_DECAP_VR';

SECTION_NUMBER 1
 '@BASEBOARD_FAB2_LIB.BASEBOARD_FAB2(SCH_1):PAGE217_I281@DEV_DISCRETE.CAP_A(CHIPS)':
 C_PATH='@baseboard_fab2_lib.baseboard_fab2(sch_1):page217_i281@dev_discrete.cap~
_a(chips)',
 P_PATH='@baseboard_fab2_lib.baseboard_fab2(sch_1):page217_i281@dev_discrete.cap~
_a(chips)',
 PATH='I281',
 DRAWING='@BASEBOARD_FAB2_LIB.BASEBOARD_FAB2(SCH_1):PAGE217',
 TOLERANCE='20%',
 MATERIAL='X6S',
 BOM_COST='PROC_SOCKET',
 PHYS_PAGE='217',
 XY='(-200,2850)',
 ROT='0',
 VER='1',
 VALUE='22.0UF',
 PACK_TYPE='0603V',
 PART_NUMBER='E15431-004',
 LOCATION='C5D56',
 ROOM='PVCCIN_CPU0_DECAP_VR',
 GROUP='PWR_MLCC_CAP',
 CDS_LIB='dev_discrete',
 CDS_PART_NAME='CAP_A_0603V-22.0UF,4V,20%,X6S,A',
 VOLTAGE='4V',
 PRIM_FILE='./archive_libs/discrete/cap_a/chips/chips.prt';

PART_NAME
 C5D57 'CAP_A_0603V-22.0UF,4V,20%,X6S,A':
 GROUP='PWR_MLCC_CAP',
 ROOM='PVCCIN_CPU0_DECAP_VR';

SECTION_NUMBER 1
 '@BASEBOARD_FAB2_LIB.BASEBOARD_FAB2(SCH_1):PAGE217_I282@DEV_DISCRETE.CAP_A(CHIPS)':
 C_PATH='@baseboard_fab2_lib.baseboard_fab2(sch_1):page217_i282@dev_discrete.cap~
_a(chips)',
 P_PATH='@baseboard_fab2_lib.baseboard_fab2(sch_1):page217_i282@dev_discrete.cap~
_a(chips)',
 PATH='I282',
 DRAWING='@BASEBOARD_FAB2_LIB.BASEBOARD_FAB2(SCH_1):PAGE217',
 TOLERANCE='20%',
 MATERIAL='X6S',
 BOM_COST='PROC_SOCKET',
 PHYS_PAGE='217',
 XY='(150,2850)',
 ROT='0',
 VER='1',
 VALUE='22.0UF',
 PACK_TYPE='0603V',
 PART_NUMBER='E15431-004',
 LOCATION='C5D57',
 ROOM='PVCCIN_CPU0_DECAP_VR',
 GROUP='PWR_MLCC_CAP',
 CDS_LIB='dev_discrete',
 CDS_PART_NAME='CAP_A_0603V-22.0UF,4V,20%,X6S,A',
 VOLTAGE='4V',
 PRIM_FILE='./archive_libs/discrete/cap_a/chips/chips.prt';

PART_NAME
 C5D58 'CAP_A_0603V-22.0UF,4V,20%,X6S,A':
 GROUP='PWR_MLCC_CAP',
 ROOM='PVCCIN_CPU0_DECAP_VR';

SECTION_NUMBER 1
 '@BASEBOARD_FAB2_LIB.BASEBOARD_FAB2(SCH_1):PAGE217_I269@DEV_DISCRETE.CAP_A(CHIPS)':
 C_PATH='@baseboard_fab2_lib.baseboard_fab2(sch_1):page217_i269@dev_discrete.cap~
_a(chips)',
 P_PATH='@baseboard_fab2_lib.baseboard_fab2(sch_1):page217_i269@dev_discrete.cap~
_a(chips)',
 PATH='I269',
 DRAWING='@BASEBOARD_FAB2_LIB.BASEBOARD_FAB2(SCH_1):PAGE217',
 TOLERANCE='20%',
 MATERIAL='X6S',
 BOM_COST='PROC_SOCKET',
 PHYS_PAGE='217',
 XY='(1000,1950)',
 ROT='0',
 VER='1',
 VALUE='22.0UF',
 PACK_TYPE='0603V',
 PART_NUMBER='E15431-004',
 LOCATION='C5D58',
 ROOM='PVCCIN_CPU0_DECAP_VR',
 GROUP='PWR_MLCC_CAP',
 CDS_LIB='dev_discrete',
 CDS_PART_NAME='CAP_A_0603V-22.0UF,4V,20%,X6S,A',
 VOLTAGE='4V',
 PRIM_FILE='./archive_libs/discrete/cap_a/chips/chips.prt';

PART_NAME
 C5D59 'CAP_A_0603V-22.0UF,4V,20%,X6S,A':
 GROUP='PWR_MLCC_CAP',
 ROOM='PVCCIN_CPU0_DECAP_VR';

SECTION_NUMBER 1
 '@BASEBOARD_FAB2_LIB.BASEBOARD_FAB2(SCH_1):PAGE217_I271@DEV_DISCRETE.CAP_A(CHIPS)':
 C_PATH='@baseboard_fab2_lib.baseboard_fab2(sch_1):page217_i271@dev_discrete.cap~
_a(chips)',
 P_PATH='@baseboard_fab2_lib.baseboard_fab2(sch_1):page217_i271@dev_discrete.cap~
_a(chips)',
 PATH='I271',
 DRAWING='@BASEBOARD_FAB2_LIB.BASEBOARD_FAB2(SCH_1):PAGE217',
 TOLERANCE='20%',
 MATERIAL='X6S',
 BOM_COST='PROC_SOCKET',
 PHYS_PAGE='217',
 XY='(1300,1950)',
 ROT='0',
 VER='1',
 VALUE='22.0UF',
 PACK_TYPE='0603V',
 PART_NUMBER='E15431-004',
 LOCATION='C5D59',
 ROOM='PVCCIN_CPU0_DECAP_VR',
 GROUP='PWR_MLCC_CAP',
 CDS_LIB='dev_discrete',
 CDS_PART_NAME='CAP_A_0603V-22.0UF,4V,20%,X6S,A',
 VOLTAGE='4V',
 PRIM_FILE='./archive_libs/discrete/cap_a/chips/chips.prt';

PART_NAME
 C5D60 'CAP_A_0603V-22.0UF,4V,20%,X6S,A':
 GROUP='PWR_MLCC_CAP',
 ROOM='PVCCIN_CPU0_DECAP_VR';

SECTION_NUMBER 1
 '@BASEBOARD_FAB2_LIB.BASEBOARD_FAB2(SCH_1):PAGE217_I272@DEV_DISCRETE.CAP_A(CHIPS)':
 C_PATH='@baseboard_fab2_lib.baseboard_fab2(sch_1):page217_i272@dev_discrete.cap~
_a(chips)',
 P_PATH='@baseboard_fab2_lib.baseboard_fab2(sch_1):page217_i272@dev_discrete.cap~
_a(chips)',
 PATH='I272',
 DRAWING='@BASEBOARD_FAB2_LIB.BASEBOARD_FAB2(SCH_1):PAGE217',
 TOLERANCE='20%',
 MATERIAL='X6S',
 BOM_COST='PROC_SOCKET',
 PHYS_PAGE='217',
 XY='(1600,1950)',
 ROT='0',
 VER='1',
 VALUE='22.0UF',
 PACK_TYPE='0603V',
 PART_NUMBER='E15431-004',
 LOCATION='C5D60',
 ROOM='PVCCIN_CPU0_DECAP_VR',
 GROUP='PWR_MLCC_CAP',
 CDS_LIB='dev_discrete',
 CDS_PART_NAME='CAP_A_0603V-22.0UF,4V,20%,X6S,A',
 VOLTAGE='4V',
 PRIM_FILE='./archive_libs/discrete/cap_a/chips/chips.prt';

PART_NAME
 C5D61 'CAP_A_0603V-22.0UF,4V,20%,X6S,A':
 GROUP='PWR_MLCC_CAP',
 ROOM='PVCCIN_CPU0_DECAP_VR';

SECTION_NUMBER 1
 '@BASEBOARD_FAB2_LIB.BASEBOARD_FAB2(SCH_1):PAGE217_I270@DEV_DISCRETE.CAP_A(CHIPS)':
 C_PATH='@baseboard_fab2_lib.baseboard_fab2(sch_1):page217_i270@dev_discrete.cap~
_a(chips)',
 P_PATH='@baseboard_fab2_lib.baseboard_fab2(sch_1):page217_i270@dev_discrete.cap~
_a(chips)',
 PATH='I270',
 DRAWING='@BASEBOARD_FAB2_LIB.BASEBOARD_FAB2(SCH_1):PAGE217',
 TOLERANCE='20%',
 MATERIAL='X6S',
 BOM_COST='PROC_SOCKET',
 PHYS_PAGE='217',
 XY='(1900,1950)',
 ROT='0',
 VER='1',
 VALUE='22.0UF',
 PACK_TYPE='0603V',
 PART_NUMBER='E15431-004',
 LOCATION='C5D61',
 ROOM='PVCCIN_CPU0_DECAP_VR',
 GROUP='PWR_MLCC_CAP',
 CDS_LIB='dev_discrete',
 CDS_PART_NAME='CAP_A_0603V-22.0UF,4V,20%,X6S,A',
 VOLTAGE='4V',
 PRIM_FILE='./archive_libs/discrete/cap_a/chips/chips.prt';

PART_NAME
 C5F1 'CAP_A_0603V-47UF,4V,20%,X5R,60A':
 GROUP='PWR_MLCC_CAP';

SECTION_NUMBER 1
 '@BASEBOARD_FAB2_LIB.BASEBOARD_FAB2(SCH_1):PAGE217_I206@DEV_DISCRETE.CAP_A(CHIPS)':
 C_PATH='@baseboard_fab2_lib.baseboard_fab2(sch_1):page217_i206@dev_discrete.cap~
_a(chips)',
 P_PATH='@baseboard_fab2_lib.baseboard_fab2(sch_1):page217_i206@dev_discrete.cap~
_a(chips)',
 PATH='I206',
 DRAWING='@BASEBOARD_FAB2_LIB.BASEBOARD_FAB2(SCH_1):PAGE217',
 BOM_SS='NOPOP',
 TOLERANCE='20%',
 SEC_TYPE='0603V',
 MATERIAL='X5R',
 PHYS_PAGE='217',
 XY='(3275,1000)',
 ROT='0',
 VER='1',
 VALUE='47UF',
 PACK_TYPE='0603V',
 PART_NUMBER='602433-106',
 LOCATION='C5F1',
 GROUP='PWR_MLCC_CAP',
 SEC='1',
 CDS_LIB='dev_discrete',
 CDS_PART_NAME='CAP_A_0603V-47UF,4V,20%,X5R,60A',
 VOLTAGE='4V',
 PRIM_FILE='./archive_libs/discrete/cap_a/chips/chips.prt';

PART_NAME
 C5F2 'CAP_A_0603V-47UF,4V,20%,X5R,60A':
 GROUP='PWR_MLCC_CAP';

SECTION_NUMBER 1
 '@BASEBOARD_FAB2_LIB.BASEBOARD_FAB2(SCH_1):PAGE217_I205@DEV_DISCRETE.CAP_A(CHIPS)':
 C_PATH='@baseboard_fab2_lib.baseboard_fab2(sch_1):page217_i205@dev_discrete.cap~
_a(chips)',
 P_PATH='@baseboard_fab2_lib.baseboard_fab2(sch_1):page217_i205@dev_discrete.cap~
_a(chips)',
 PATH='I205',
 DRAWING='@BASEBOARD_FAB2_LIB.BASEBOARD_FAB2(SCH_1):PAGE217',
 BOM_SS='NOPOP',
 TOLERANCE='20%',
 SEC_TYPE='0603V',
 MATERIAL='X5R',
 PHYS_PAGE='217',
 XY='(2925,1000)',
 ROT='0',
 VER='1',
 VALUE='47UF',
 PACK_TYPE='0603V',
 PART_NUMBER='602433-106',
 LOCATION='C5F2',
 GROUP='PWR_MLCC_CAP',
 SEC='1',
 CDS_LIB='dev_discrete',
 CDS_PART_NAME='CAP_A_0603V-47UF,4V,20%,X5R,60A',
 VOLTAGE='4V',
 PRIM_FILE='./archive_libs/discrete/cap_a/chips/chips.prt';

PART_NAME
 C5G1 'CAP_A_0603V-47UF,4V,20%,X5R,60A':
 GROUP='PWR_MLCC_CAP';

SECTION_NUMBER 1
 '@BASEBOARD_FAB2_LIB.BASEBOARD_FAB2(SCH_1):PAGE217_I307@DEV_DISCRETE.CAP_A(CHIPS)':
 C_PATH='@baseboard_fab2_lib.baseboard_fab2(sch_1):page217_i307@dev_discrete.cap~
_a(chips)',
 P_PATH='@baseboard_fab2_lib.baseboard_fab2(sch_1):page217_i307@dev_discrete.cap~
_a(chips)',
 PATH='I307',
 DRAWING='@BASEBOARD_FAB2_LIB.BASEBOARD_FAB2(SCH_1):PAGE217',
 BOM_SS='E15431-004',
 TOLERANCE='20%',
 SEC_TYPE='0603V',
 MATERIAL='X5R',
 PHYS_PAGE='217',
 XY='(525,-650)',
 ROT='0',
 VER='1',
 VALUE='47UF',
 PACK_TYPE='0603V',
 PART_NUMBER='602433-106',
 LOCATION='C5G1',
 GROUP='PWR_MLCC_CAP',
 SEC='1',
 CDS_LIB='dev_discrete',
 CDS_PART_NAME='CAP_A_0603V-47UF,4V,20%,X5R,60A',
 VOLTAGE='4V',
 PRIM_FILE='./archive_libs/discrete/cap_a/chips/chips.prt';

PART_NAME
 C5G2 'CAP_A_0603V-47UF,4V,20%,X5R,60A':
 GROUP='PWR_MLCC_CAP';

SECTION_NUMBER 1
 '@BASEBOARD_FAB2_LIB.BASEBOARD_FAB2(SCH_1):PAGE217_I301@DEV_DISCRETE.CAP_A(CHIPS)':
 C_PATH='@baseboard_fab2_lib.baseboard_fab2(sch_1):page217_i301@dev_discrete.cap~
_a(chips)',
 P_PATH='@baseboard_fab2_lib.baseboard_fab2(sch_1):page217_i301@dev_discrete.cap~
_a(chips)',
 PATH='I301',
 DRAWING='@BASEBOARD_FAB2_LIB.BASEBOARD_FAB2(SCH_1):PAGE217',
 BOM_SS='E15431-004',
 TOLERANCE='20%',
 SEC_TYPE='0603V',
 MATERIAL='X5R',
 PHYS_PAGE='217',
 XY='(-1225,-650)',
 ROT='0',
 VER='1',
 VALUE='47UF',
 PACK_TYPE='0603V',
 PART_NUMBER='602433-106',
 LOCATION='C5G2',
 GROUP='PWR_MLCC_CAP',
 SEC='1',
 CDS_LIB='dev_discrete',
 CDS_PART_NAME='CAP_A_0603V-47UF,4V,20%,X5R,60A',
 VOLTAGE='4V',
 PRIM_FILE='./archive_libs/discrete/cap_a/chips/chips.prt';

PART_NAME
 C5G3 'CAP_A_0603V-47UF,4V,20%,X5R,60A':
 GROUP='PWR_MLCC_CAP';

SECTION_NUMBER 1
 '@BASEBOARD_FAB2_LIB.BASEBOARD_FAB2(SCH_1):PAGE217_I314@DEV_DISCRETE.CAP_A(CHIPS)':
 C_PATH='@baseboard_fab2_lib.baseboard_fab2(sch_1):page217_i314@dev_discrete.cap~
_a(chips)',
 P_PATH='@baseboard_fab2_lib.baseboard_fab2(sch_1):page217_i314@dev_discrete.cap~
_a(chips)',
 PATH='I314',
 DRAWING='@BASEBOARD_FAB2_LIB.BASEBOARD_FAB2(SCH_1):PAGE217',
 BOM_SS='E15431-004',
 TOLERANCE='20%',
 SEC_TYPE='0603V',
 MATERIAL='X5R',
 PHYS_PAGE='217',
 XY='(2550,-650)',
 ROT='0',
 VER='1',
 VALUE='47UF',
 PACK_TYPE='0603V',
 PART_NUMBER='602433-106',
 LOCATION='C5G3',
 GROUP='PWR_MLCC_CAP',
 SEC='1',
 CDS_LIB='dev_discrete',
 CDS_PART_NAME='CAP_A_0603V-47UF,4V,20%,X5R,60A',
 VOLTAGE='4V',
 PRIM_FILE='./archive_libs/discrete/cap_a/chips/chips.prt';

PART_NAME
 C5G4 'CAP_A_0603V-47UF,4V,20%,X5R,60A':
 GROUP='PWR_MLCC_CAP';

SECTION_NUMBER 1
 '@BASEBOARD_FAB2_LIB.BASEBOARD_FAB2(SCH_1):PAGE217_I302@DEV_DISCRETE.CAP_A(CHIPS)':
 C_PATH='@baseboard_fab2_lib.baseboard_fab2(sch_1):page217_i302@dev_discrete.cap~
_a(chips)',
 P_PATH='@baseboard_fab2_lib.baseboard_fab2(sch_1):page217_i302@dev_discrete.cap~
_a(chips)',
 PATH='I302',
 DRAWING='@BASEBOARD_FAB2_LIB.BASEBOARD_FAB2(SCH_1):PAGE217',
 BOM_SS='E15431-004',
 TOLERANCE='20%',
 SEC_TYPE='0603V',
 MATERIAL='X5R',
 PHYS_PAGE='217',
 XY='(-950,-650)',
 ROT='0',
 VER='1',
 VALUE='47UF',
 PACK_TYPE='0603V',
 PART_NUMBER='602433-106',
 LOCATION='C5G4',
 GROUP='PWR_MLCC_CAP',
 SEC='1',
 CDS_LIB='dev_discrete',
 CDS_PART_NAME='CAP_A_0603V-47UF,4V,20%,X5R,60A',
 VOLTAGE='4V',
 PRIM_FILE='./archive_libs/discrete/cap_a/chips/chips.prt';

PART_NAME
 C5G5 'CAP_A_0603V-47UF,4V,20%,X5R,60A':
 GROUP='PWR_MLCC_CAP';

SECTION_NUMBER 1
 '@BASEBOARD_FAB2_LIB.BASEBOARD_FAB2(SCH_1):PAGE217_I305@DEV_DISCRETE.CAP_A(CHIPS)':
 C_PATH='@baseboard_fab2_lib.baseboard_fab2(sch_1):page217_i305@dev_discrete.cap~
_a(chips)',
 P_PATH='@baseboard_fab2_lib.baseboard_fab2(sch_1):page217_i305@dev_discrete.cap~
_a(chips)',
 PATH='I305',
 DRAWING='@BASEBOARD_FAB2_LIB.BASEBOARD_FAB2(SCH_1):PAGE217',
 BOM_SS='E15431-004',
 TOLERANCE='20%',
 SEC_TYPE='0603V',
 MATERIAL='X5R',
 PHYS_PAGE='217',
 XY='(-75,-650)',
 ROT='0',
 VER='1',
 VALUE='47UF',
 PACK_TYPE='0603V',
 PART_NUMBER='602433-106',
 LOCATION='C5G5',
 GROUP='PWR_MLCC_CAP',
 SEC='1',
 CDS_LIB='dev_discrete',
 CDS_PART_NAME='CAP_A_0603V-47UF,4V,20%,X5R,60A',
 VOLTAGE='4V',
 PRIM_FILE='./archive_libs/discrete/cap_a/chips/chips.prt';

PART_NAME
 C5G6 'CAP_A_0603V-47UF,4V,20%,X5R,60A':
 GROUP='PWR_MLCC_CAP';

SECTION_NUMBER 1
 '@BASEBOARD_FAB2_LIB.BASEBOARD_FAB2(SCH_1):PAGE217_I304@DEV_DISCRETE.CAP_A(CHIPS)':
 C_PATH='@baseboard_fab2_lib.baseboard_fab2(sch_1):page217_i304@dev_discrete.cap~
_a(chips)',
 P_PATH='@baseboard_fab2_lib.baseboard_fab2(sch_1):page217_i304@dev_discrete.cap~
_a(chips)',
 PATH='I304',
 DRAWING='@BASEBOARD_FAB2_LIB.BASEBOARD_FAB2(SCH_1):PAGE217',
 BOM_SS='E15431-004',
 TOLERANCE='20%',
 SEC_TYPE='0603V',
 MATERIAL='X5R',
 PHYS_PAGE='217',
 XY='(-375,-650)',
 ROT='0',
 VER='1',
 VALUE='47UF',
 PACK_TYPE='0603V',
 PART_NUMBER='602433-106',
 LOCATION='C5G6',
 GROUP='PWR_MLCC_CAP',
 SEC='1',
 CDS_LIB='dev_discrete',
 CDS_PART_NAME='CAP_A_0603V-47UF,4V,20%,X5R,60A',
 VOLTAGE='4V',
 PRIM_FILE='./archive_libs/discrete/cap_a/chips/chips.prt';

PART_NAME
 C5G7 'CAP_A_0603V-47UF,4V,20%,X5R,60A':
 GROUP='PWR_MLCC_CAP';

SECTION_NUMBER 1
 '@BASEBOARD_FAB2_LIB.BASEBOARD_FAB2(SCH_1):PAGE217_I306@DEV_DISCRETE.CAP_A(CHIPS)':
 C_PATH='@baseboard_fab2_lib.baseboard_fab2(sch_1):page217_i306@dev_discrete.cap~
_a(chips)',
 P_PATH='@baseboard_fab2_lib.baseboard_fab2(sch_1):page217_i306@dev_discrete.cap~
_a(chips)',
 PATH='I306',
 DRAWING='@BASEBOARD_FAB2_LIB.BASEBOARD_FAB2(SCH_1):PAGE217',
 BOM_SS='E15431-004',
 TOLERANCE='20%',
 SEC_TYPE='0603V',
 MATERIAL='X5R',
 PHYS_PAGE='217',
 XY='(200,-650)',
 ROT='0',
 VER='1',
 VALUE='47UF',
 PACK_TYPE='0603V',
 PART_NUMBER='602433-106',
 LOCATION='C5G7',
 GROUP='PWR_MLCC_CAP',
 SEC='1',
 CDS_LIB='dev_discrete',
 CDS_PART_NAME='CAP_A_0603V-47UF,4V,20%,X5R,60A',
 VOLTAGE='4V',
 PRIM_FILE='./archive_libs/discrete/cap_a/chips/chips.prt';

PART_NAME
 C5G8 'CAP_A_0603V-47UF,4V,20%,X5R,60A':
 GROUP='PWR_MLCC_CAP';

SECTION_NUMBER 1
 '@BASEBOARD_FAB2_LIB.BASEBOARD_FAB2(SCH_1):PAGE217_I308@DEV_DISCRETE.CAP_A(CHIPS)':
 C_PATH='@baseboard_fab2_lib.baseboard_fab2(sch_1):page217_i308@dev_discrete.cap~
_a(chips)',
 P_PATH='@baseboard_fab2_lib.baseboard_fab2(sch_1):page217_i308@dev_discrete.cap~
_a(chips)',
 PATH='I308',
 DRAWING='@BASEBOARD_FAB2_LIB.BASEBOARD_FAB2(SCH_1):PAGE217',
 BOM_SS='E15431-004',
 TOLERANCE='20%',
 SEC_TYPE='0603V',
 MATERIAL='X5R',
 PHYS_PAGE='217',
 XY='(825,-650)',
 ROT='0',
 VER='1',
 VALUE='47UF',
 PACK_TYPE='0603V',
 PART_NUMBER='602433-106',
 LOCATION='C5G8',
 GROUP='PWR_MLCC_CAP',
 SEC='1',
 CDS_LIB='dev_discrete',
 CDS_PART_NAME='CAP_A_0603V-47UF,4V,20%,X5R,60A',
 VOLTAGE='4V',
 PRIM_FILE='./archive_libs/discrete/cap_a/chips/chips.prt';

PART_NAME
 C5G9 'CAP_0805-100UF,4V,20%,X5R,6024A':
 GROUP='PWR_MLCC_CAP',
 ROOM='VDDQ_ABC_PWR_VR';

SECTION_NUMBER 1
 '@BASEBOARD_FAB2_LIB.BASEBOARD_FAB2(SCH_1):PAGE217_I318@MSTR_DISCRETE.CAP(CHIPS)':
 C_PATH='@baseboard_fab2_lib.baseboard_fab2(sch_1):page217_i318@mstr_discrete.ca~
p(chips)',
 P_PATH='@baseboard_fab2_lib.baseboard_fab2(sch_1):page217_i318@mstr_discrete.ca~
p(chips)',
 PATH='I318',
 DRAWING='@BASEBOARD_FAB2_LIB.BASEBOARD_FAB2(SCH_1):PAGE217',
 NEW_PN='078.1071T.M002',
 NEW_MATERIAL='X6S',
 BOM_SS='NOPOP',
 TOLERANCE='20%',
 SEC_TYPE='0805',
 MATERIAL='X5R',
 BOM_COST='MEM_VRD_PVDDQ_CD',
 PHYS_PAGE='217',
 XY='(3225,2850)',
 ROT='0',
 VER='1',
 VALUE='100UF',
 PACK_TYPE='0805',
 PART_NUMBER='602433-112',
 LOCATION='C5G9',
 ROOM='VDDQ_ABC_PWR_VR',
 GROUP='PWR_MLCC_CAP',
 SEC='1',
 CDS_LIB='mstr_discrete',
 CDS_PART_NAME='CAP_0805-100UF,4V,20%,X5R,6024A',
 VOLTAGE='4V',
 PRIM_FILE='./archive_libs/mstr_discrete/cap/chips/chips.prt';

PART_NAME
 C5G10 'CAP_A_0603V-47UF,4V,20%,X5R,60A':
 GROUP='PWR_MLCC_CAP';

SECTION_NUMBER 1
 '@BASEBOARD_FAB2_LIB.BASEBOARD_FAB2(SCH_1):PAGE217_I207@DEV_DISCRETE.CAP_A(CHIPS)':
 C_PATH='@baseboard_fab2_lib.baseboard_fab2(sch_1):page217_i207@dev_discrete.cap~
_a(chips)',
 P_PATH='@baseboard_fab2_lib.baseboard_fab2(sch_1):page217_i207@dev_discrete.cap~
_a(chips)',
 PATH='I207',
 DRAWING='@BASEBOARD_FAB2_LIB.BASEBOARD_FAB2(SCH_1):PAGE217',
 BOM_SS='NOPOP',
 TOLERANCE='20%',
 SEC_TYPE='0603V',
 MATERIAL='X5R',
 PHYS_PAGE='217',
 XY='(3675,1000)',
 ROT='0',
 VER='1',
 VALUE='47UF',
 PACK_TYPE='0603V',
 PART_NUMBER='602433-106',
 LOCATION='C5G10',
 GROUP='PWR_MLCC_CAP',
 SEC='1',
 CDS_LIB='dev_discrete',
 CDS_PART_NAME='CAP_A_0603V-47UF,4V,20%,X5R,60A',
 VOLTAGE='4V',
 PRIM_FILE='./archive_libs/discrete/cap_a/chips/chips.prt';

PART_NAME
 C5G11 'CAP_A_0603V-47UF,4V,20%,X5R,60A':
 GROUP='PWR_MLCC_CAP';

SECTION_NUMBER 1
 '@BASEBOARD_FAB2_LIB.BASEBOARD_FAB2(SCH_1):PAGE217_I299@DEV_DISCRETE.CAP_A(CHIPS)':
 C_PATH='@baseboard_fab2_lib.baseboard_fab2(sch_1):page217_i299@dev_discrete.cap~
_a(chips)',
 P_PATH='@baseboard_fab2_lib.baseboard_fab2(sch_1):page217_i299@dev_discrete.cap~
_a(chips)',
 PATH='I299',
 DRAWING='@BASEBOARD_FAB2_LIB.BASEBOARD_FAB2(SCH_1):PAGE217',
 BOM_SS='E15431-004',
 TOLERANCE='20%',
 SEC_TYPE='0603V',
 MATERIAL='X5R',
 PHYS_PAGE='217',
 XY='(-1825,-650)',
 ROT='0',
 VER='1',
 VALUE='47UF',
 PACK_TYPE='0603V',
 PART_NUMBER='602433-106',
 LOCATION='C5G11',
 GROUP='PWR_MLCC_CAP',
 SEC='1',
 CDS_LIB='dev_discrete',
 CDS_PART_NAME='CAP_A_0603V-47UF,4V,20%,X5R,60A',
 VOLTAGE='4V',
 PRIM_FILE='./archive_libs/discrete/cap_a/chips/chips.prt';

PART_NAME
 C5G12 'CAP_A_0603V-47UF,4V,20%,X5R,60A':
 GROUP='PWR_MLCC_CAP';

SECTION_NUMBER 1
 '@BASEBOARD_FAB2_LIB.BASEBOARD_FAB2(SCH_1):PAGE217_I300@DEV_DISCRETE.CAP_A(CHIPS)':
 C_PATH='@baseboard_fab2_lib.baseboard_fab2(sch_1):page217_i300@dev_discrete.cap~
_a(chips)',
 P_PATH='@baseboard_fab2_lib.baseboard_fab2(sch_1):page217_i300@dev_discrete.cap~
_a(chips)',
 PATH='I300',
 DRAWING='@BASEBOARD_FAB2_LIB.BASEBOARD_FAB2(SCH_1):PAGE217',
 BOM_SS='E15431-004',
 TOLERANCE='20%',
 SEC_TYPE='0603V',
 MATERIAL='X5R',
 PHYS_PAGE='217',
 XY='(-1525,-650)',
 ROT='0',
 VER='1',
 VALUE='47UF',
 PACK_TYPE='0603V',
 PART_NUMBER='602433-106',
 LOCATION='C5G12',
 GROUP='PWR_MLCC_CAP',
 SEC='1',
 CDS_LIB='dev_discrete',
 CDS_PART_NAME='CAP_A_0603V-47UF,4V,20%,X5R,60A',
 VOLTAGE='4V',
 PRIM_FILE='./archive_libs/discrete/cap_a/chips/chips.prt';

PART_NAME
 C5G13 'CAP_A_0603V-47UF,4V,20%,X5R,60A':
 GROUP='PWR_MLCC_CAP';

SECTION_NUMBER 1
 '@BASEBOARD_FAB2_LIB.BASEBOARD_FAB2(SCH_1):PAGE217_I303@DEV_DISCRETE.CAP_A(CHIPS)':
 C_PATH='@baseboard_fab2_lib.baseboard_fab2(sch_1):page217_i303@dev_discrete.cap~
_a(chips)',
 P_PATH='@baseboard_fab2_lib.baseboard_fab2(sch_1):page217_i303@dev_discrete.cap~
_a(chips)',
 PATH='I303',
 DRAWING='@BASEBOARD_FAB2_LIB.BASEBOARD_FAB2(SCH_1):PAGE217',
 BOM_SS='E15431-004',
 TOLERANCE='20%',
 SEC_TYPE='0603V',
 MATERIAL='X5R',
 PHYS_PAGE='217',
 XY='(-675,-650)',
 ROT='0',
 VER='1',
 VALUE='47UF',
 PACK_TYPE='0603V',
 PART_NUMBER='602433-106',
 LOCATION='C5G13',
 GROUP='PWR_MLCC_CAP',
 SEC='1',
 CDS_LIB='dev_discrete',
 CDS_PART_NAME='CAP_A_0603V-47UF,4V,20%,X5R,60A',
 VOLTAGE='4V',
 PRIM_FILE='./archive_libs/discrete/cap_a/chips/chips.prt';

PART_NAME
 C5G14 'CAP_A_0603V-47UF,4V,20%,X5R,60A':
 GROUP='PWR_MLCC_CAP';

SECTION_NUMBER 1
 '@BASEBOARD_FAB2_LIB.BASEBOARD_FAB2(SCH_1):PAGE217_I311@DEV_DISCRETE.CAP_A(CHIPS)':
 C_PATH='@baseboard_fab2_lib.baseboard_fab2(sch_1):page217_i311@dev_discrete.cap~
_a(chips)',
 P_PATH='@baseboard_fab2_lib.baseboard_fab2(sch_1):page217_i311@dev_discrete.cap~
_a(chips)',
 PATH='I311',
 DRAWING='@BASEBOARD_FAB2_LIB.BASEBOARD_FAB2(SCH_1):PAGE217',
 BOM_SS='E15431-004',
 TOLERANCE='20%',
 SEC_TYPE='0603V',
 MATERIAL='X5R',
 PHYS_PAGE='217',
 XY='(1675,-650)',
 ROT='0',
 VER='1',
 VALUE='47UF',
 PACK_TYPE='0603V',
 PART_NUMBER='602433-106',
 LOCATION='C5G14',
 GROUP='PWR_MLCC_CAP',
 SEC='1',
 CDS_LIB='dev_discrete',
 CDS_PART_NAME='CAP_A_0603V-47UF,4V,20%,X5R,60A',
 VOLTAGE='4V',
 PRIM_FILE='./archive_libs/discrete/cap_a/chips/chips.prt';

PART_NAME
 C5G15 'CAP_A_0603V-47UF,4V,20%,X5R,60A':
 GROUP='PWR_MLCC_CAP';

SECTION_NUMBER 1
 '@BASEBOARD_FAB2_LIB.BASEBOARD_FAB2(SCH_1):PAGE217_I313@DEV_DISCRETE.CAP_A(CHIPS)':
 C_PATH='@baseboard_fab2_lib.baseboard_fab2(sch_1):page217_i313@dev_discrete.cap~
_a(chips)',
 P_PATH='@baseboard_fab2_lib.baseboard_fab2(sch_1):page217_i313@dev_discrete.cap~
_a(chips)',
 PATH='I313',
 DRAWING='@BASEBOARD_FAB2_LIB.BASEBOARD_FAB2(SCH_1):PAGE217',
 BOM_SS='E15431-004',
 TOLERANCE='20%',
 SEC_TYPE='0603V',
 MATERIAL='X5R',
 PHYS_PAGE='217',
 XY='(2275,-650)',
 ROT='0',
 VER='1',
 VALUE='47UF',
 PACK_TYPE='0603V',
 PART_NUMBER='602433-106',
 LOCATION='C5G15',
 GROUP='PWR_MLCC_CAP',
 SEC='1',
 CDS_LIB='dev_discrete',
 CDS_PART_NAME='CAP_A_0603V-47UF,4V,20%,X5R,60A',
 VOLTAGE='4V',
 PRIM_FILE='./archive_libs/discrete/cap_a/chips/chips.prt';

PART_NAME
 C5G16 'CAP_A_0603V-47UF,4V,20%,X5R,60A':
 GROUP='PWR_MLCC_CAP';

SECTION_NUMBER 1
 '@BASEBOARD_FAB2_LIB.BASEBOARD_FAB2(SCH_1):PAGE217_I312@DEV_DISCRETE.CAP_A(CHIPS)':
 C_PATH='@baseboard_fab2_lib.baseboard_fab2(sch_1):page217_i312@dev_discrete.cap~
_a(chips)',
 P_PATH='@baseboard_fab2_lib.baseboard_fab2(sch_1):page217_i312@dev_discrete.cap~
_a(chips)',
 PATH='I312',
 DRAWING='@BASEBOARD_FAB2_LIB.BASEBOARD_FAB2(SCH_1):PAGE217',
 BOM_SS='E15431-004',
 TOLERANCE='20%',
 SEC_TYPE='0603V',
 MATERIAL='X5R',
 PHYS_PAGE='217',
 XY='(1975,-650)',
 ROT='0',
 VER='1',
 VALUE='47UF',
 PACK_TYPE='0603V',
 PART_NUMBER='602433-106',
 LOCATION='C5G16',
 GROUP='PWR_MLCC_CAP',
 SEC='1',
 CDS_LIB='dev_discrete',
 CDS_PART_NAME='CAP_A_0603V-47UF,4V,20%,X5R,60A',
 VOLTAGE='4V',
 PRIM_FILE='./archive_libs/discrete/cap_a/chips/chips.prt';

PART_NAME
 C5G17 'CAP_A_0603V-47UF,4V,20%,X5R,60A':
 GROUP='PWR_MLCC_CAP';

SECTION_NUMBER 1
 '@BASEBOARD_FAB2_LIB.BASEBOARD_FAB2(SCH_1):PAGE217_I310@DEV_DISCRETE.CAP_A(CHIPS)':
 C_PATH='@baseboard_fab2_lib.baseboard_fab2(sch_1):page217_i310@dev_discrete.cap~
_a(chips)',
 P_PATH='@baseboard_fab2_lib.baseboard_fab2(sch_1):page217_i310@dev_discrete.cap~
_a(chips)',
 PATH='I310',
 DRAWING='@BASEBOARD_FAB2_LIB.BASEBOARD_FAB2(SCH_1):PAGE217',
 BOM_SS='E15431-004',
 TOLERANCE='20%',
 SEC_TYPE='0603V',
 MATERIAL='X5R',
 PHYS_PAGE='217',
 XY='(1400,-650)',
 ROT='0',
 VER='1',
 VALUE='47UF',
 PACK_TYPE='0603V',
 PART_NUMBER='602433-106',
 LOCATION='C5G17',
 GROUP='PWR_MLCC_CAP',
 SEC='1',
 CDS_LIB='dev_discrete',
 CDS_PART_NAME='CAP_A_0603V-47UF,4V,20%,X5R,60A',
 VOLTAGE='4V',
 PRIM_FILE='./archive_libs/discrete/cap_a/chips/chips.prt';

PART_NAME
 C5G18 'CAP_A_0603V-47UF,4V,20%,X5R,60A':
 GROUP='PWR_MLCC_CAP';

SECTION_NUMBER 1
 '@BASEBOARD_FAB2_LIB.BASEBOARD_FAB2(SCH_1):PAGE217_I309@DEV_DISCRETE.CAP_A(CHIPS)':
 C_PATH='@baseboard_fab2_lib.baseboard_fab2(sch_1):page217_i309@dev_discrete.cap~
_a(chips)',
 P_PATH='@baseboard_fab2_lib.baseboard_fab2(sch_1):page217_i309@dev_discrete.cap~
_a(chips)',
 PATH='I309',
 DRAWING='@BASEBOARD_FAB2_LIB.BASEBOARD_FAB2(SCH_1):PAGE217',
 BOM_SS='E15431-004',
 TOLERANCE='20%',
 SEC_TYPE='0603V',
 MATERIAL='X5R',
 PHYS_PAGE='217',
 XY='(1125,-650)',
 ROT='0',
 VER='1',
 VALUE='47UF',
 PACK_TYPE='0603V',
 PART_NUMBER='602433-106',
 LOCATION='C5G18',
 GROUP='PWR_MLCC_CAP',
 SEC='1',
 CDS_LIB='dev_discrete',
 CDS_PART_NAME='CAP_A_0603V-47UF,4V,20%,X5R,60A',
 VOLTAGE='4V',
 PRIM_FILE='./archive_libs/discrete/cap_a/chips/chips.prt';

PART_NAME
 C5G19 'CAP_A_0603V-47UF,4V,20%,X5R,60A':
 GROUP='PWR_MLCC_CAP';

SECTION_NUMBER 1
 '@BASEBOARD_FAB2_LIB.BASEBOARD_FAB2(SCH_1):PAGE217_I213@DEV_DISCRETE.CAP_A(CHIPS)':
 C_PATH='@baseboard_fab2_lib.baseboard_fab2(sch_1):page217_i213@dev_discrete.cap~
_a(chips)',
 P_PATH='@baseboard_fab2_lib.baseboard_fab2(sch_1):page217_i213@dev_discrete.cap~
_a(chips)',
 PATH='I213',
 DRAWING='@BASEBOARD_FAB2_LIB.BASEBOARD_FAB2(SCH_1):PAGE217',
 BOM_SS='NOPOP',
 TOLERANCE='20%',
 SEC_TYPE='0603V',
 MATERIAL='X5R',
 PHYS_PAGE='217',
 XY='(2900,1725)',
 ROT='0',
 VER='1',
 VALUE='47UF',
 PACK_TYPE='0603V',
 PART_NUMBER='602433-106',
 LOCATION='C5G19',
 GROUP='PWR_MLCC_CAP',
 SEC='1',
 CDS_LIB='dev_discrete',
 CDS_PART_NAME='CAP_A_0603V-47UF,4V,20%,X5R,60A',
 VOLTAGE='4V',
 PRIM_FILE='./archive_libs/discrete/cap_a/chips/chips.prt';

PART_NAME
 C5G20 'CAP_0805-100UF,4V,20%,X5R,6024A':
 GROUP='PWR_MLCC_CAP',
 ROOM='VDDQ_ABC_PWR_VR';

SECTION_NUMBER 1
 '@BASEBOARD_FAB2_LIB.BASEBOARD_FAB2(SCH_1):PAGE217_I329@MSTR_DISCRETE.CAP(CHIPS)':
 C_PATH='@baseboard_fab2_lib.baseboard_fab2(sch_1):page217_i329@mstr_discrete.ca~
p(chips)',
 P_PATH='@baseboard_fab2_lib.baseboard_fab2(sch_1):page217_i329@mstr_discrete.ca~
p(chips)',
 PATH='I329',
 DRAWING='@BASEBOARD_FAB2_LIB.BASEBOARD_FAB2(SCH_1):PAGE217',
 NEW_PN='078.1071T.M002',
 NEW_MATERIAL='X6S',
 BOM_SS='NOPOP',
 TOLERANCE='20%',
 SEC_TYPE='0805',
 MATERIAL='X5R',
 BOM_COST='MEM_VRD_PVDDQ_CD',
 PHYS_PAGE='217',
 XY='(2875,2850)',
 ROT='0',
 VER='1',
 VALUE='100UF',
 PACK_TYPE='0805',
 PART_NUMBER='602433-112',
 LOCATION='C5G20',
 ROOM='VDDQ_ABC_PWR_VR',
 GROUP='PWR_MLCC_CAP',
 SEC='1',
 CDS_LIB='mstr_discrete',
 CDS_PART_NAME='CAP_0805-100UF,4V,20%,X5R,6024A',
 VOLTAGE='4V',
 PRIM_FILE='./archive_libs/mstr_discrete/cap/chips/chips.prt';

PART_NAME
 C5G21 'CAP_0805-47UF,4V,20%,X6S,C9533A':
 GROUP='PWR_MLCC_CAP',
 ROOM='PVCCIN_CPU0_DECAP_VR';

SECTION_NUMBER 1
 '@BASEBOARD_FAB2_LIB.BASEBOARD_FAB2(SCH_1):PAGE242_I92@MSTR_DISCRETE.CAP(CHIPS)':
 C_PATH='@baseboard_fab2_lib.baseboard_fab2(sch_1):page242_i92@mstr_discrete.cap~
(chips)',
 P_PATH='@baseboard_fab2_lib.baseboard_fab2(sch_1):page242_i92@mstr_discrete.cap~
(chips)',
 PATH='I92',
 DRAWING='@BASEBOARD_FAB2_LIB.BASEBOARD_FAB2(SCH_1):PAGE242',
 POP='NOPOP',
 TOLERANCE='20%',
 SEC_TYPE='0805',
 MATERIAL='X6S',
 BOM_COST='PROC_SOCKET',
 PHYS_PAGE='242',
 XY='(-7750,3775)',
 ROT='0',
 VER='1',
 VALUE='47UF',
 PACK_TYPE='0805',
 PART_NUMBER='C95333-006',
 LOCATION='C5G21',
 ROOM='PVCCIN_CPU0_DECAP_VR',
 GROUP='PWR_MLCC_CAP',
 SEC='1',
 CDS_LIB='mstr_discrete',
 CDS_PART_NAME='CAP_0805-47UF,4V,20%,X6S,C9533A',
 VOLTAGE='4V',
 PRIM_FILE='./archive_libs/mstr_discrete/cap/chips/chips.prt';

PART_NAME
 C5G22 'CAP_0805-47UF,4V,20%,X6S,C9533A':
 GROUP='PWR_MLCC_CAP',
 ROOM='PVCCIN_CPU0_DECAP_VR';

SECTION_NUMBER 1
 '@BASEBOARD_FAB2_LIB.BASEBOARD_FAB2(SCH_1):PAGE242_I90@MSTR_DISCRETE.CAP(CHIPS)':
 C_PATH='@baseboard_fab2_lib.baseboard_fab2(sch_1):page242_i90@mstr_discrete.cap~
(chips)',
 P_PATH='@baseboard_fab2_lib.baseboard_fab2(sch_1):page242_i90@mstr_discrete.cap~
(chips)',
 PATH='I90',
 DRAWING='@BASEBOARD_FAB2_LIB.BASEBOARD_FAB2(SCH_1):PAGE242',
 POP='NOPOP',
 TOLERANCE='20%',
 SEC_TYPE='0805',
 MATERIAL='X6S',
 BOM_COST='PROC_SOCKET',
 PHYS_PAGE='242',
 XY='(-7350,3775)',
 ROT='0',
 VER='1',
 VALUE='47UF',
 PACK_TYPE='0805',
 PART_NUMBER='C95333-006',
 LOCATION='C5G22',
 ROOM='PVCCIN_CPU0_DECAP_VR',
 GROUP='PWR_MLCC_CAP',
 SEC='1',
 CDS_LIB='mstr_discrete',
 CDS_PART_NAME='CAP_0805-47UF,4V,20%,X6S,C9533A',
 VOLTAGE='4V',
 PRIM_FILE='./archive_libs/mstr_discrete/cap/chips/chips.prt';

PART_NAME
 C5G41 'CAP_A_0603V-22.0UF,4V,20%,X6S,A':
 GROUP='PWR_MLCC_CAP',
 ROOM='PVDDQ_KLM';

SECTION_NUMBER 1
 '@BASEBOARD_FAB2_LIB.BASEBOARD_FAB2(SCH_1):PAGE242_I53@DEV_DISCRETE.CAP_A(CHIPS)':
 C_PATH='@baseboard_fab2_lib.baseboard_fab2(sch_1):page242_i53@dev_discrete.cap_~
a(chips)',
 P_PATH='@baseboard_fab2_lib.baseboard_fab2(sch_1):page242_i53@dev_discrete.cap_~
a(chips)',
 PATH='I53',
 DRAWING='@BASEBOARD_FAB2_LIB.BASEBOARD_FAB2(SCH_1):PAGE242',
 BOM_DS='NOPOP',
 TOLERANCE='20%',
 SEC_TYPE='0603V',
 MATERIAL='X6S',
 PHYS_PAGE='242',
 XY='(-7750,2800)',
 ROT='0',
 VER='1',
 VALUE='22.0UF',
 PACK_TYPE='0603V',
 PART_NUMBER='E15431-004',
 LOCATION='C5G41',
 ROOM='PVDDQ_KLM',
 GROUP='PWR_MLCC_CAP',
 SEC='1',
 CDS_LIB='dev_discrete',
 CDS_PART_NAME='CAP_A_0603V-22.0UF,4V,20%,X6S,A',
 VOLTAGE='4V',
 PRIM_FILE='./archive_libs/discrete/cap_a/chips/chips.prt';

PART_NAME
 C5G42 'CAP_A_0603V-22.0UF,4V,20%,X6S,A':
 GROUP='PWR_MLCC_CAP',
 ROOM='PVDDQ_KLM';

SECTION_NUMBER 1
 '@BASEBOARD_FAB2_LIB.BASEBOARD_FAB2(SCH_1):PAGE242_I54@DEV_DISCRETE.CAP_A(CHIPS)':
 C_PATH='@baseboard_fab2_lib.baseboard_fab2(sch_1):page242_i54@dev_discrete.cap_~
a(chips)',
 P_PATH='@baseboard_fab2_lib.baseboard_fab2(sch_1):page242_i54@dev_discrete.cap_~
a(chips)',
 PATH='I54',
 DRAWING='@BASEBOARD_FAB2_LIB.BASEBOARD_FAB2(SCH_1):PAGE242',
 BOM_DS='NOPOP',
 TOLERANCE='20%',
 SEC_TYPE='0603V',
 MATERIAL='X6S',
 PHYS_PAGE='242',
 XY='(-7350,2800)',
 ROT='0',
 VER='1',
 VALUE='22.0UF',
 PACK_TYPE='0603V',
 PART_NUMBER='E15431-004',
 LOCATION='C5G42',
 ROOM='PVDDQ_KLM',
 GROUP='PWR_MLCC_CAP',
 SEC='1',
 CDS_LIB='dev_discrete',
 CDS_PART_NAME='CAP_A_0603V-22.0UF,4V,20%,X6S,A',
 VOLTAGE='4V',
 PRIM_FILE='./archive_libs/discrete/cap_a/chips/chips.prt';

PART_NAME
 C5G43 'CAP_A_0603V-22.0UF,4V,20%,X6S,A':
 GROUP='PWR_MLCC_CAP',
 ROOM='PVDDQ_KLM';

SECTION_NUMBER 1
 '@BASEBOARD_FAB2_LIB.BASEBOARD_FAB2(SCH_1):PAGE242_I56@DEV_DISCRETE.CAP_A(CHIPS)':
 C_PATH='@baseboard_fab2_lib.baseboard_fab2(sch_1):page242_i56@dev_discrete.cap_~
a(chips)',
 P_PATH='@baseboard_fab2_lib.baseboard_fab2(sch_1):page242_i56@dev_discrete.cap_~
a(chips)',
 PATH='I56',
 DRAWING='@BASEBOARD_FAB2_LIB.BASEBOARD_FAB2(SCH_1):PAGE242',
 BOM_DS='NOPOP',
 TOLERANCE='20%',
 SEC_TYPE='0603V',
 MATERIAL='X6S',
 PHYS_PAGE='242',
 XY='(-6950,2800)',
 ROT='0',
 VER='1',
 VALUE='22.0UF',
 PACK_TYPE='0603V',
 PART_NUMBER='E15431-004',
 LOCATION='C5G43',
 ROOM='PVDDQ_KLM',
 GROUP='PWR_MLCC_CAP',
 SEC='1',
 CDS_LIB='dev_discrete',
 CDS_PART_NAME='CAP_A_0603V-22.0UF,4V,20%,X6S,A',
 VOLTAGE='4V',
 PRIM_FILE='./archive_libs/discrete/cap_a/chips/chips.prt';

PART_NAME
 C5G44 'CAP_A_0603V-22.0UF,4V,20%,X6S,A':
 GROUP='PWR_MLCC_CAP',
 ROOM='PVDDQ_KLM';

SECTION_NUMBER 1
 '@BASEBOARD_FAB2_LIB.BASEBOARD_FAB2(SCH_1):PAGE242_I55@DEV_DISCRETE.CAP_A(CHIPS)':
 C_PATH='@baseboard_fab2_lib.baseboard_fab2(sch_1):page242_i55@dev_discrete.cap_~
a(chips)',
 P_PATH='@baseboard_fab2_lib.baseboard_fab2(sch_1):page242_i55@dev_discrete.cap_~
a(chips)',
 PATH='I55',
 DRAWING='@BASEBOARD_FAB2_LIB.BASEBOARD_FAB2(SCH_1):PAGE242',
 BOM_DS='NOPOP',
 TOLERANCE='20%',
 SEC_TYPE='0603V',
 MATERIAL='X6S',
 PHYS_PAGE='242',
 XY='(-6550,2800)',
 ROT='0',
 VER='1',
 VALUE='22.0UF',
 PACK_TYPE='0603V',
 PART_NUMBER='E15431-004',
 LOCATION='C5G44',
 ROOM='PVDDQ_KLM',
 GROUP='PWR_MLCC_CAP',
 SEC='1',
 CDS_LIB='dev_discrete',
 CDS_PART_NAME='CAP_A_0603V-22.0UF,4V,20%,X6S,A',
 VOLTAGE='4V',
 PRIM_FILE='./archive_libs/discrete/cap_a/chips/chips.prt';

PART_NAME
 C5G45 'CAP_A_0603V-22.0UF,4V,20%,X6S,A':
 GROUP='PWR_MLCC_CAP',
 ROOM='PVDDQ_KLM';

SECTION_NUMBER 1
 '@BASEBOARD_FAB2_LIB.BASEBOARD_FAB2(SCH_1):PAGE242_I60@DEV_DISCRETE.CAP_A(CHIPS)':
 C_PATH='@baseboard_fab2_lib.baseboard_fab2(sch_1):page242_i60@dev_discrete.cap_~
a(chips)',
 P_PATH='@baseboard_fab2_lib.baseboard_fab2(sch_1):page242_i60@dev_discrete.cap_~
a(chips)',
 PATH='I60',
 DRAWING='@BASEBOARD_FAB2_LIB.BASEBOARD_FAB2(SCH_1):PAGE242',
 BOM_DS='NOPOP',
 TOLERANCE='20%',
 SEC_TYPE='0603V',
 MATERIAL='X6S',
 PHYS_PAGE='242',
 XY='(-6150,2800)',
 ROT='0',
 VER='1',
 VALUE='22.0UF',
 PACK_TYPE='0603V',
 PART_NUMBER='E15431-004',
 LOCATION='C5G45',
 ROOM='PVDDQ_KLM',
 GROUP='PWR_MLCC_CAP',
 SEC='1',
 CDS_LIB='dev_discrete',
 CDS_PART_NAME='CAP_A_0603V-22.0UF,4V,20%,X6S,A',
 VOLTAGE='4V',
 PRIM_FILE='./archive_libs/discrete/cap_a/chips/chips.prt';

PART_NAME
 C5G46 'CAP_A_0603V-22.0UF,4V,20%,X6S,A':
 GROUP='PWR_MLCC_CAP',
 ROOM='PVDDQ_KLM';

SECTION_NUMBER 1
 '@BASEBOARD_FAB2_LIB.BASEBOARD_FAB2(SCH_1):PAGE242_I59@DEV_DISCRETE.CAP_A(CHIPS)':
 C_PATH='@baseboard_fab2_lib.baseboard_fab2(sch_1):page242_i59@dev_discrete.cap_~
a(chips)',
 P_PATH='@baseboard_fab2_lib.baseboard_fab2(sch_1):page242_i59@dev_discrete.cap_~
a(chips)',
 PATH='I59',
 DRAWING='@BASEBOARD_FAB2_LIB.BASEBOARD_FAB2(SCH_1):PAGE242',
 BOM_DS='NOPOP',
 TOLERANCE='20%',
 SEC_TYPE='0603V',
 MATERIAL='X6S',
 PHYS_PAGE='242',
 XY='(-5750,2800)',
 ROT='0',
 VER='1',
 VALUE='22.0UF',
 PACK_TYPE='0603V',
 PART_NUMBER='E15431-004',
 LOCATION='C5G46',
 ROOM='PVDDQ_KLM',
 GROUP='PWR_MLCC_CAP',
 SEC='1',
 CDS_LIB='dev_discrete',
 CDS_PART_NAME='CAP_A_0603V-22.0UF,4V,20%,X6S,A',
 VOLTAGE='4V',
 PRIM_FILE='./archive_libs/discrete/cap_a/chips/chips.prt';

PART_NAME
 C5G47 'CAP_A_0603V-22.0UF,4V,20%,X6S,A':
 GROUP='PWR_MLCC_CAP',
 ROOM='PVDDQ_KLM';

SECTION_NUMBER 1
 '@BASEBOARD_FAB2_LIB.BASEBOARD_FAB2(SCH_1):PAGE242_I58@DEV_DISCRETE.CAP_A(CHIPS)':
 C_PATH='@baseboard_fab2_lib.baseboard_fab2(sch_1):page242_i58@dev_discrete.cap_~
a(chips)',
 P_PATH='@baseboard_fab2_lib.baseboard_fab2(sch_1):page242_i58@dev_discrete.cap_~
a(chips)',
 PATH='I58',
 DRAWING='@BASEBOARD_FAB2_LIB.BASEBOARD_FAB2(SCH_1):PAGE242',
 BOM_DS='NOPOP',
 TOLERANCE='20%',
 SEC_TYPE='0603V',
 MATERIAL='X6S',
 PHYS_PAGE='242',
 XY='(-5350,2800)',
 ROT='0',
 VER='1',
 VALUE='22.0UF',
 PACK_TYPE='0603V',
 PART_NUMBER='E15431-004',
 LOCATION='C5G47',
 ROOM='PVDDQ_KLM',
 GROUP='PWR_MLCC_CAP',
 SEC='1',
 CDS_LIB='dev_discrete',
 CDS_PART_NAME='CAP_A_0603V-22.0UF,4V,20%,X6S,A',
 VOLTAGE='4V',
 PRIM_FILE='./archive_libs/discrete/cap_a/chips/chips.prt';

PART_NAME
 C5G48 'CAP_A_0603V-22.0UF,4V,20%,X6S,A':
 GROUP='PWR_MLCC_CAP',
 ROOM='PVDDQ_KLM';

SECTION_NUMBER 1
 '@BASEBOARD_FAB2_LIB.BASEBOARD_FAB2(SCH_1):PAGE242_I57@DEV_DISCRETE.CAP_A(CHIPS)':
 C_PATH='@baseboard_fab2_lib.baseboard_fab2(sch_1):page242_i57@dev_discrete.cap_~
a(chips)',
 P_PATH='@baseboard_fab2_lib.baseboard_fab2(sch_1):page242_i57@dev_discrete.cap_~
a(chips)',
 PATH='I57',
 DRAWING='@BASEBOARD_FAB2_LIB.BASEBOARD_FAB2(SCH_1):PAGE242',
 BOM_DS='NOPOP',
 TOLERANCE='20%',
 SEC_TYPE='0603V',
 MATERIAL='X6S',
 PHYS_PAGE='242',
 XY='(-4950,2800)',
 ROT='0',
 VER='1',
 VALUE='22.0UF',
 PACK_TYPE='0603V',
 PART_NUMBER='E15431-004',
 LOCATION='C5G48',
 ROOM='PVDDQ_KLM',
 GROUP='PWR_MLCC_CAP',
 SEC='1',
 CDS_LIB='dev_discrete',
 CDS_PART_NAME='CAP_A_0603V-22.0UF,4V,20%,X6S,A',
 VOLTAGE='4V',
 PRIM_FILE='./archive_libs/discrete/cap_a/chips/chips.prt';

PART_NAME
 C5G49 'CAP_A_0603V-22.0UF,4V,20%,X6S,A':
 GROUP='PWR_MLCC_CAP',
 ROOM='PVDDQ_KLM';

SECTION_NUMBER 1
 '@BASEBOARD_FAB2_LIB.BASEBOARD_FAB2(SCH_1):PAGE242_I61@DEV_DISCRETE.CAP_A(CHIPS)':
 C_PATH='@baseboard_fab2_lib.baseboard_fab2(sch_1):page242_i61@dev_discrete.cap_~
a(chips)',
 P_PATH='@baseboard_fab2_lib.baseboard_fab2(sch_1):page242_i61@dev_discrete.cap_~
a(chips)',
 PATH='I61',
 DRAWING='@BASEBOARD_FAB2_LIB.BASEBOARD_FAB2(SCH_1):PAGE242',
 BOM_DS='NOPOP',
 TOLERANCE='20%',
 SEC_TYPE='0603V',
 MATERIAL='X6S',
 PHYS_PAGE='242',
 XY='(-4550,2800)',
 ROT='0',
 VER='1',
 VALUE='22.0UF',
 PACK_TYPE='0603V',
 PART_NUMBER='E15431-004',
 LOCATION='C5G49',
 ROOM='PVDDQ_KLM',
 GROUP='PWR_MLCC_CAP',
 SEC='1',
 CDS_LIB='dev_discrete',
 CDS_PART_NAME='CAP_A_0603V-22.0UF,4V,20%,X6S,A',
 VOLTAGE='4V',
 PRIM_FILE='./archive_libs/discrete/cap_a/chips/chips.prt';

PART_NAME
 C5G50 'CAP_A_0603V-22.0UF,4V,20%,X6S,A':
 GROUP='PWR_MLCC_CAP',
 ROOM='PVDDQ_KLM';

SECTION_NUMBER 1
 '@BASEBOARD_FAB2_LIB.BASEBOARD_FAB2(SCH_1):PAGE242_I70@DEV_DISCRETE.CAP_A(CHIPS)':
 C_PATH='@baseboard_fab2_lib.baseboard_fab2(sch_1):page242_i70@dev_discrete.cap_~
a(chips)',
 P_PATH='@baseboard_fab2_lib.baseboard_fab2(sch_1):page242_i70@dev_discrete.cap_~
a(chips)',
 PATH='I70',
 DRAWING='@BASEBOARD_FAB2_LIB.BASEBOARD_FAB2(SCH_1):PAGE242',
 BOM_DS='NOPOP',
 TOLERANCE='20%',
 SEC_TYPE='0603V',
 MATERIAL='X6S',
 PHYS_PAGE='242',
 XY='(-7750,1850)',
 ROT='0',
 VER='1',
 VALUE='22.0UF',
 PACK_TYPE='0603V',
 PART_NUMBER='E15431-004',
 LOCATION='C5G50',
 ROOM='PVDDQ_KLM',
 GROUP='PWR_MLCC_CAP',
 SEC='1',
 CDS_LIB='dev_discrete',
 CDS_PART_NAME='CAP_A_0603V-22.0UF,4V,20%,X6S,A',
 VOLTAGE='4V',
 PRIM_FILE='./archive_libs/discrete/cap_a/chips/chips.prt';

PART_NAME
 C5G51 'CAP_A_0603V-22.0UF,4V,20%,X6S,A':
 GROUP='PWR_MLCC_CAP',
 ROOM='PVDDQ_KLM';

SECTION_NUMBER 1
 '@BASEBOARD_FAB2_LIB.BASEBOARD_FAB2(SCH_1):PAGE242_I69@DEV_DISCRETE.CAP_A(CHIPS)':
 C_PATH='@baseboard_fab2_lib.baseboard_fab2(sch_1):page242_i69@dev_discrete.cap_~
a(chips)',
 P_PATH='@baseboard_fab2_lib.baseboard_fab2(sch_1):page242_i69@dev_discrete.cap_~
a(chips)',
 PATH='I69',
 DRAWING='@BASEBOARD_FAB2_LIB.BASEBOARD_FAB2(SCH_1):PAGE242',
 BOM_DS='NOPOP',
 TOLERANCE='20%',
 SEC_TYPE='0603V',
 MATERIAL='X6S',
 PHYS_PAGE='242',
 XY='(-7350,1850)',
 ROT='0',
 VER='1',
 VALUE='22.0UF',
 PACK_TYPE='0603V',
 PART_NUMBER='E15431-004',
 LOCATION='C5G51',
 ROOM='PVDDQ_KLM',
 GROUP='PWR_MLCC_CAP',
 SEC='1',
 CDS_LIB='dev_discrete',
 CDS_PART_NAME='CAP_A_0603V-22.0UF,4V,20%,X6S,A',
 VOLTAGE='4V',
 PRIM_FILE='./archive_libs/discrete/cap_a/chips/chips.prt';

PART_NAME
 C5G52 'CAP_A_0603V-22.0UF,4V,20%,X6S,A':
 GROUP='PWR_MLCC_CAP',
 ROOM='PVDDQ_KLM';

SECTION_NUMBER 1
 '@BASEBOARD_FAB2_LIB.BASEBOARD_FAB2(SCH_1):PAGE242_I68@DEV_DISCRETE.CAP_A(CHIPS)':
 C_PATH='@baseboard_fab2_lib.baseboard_fab2(sch_1):page242_i68@dev_discrete.cap_~
a(chips)',
 P_PATH='@baseboard_fab2_lib.baseboard_fab2(sch_1):page242_i68@dev_discrete.cap_~
a(chips)',
 PATH='I68',
 DRAWING='@BASEBOARD_FAB2_LIB.BASEBOARD_FAB2(SCH_1):PAGE242',
 BOM_DS='NOPOP',
 TOLERANCE='20%',
 SEC_TYPE='0603V',
 MATERIAL='X6S',
 PHYS_PAGE='242',
 XY='(-6950,1850)',
 ROT='0',
 VER='1',
 VALUE='22.0UF',
 PACK_TYPE='0603V',
 PART_NUMBER='E15431-004',
 LOCATION='C5G52',
 ROOM='PVDDQ_KLM',
 GROUP='PWR_MLCC_CAP',
 SEC='1',
 CDS_LIB='dev_discrete',
 CDS_PART_NAME='CAP_A_0603V-22.0UF,4V,20%,X6S,A',
 VOLTAGE='4V',
 PRIM_FILE='./archive_libs/discrete/cap_a/chips/chips.prt';

PART_NAME
 C5G53 'CAP_A_0603V-22.0UF,4V,20%,X6S,A':
 GROUP='PWR_MLCC_CAP',
 ROOM='PVDDQ_KLM';

SECTION_NUMBER 1
 '@BASEBOARD_FAB2_LIB.BASEBOARD_FAB2(SCH_1):PAGE242_I67@DEV_DISCRETE.CAP_A(CHIPS)':
 C_PATH='@baseboard_fab2_lib.baseboard_fab2(sch_1):page242_i67@dev_discrete.cap_~
a(chips)',
 P_PATH='@baseboard_fab2_lib.baseboard_fab2(sch_1):page242_i67@dev_discrete.cap_~
a(chips)',
 PATH='I67',
 DRAWING='@BASEBOARD_FAB2_LIB.BASEBOARD_FAB2(SCH_1):PAGE242',
 BOM_DS='NOPOP',
 TOLERANCE='20%',
 SEC_TYPE='0603V',
 MATERIAL='X6S',
 PHYS_PAGE='242',
 XY='(-6550,1850)',
 ROT='0',
 VER='1',
 VALUE='22.0UF',
 PACK_TYPE='0603V',
 PART_NUMBER='E15431-004',
 LOCATION='C5G53',
 ROOM='PVDDQ_KLM',
 GROUP='PWR_MLCC_CAP',
 SEC='1',
 CDS_LIB='dev_discrete',
 CDS_PART_NAME='CAP_A_0603V-22.0UF,4V,20%,X6S,A',
 VOLTAGE='4V',
 PRIM_FILE='./archive_libs/discrete/cap_a/chips/chips.prt';

PART_NAME
 C5G54 'CAP_A_0603V-22.0UF,4V,20%,X6S,A':
 GROUP='PWR_MLCC_CAP',
 ROOM='PVDDQ_KLM';

SECTION_NUMBER 1
 '@BASEBOARD_FAB2_LIB.BASEBOARD_FAB2(SCH_1):PAGE242_I62@DEV_DISCRETE.CAP_A(CHIPS)':
 C_PATH='@baseboard_fab2_lib.baseboard_fab2(sch_1):page242_i62@dev_discrete.cap_~
a(chips)',
 P_PATH='@baseboard_fab2_lib.baseboard_fab2(sch_1):page242_i62@dev_discrete.cap_~
a(chips)',
 PATH='I62',
 DRAWING='@BASEBOARD_FAB2_LIB.BASEBOARD_FAB2(SCH_1):PAGE242',
 BOM_DS='NOPOP',
 TOLERANCE='20%',
 SEC_TYPE='0603V',
 MATERIAL='X6S',
 PHYS_PAGE='242',
 XY='(-6150,1850)',
 ROT='0',
 VER='1',
 VALUE='22.0UF',
 PACK_TYPE='0603V',
 PART_NUMBER='E15431-004',
 LOCATION='C5G54',
 ROOM='PVDDQ_KLM',
 GROUP='PWR_MLCC_CAP',
 SEC='1',
 CDS_LIB='dev_discrete',
 CDS_PART_NAME='CAP_A_0603V-22.0UF,4V,20%,X6S,A',
 VOLTAGE='4V',
 PRIM_FILE='./archive_libs/discrete/cap_a/chips/chips.prt';

PART_NAME
 C5G55 'CAP_A_0603V-22.0UF,4V,20%,X6S,A':
 GROUP='PWR_MLCC_CAP',
 ROOM='PVDDQ_KLM';

SECTION_NUMBER 1
 '@BASEBOARD_FAB2_LIB.BASEBOARD_FAB2(SCH_1):PAGE242_I66@DEV_DISCRETE.CAP_A(CHIPS)':
 C_PATH='@baseboard_fab2_lib.baseboard_fab2(sch_1):page242_i66@dev_discrete.cap_~
a(chips)',
 P_PATH='@baseboard_fab2_lib.baseboard_fab2(sch_1):page242_i66@dev_discrete.cap_~
a(chips)',
 PATH='I66',
 DRAWING='@BASEBOARD_FAB2_LIB.BASEBOARD_FAB2(SCH_1):PAGE242',
 BOM_DS='NOPOP',
 TOLERANCE='20%',
 SEC_TYPE='0603V',
 MATERIAL='X6S',
 PHYS_PAGE='242',
 XY='(-5750,1850)',
 ROT='0',
 VER='1',
 VALUE='22.0UF',
 PACK_TYPE='0603V',
 PART_NUMBER='E15431-004',
 LOCATION='C5G55',
 ROOM='PVDDQ_KLM',
 GROUP='PWR_MLCC_CAP',
 SEC='1',
 CDS_LIB='dev_discrete',
 CDS_PART_NAME='CAP_A_0603V-22.0UF,4V,20%,X6S,A',
 VOLTAGE='4V',
 PRIM_FILE='./archive_libs/discrete/cap_a/chips/chips.prt';

PART_NAME
 C5G56 'CAP_A_0603V-22.0UF,4V,20%,X6S,A':
 GROUP='PWR_MLCC_CAP',
 ROOM='PVDDQ_KLM';

SECTION_NUMBER 1
 '@BASEBOARD_FAB2_LIB.BASEBOARD_FAB2(SCH_1):PAGE242_I65@DEV_DISCRETE.CAP_A(CHIPS)':
 C_PATH='@baseboard_fab2_lib.baseboard_fab2(sch_1):page242_i65@dev_discrete.cap_~
a(chips)',
 P_PATH='@baseboard_fab2_lib.baseboard_fab2(sch_1):page242_i65@dev_discrete.cap_~
a(chips)',
 PATH='I65',
 DRAWING='@BASEBOARD_FAB2_LIB.BASEBOARD_FAB2(SCH_1):PAGE242',
 BOM_DS='NOPOP',
 TOLERANCE='20%',
 SEC_TYPE='0603V',
 MATERIAL='X6S',
 PHYS_PAGE='242',
 XY='(-5350,1850)',
 ROT='0',
 VER='1',
 VALUE='22.0UF',
 PACK_TYPE='0603V',
 PART_NUMBER='E15431-004',
 LOCATION='C5G56',
 ROOM='PVDDQ_KLM',
 GROUP='PWR_MLCC_CAP',
 SEC='1',
 CDS_LIB='dev_discrete',
 CDS_PART_NAME='CAP_A_0603V-22.0UF,4V,20%,X6S,A',
 VOLTAGE='4V',
 PRIM_FILE='./archive_libs/discrete/cap_a/chips/chips.prt';

PART_NAME
 C5G57 'CAP_A_0603V-22.0UF,4V,20%,X6S,A':
 GROUP='PWR_MLCC_CAP',
 ROOM='PVDDQ_KLM';

SECTION_NUMBER 1
 '@BASEBOARD_FAB2_LIB.BASEBOARD_FAB2(SCH_1):PAGE242_I64@DEV_DISCRETE.CAP_A(CHIPS)':
 C_PATH='@baseboard_fab2_lib.baseboard_fab2(sch_1):page242_i64@dev_discrete.cap_~
a(chips)',
 P_PATH='@baseboard_fab2_lib.baseboard_fab2(sch_1):page242_i64@dev_discrete.cap_~
a(chips)',
 PATH='I64',
 DRAWING='@BASEBOARD_FAB2_LIB.BASEBOARD_FAB2(SCH_1):PAGE242',
 BOM_DS='NOPOP',
 TOLERANCE='20%',
 SEC_TYPE='0603V',
 MATERIAL='X6S',
 PHYS_PAGE='242',
 XY='(-4950,1850)',
 ROT='0',
 VER='1',
 VALUE='22.0UF',
 PACK_TYPE='0603V',
 PART_NUMBER='E15431-004',
 LOCATION='C5G57',
 ROOM='PVDDQ_KLM',
 GROUP='PWR_MLCC_CAP',
 SEC='1',
 CDS_LIB='dev_discrete',
 CDS_PART_NAME='CAP_A_0603V-22.0UF,4V,20%,X6S,A',
 VOLTAGE='4V',
 PRIM_FILE='./archive_libs/discrete/cap_a/chips/chips.prt';

PART_NAME
 C5G58 'CAP_A_0603V-22.0UF,4V,20%,X6S,A':
 GROUP='PWR_MLCC_CAP',
 ROOM='PVDDQ_KLM';

SECTION_NUMBER 1
 '@BASEBOARD_FAB2_LIB.BASEBOARD_FAB2(SCH_1):PAGE242_I63@DEV_DISCRETE.CAP_A(CHIPS)':
 C_PATH='@baseboard_fab2_lib.baseboard_fab2(sch_1):page242_i63@dev_discrete.cap_~
a(chips)',
 P_PATH='@baseboard_fab2_lib.baseboard_fab2(sch_1):page242_i63@dev_discrete.cap_~
a(chips)',
 PATH='I63',
 DRAWING='@BASEBOARD_FAB2_LIB.BASEBOARD_FAB2(SCH_1):PAGE242',
 BOM_DS='NOPOP',
 TOLERANCE='20%',
 SEC_TYPE='0603V',
 MATERIAL='X6S',
 PHYS_PAGE='242',
 XY='(-4550,1850)',
 ROT='0',
 VER='1',
 VALUE='22.0UF',
 PACK_TYPE='0603V',
 PART_NUMBER='E15431-004',
 LOCATION='C5G58',
 ROOM='PVDDQ_KLM',
 GROUP='PWR_MLCC_CAP',
 SEC='1',
 CDS_LIB='dev_discrete',
 CDS_PART_NAME='CAP_A_0603V-22.0UF,4V,20%,X6S,A',
 VOLTAGE='4V',
 PRIM_FILE='./archive_libs/discrete/cap_a/chips/chips.prt';

PART_NAME
 C5G59 'CAP_A_0603V-22.0UF,4V,20%,X6S,A':
 GROUP='PWR_MLCC_CAP',
 ROOM='PVDDQ_KLM';

SECTION_NUMBER 1
 '@BASEBOARD_FAB2_LIB.BASEBOARD_FAB2(SCH_1):PAGE242_I79@DEV_DISCRETE.CAP_A(CHIPS)':
 C_PATH='@baseboard_fab2_lib.baseboard_fab2(sch_1):page242_i79@dev_discrete.cap_~
a(chips)',
 P_PATH='@baseboard_fab2_lib.baseboard_fab2(sch_1):page242_i79@dev_discrete.cap_~
a(chips)',
 PATH='I79',
 DRAWING='@BASEBOARD_FAB2_LIB.BASEBOARD_FAB2(SCH_1):PAGE242',
 BOM_DS='NOPOP',
 TOLERANCE='20%',
 SEC_TYPE='0603V',
 MATERIAL='X6S',
 PHYS_PAGE='242',
 XY='(-3800,2800)',
 ROT='0',
 VER='1',
 VALUE='22.0UF',
 PACK_TYPE='0603V',
 PART_NUMBER='E15431-004',
 LOCATION='C5G59',
 ROOM='PVDDQ_KLM',
 GROUP='PWR_MLCC_CAP',
 SEC='1',
 CDS_LIB='dev_discrete',
 CDS_PART_NAME='CAP_A_0603V-22.0UF,4V,20%,X6S,A',
 VOLTAGE='4V',
 PRIM_FILE='./archive_libs/discrete/cap_a/chips/chips.prt';

PART_NAME
 C5G60 'CAP_A_0603V-22.0UF,4V,20%,X6S,A':
 GROUP='PWR_MLCC_CAP',
 ROOM='PVDDQ_KLM';

SECTION_NUMBER 1
 '@BASEBOARD_FAB2_LIB.BASEBOARD_FAB2(SCH_1):PAGE242_I78@DEV_DISCRETE.CAP_A(CHIPS)':
 C_PATH='@baseboard_fab2_lib.baseboard_fab2(sch_1):page242_i78@dev_discrete.cap_~
a(chips)',
 P_PATH='@baseboard_fab2_lib.baseboard_fab2(sch_1):page242_i78@dev_discrete.cap_~
a(chips)',
 PATH='I78',
 DRAWING='@BASEBOARD_FAB2_LIB.BASEBOARD_FAB2(SCH_1):PAGE242',
 BOM_DS='NOPOP',
 TOLERANCE='20%',
 SEC_TYPE='0603V',
 MATERIAL='X6S',
 PHYS_PAGE='242',
 XY='(-3400,2800)',
 ROT='0',
 VER='1',
 VALUE='22.0UF',
 PACK_TYPE='0603V',
 PART_NUMBER='E15431-004',
 LOCATION='C5G60',
 ROOM='PVDDQ_KLM',
 GROUP='PWR_MLCC_CAP',
 SEC='1',
 CDS_LIB='dev_discrete',
 CDS_PART_NAME='CAP_A_0603V-22.0UF,4V,20%,X6S,A',
 VOLTAGE='4V',
 PRIM_FILE='./archive_libs/discrete/cap_a/chips/chips.prt';

PART_NAME
 C5G61 'CAP_A_0603V-22.0UF,4V,20%,X6S,A':
 GROUP='PWR_MLCC_CAP',
 ROOM='PVDDQ_KLM';

SECTION_NUMBER 1
 '@BASEBOARD_FAB2_LIB.BASEBOARD_FAB2(SCH_1):PAGE242_I77@DEV_DISCRETE.CAP_A(CHIPS)':
 C_PATH='@baseboard_fab2_lib.baseboard_fab2(sch_1):page242_i77@dev_discrete.cap_~
a(chips)',
 P_PATH='@baseboard_fab2_lib.baseboard_fab2(sch_1):page242_i77@dev_discrete.cap_~
a(chips)',
 PATH='I77',
 DRAWING='@BASEBOARD_FAB2_LIB.BASEBOARD_FAB2(SCH_1):PAGE242',
 BOM_DS='NOPOP',
 TOLERANCE='20%',
 SEC_TYPE='0603V',
 MATERIAL='X6S',
 PHYS_PAGE='242',
 XY='(-3000,2800)',
 ROT='0',
 VER='1',
 VALUE='22.0UF',
 PACK_TYPE='0603V',
 PART_NUMBER='E15431-004',
 LOCATION='C5G61',
 ROOM='PVDDQ_KLM',
 GROUP='PWR_MLCC_CAP',
 SEC='1',
 CDS_LIB='dev_discrete',
 CDS_PART_NAME='CAP_A_0603V-22.0UF,4V,20%,X6S,A',
 VOLTAGE='4V',
 PRIM_FILE='./archive_libs/discrete/cap_a/chips/chips.prt';

PART_NAME
 C5G62 'CAP_A_0603V-22.0UF,4V,20%,X6S,A':
 GROUP='PWR_MLCC_CAP',
 ROOM='PVDDQ_KLM';

SECTION_NUMBER 1
 '@BASEBOARD_FAB2_LIB.BASEBOARD_FAB2(SCH_1):PAGE242_I76@DEV_DISCRETE.CAP_A(CHIPS)':
 C_PATH='@baseboard_fab2_lib.baseboard_fab2(sch_1):page242_i76@dev_discrete.cap_~
a(chips)',
 P_PATH='@baseboard_fab2_lib.baseboard_fab2(sch_1):page242_i76@dev_discrete.cap_~
a(chips)',
 PATH='I76',
 DRAWING='@BASEBOARD_FAB2_LIB.BASEBOARD_FAB2(SCH_1):PAGE242',
 BOM_DS='NOPOP',
 TOLERANCE='20%',
 SEC_TYPE='0603V',
 MATERIAL='X6S',
 PHYS_PAGE='242',
 XY='(-2600,2800)',
 ROT='0',
 VER='1',
 VALUE='22.0UF',
 PACK_TYPE='0603V',
 PART_NUMBER='E15431-004',
 LOCATION='C5G62',
 ROOM='PVDDQ_KLM',
 GROUP='PWR_MLCC_CAP',
 SEC='1',
 CDS_LIB='dev_discrete',
 CDS_PART_NAME='CAP_A_0603V-22.0UF,4V,20%,X6S,A',
 VOLTAGE='4V',
 PRIM_FILE='./archive_libs/discrete/cap_a/chips/chips.prt';

PART_NAME
 C5G63 'CAP_A_0603V-22.0UF,4V,20%,X6S,A':
 GROUP='PWR_MLCC_CAP',
 ROOM='PVDDQ_KLM';

SECTION_NUMBER 1
 '@BASEBOARD_FAB2_LIB.BASEBOARD_FAB2(SCH_1):PAGE242_I75@DEV_DISCRETE.CAP_A(CHIPS)':
 C_PATH='@baseboard_fab2_lib.baseboard_fab2(sch_1):page242_i75@dev_discrete.cap_~
a(chips)',
 P_PATH='@baseboard_fab2_lib.baseboard_fab2(sch_1):page242_i75@dev_discrete.cap_~
a(chips)',
 PATH='I75',
 DRAWING='@BASEBOARD_FAB2_LIB.BASEBOARD_FAB2(SCH_1):PAGE242',
 BOM_DS='NOPOP',
 TOLERANCE='20%',
 SEC_TYPE='0603V',
 MATERIAL='X6S',
 PHYS_PAGE='242',
 XY='(-2200,2800)',
 ROT='0',
 VER='1',
 VALUE='22.0UF',
 PACK_TYPE='0603V',
 PART_NUMBER='E15431-004',
 LOCATION='C5G63',
 ROOM='PVDDQ_KLM',
 GROUP='PWR_MLCC_CAP',
 SEC='1',
 CDS_LIB='dev_discrete',
 CDS_PART_NAME='CAP_A_0603V-22.0UF,4V,20%,X6S,A',
 VOLTAGE='4V',
 PRIM_FILE='./archive_libs/discrete/cap_a/chips/chips.prt';

PART_NAME
 C5G64 'CAP_A_0603V-22.0UF,4V,20%,X6S,A':
 GROUP='PWR_MLCC_CAP',
 ROOM='PVDDQ_KLM';

SECTION_NUMBER 1
 '@BASEBOARD_FAB2_LIB.BASEBOARD_FAB2(SCH_1):PAGE242_I74@DEV_DISCRETE.CAP_A(CHIPS)':
 C_PATH='@baseboard_fab2_lib.baseboard_fab2(sch_1):page242_i74@dev_discrete.cap_~
a(chips)',
 P_PATH='@baseboard_fab2_lib.baseboard_fab2(sch_1):page242_i74@dev_discrete.cap_~
a(chips)',
 PATH='I74',
 DRAWING='@BASEBOARD_FAB2_LIB.BASEBOARD_FAB2(SCH_1):PAGE242',
 BOM_DS='NOPOP',
 TOLERANCE='20%',
 SEC_TYPE='0603V',
 MATERIAL='X6S',
 PHYS_PAGE='242',
 XY='(-1800,2800)',
 ROT='0',
 VER='1',
 VALUE='22.0UF',
 PACK_TYPE='0603V',
 PART_NUMBER='E15431-004',
 LOCATION='C5G64',
 ROOM='PVDDQ_KLM',
 GROUP='PWR_MLCC_CAP',
 SEC='1',
 CDS_LIB='dev_discrete',
 CDS_PART_NAME='CAP_A_0603V-22.0UF,4V,20%,X6S,A',
 VOLTAGE='4V',
 PRIM_FILE='./archive_libs/discrete/cap_a/chips/chips.prt';

PART_NAME
 C5G65 'CAP_A_0603V-22.0UF,4V,20%,X6S,A':
 GROUP='PWR_MLCC_CAP',
 ROOM='PVDDQ_KLM';

SECTION_NUMBER 1
 '@BASEBOARD_FAB2_LIB.BASEBOARD_FAB2(SCH_1):PAGE242_I73@DEV_DISCRETE.CAP_A(CHIPS)':
 C_PATH='@baseboard_fab2_lib.baseboard_fab2(sch_1):page242_i73@dev_discrete.cap_~
a(chips)',
 P_PATH='@baseboard_fab2_lib.baseboard_fab2(sch_1):page242_i73@dev_discrete.cap_~
a(chips)',
 PATH='I73',
 DRAWING='@BASEBOARD_FAB2_LIB.BASEBOARD_FAB2(SCH_1):PAGE242',
 BOM_DS='NOPOP',
 TOLERANCE='20%',
 SEC_TYPE='0603V',
 MATERIAL='X6S',
 PHYS_PAGE='242',
 XY='(-1400,2800)',
 ROT='0',
 VER='1',
 VALUE='22.0UF',
 PACK_TYPE='0603V',
 PART_NUMBER='E15431-004',
 LOCATION='C5G65',
 ROOM='PVDDQ_KLM',
 GROUP='PWR_MLCC_CAP',
 SEC='1',
 CDS_LIB='dev_discrete',
 CDS_PART_NAME='CAP_A_0603V-22.0UF,4V,20%,X6S,A',
 VOLTAGE='4V',
 PRIM_FILE='./archive_libs/discrete/cap_a/chips/chips.prt';

PART_NAME
 C5G66 'CAP_A_0603V-22.0UF,4V,20%,X6S,A':
 GROUP='PWR_MLCC_CAP',
 ROOM='PVDDQ_KLM';

SECTION_NUMBER 1
 '@BASEBOARD_FAB2_LIB.BASEBOARD_FAB2(SCH_1):PAGE242_I72@DEV_DISCRETE.CAP_A(CHIPS)':
 C_PATH='@baseboard_fab2_lib.baseboard_fab2(sch_1):page242_i72@dev_discrete.cap_~
a(chips)',
 P_PATH='@baseboard_fab2_lib.baseboard_fab2(sch_1):page242_i72@dev_discrete.cap_~
a(chips)',
 PATH='I72',
 DRAWING='@BASEBOARD_FAB2_LIB.BASEBOARD_FAB2(SCH_1):PAGE242',
 BOM_DS='NOPOP',
 TOLERANCE='20%',
 SEC_TYPE='0603V',
 MATERIAL='X6S',
 PHYS_PAGE='242',
 XY='(-1000,2800)',
 ROT='0',
 VER='1',
 VALUE='22.0UF',
 PACK_TYPE='0603V',
 PART_NUMBER='E15431-004',
 LOCATION='C5G66',
 ROOM='PVDDQ_KLM',
 GROUP='PWR_MLCC_CAP',
 SEC='1',
 CDS_LIB='dev_discrete',
 CDS_PART_NAME='CAP_A_0603V-22.0UF,4V,20%,X6S,A',
 VOLTAGE='4V',
 PRIM_FILE='./archive_libs/discrete/cap_a/chips/chips.prt';

PART_NAME
 C5G67 'CAP_A_0603V-22.0UF,4V,20%,X6S,A':
 GROUP='PWR_MLCC_CAP',
 ROOM='PVDDQ_KLM';

SECTION_NUMBER 1
 '@BASEBOARD_FAB2_LIB.BASEBOARD_FAB2(SCH_1):PAGE242_I71@DEV_DISCRETE.CAP_A(CHIPS)':
 C_PATH='@baseboard_fab2_lib.baseboard_fab2(sch_1):page242_i71@dev_discrete.cap_~
a(chips)',
 P_PATH='@baseboard_fab2_lib.baseboard_fab2(sch_1):page242_i71@dev_discrete.cap_~
a(chips)',
 PATH='I71',
 DRAWING='@BASEBOARD_FAB2_LIB.BASEBOARD_FAB2(SCH_1):PAGE242',
 BOM_DS='NOPOP',
 TOLERANCE='20%',
 SEC_TYPE='0603V',
 MATERIAL='X6S',
 PHYS_PAGE='242',
 XY='(-600,2800)',
 ROT='0',
 VER='1',
 VALUE='22.0UF',
 PACK_TYPE='0603V',
 PART_NUMBER='E15431-004',
 LOCATION='C5G67',
 ROOM='PVDDQ_KLM',
 GROUP='PWR_MLCC_CAP',
 SEC='1',
 CDS_LIB='dev_discrete',
 CDS_PART_NAME='CAP_A_0603V-22.0UF,4V,20%,X6S,A',
 VOLTAGE='4V',
 PRIM_FILE='./archive_libs/discrete/cap_a/chips/chips.prt';

PART_NAME
 C5G68 'CAP_A_0603V-22.0UF,4V,20%,X6S,A':
 GROUP='PWR_MLCC_CAP',
 ROOM='PVDDQ_KLM';

SECTION_NUMBER 1
 '@BASEBOARD_FAB2_LIB.BASEBOARD_FAB2(SCH_1):PAGE242_I88@DEV_DISCRETE.CAP_A(CHIPS)':
 C_PATH='@baseboard_fab2_lib.baseboard_fab2(sch_1):page242_i88@dev_discrete.cap_~
a(chips)',
 P_PATH='@baseboard_fab2_lib.baseboard_fab2(sch_1):page242_i88@dev_discrete.cap_~
a(chips)',
 PATH='I88',
 DRAWING='@BASEBOARD_FAB2_LIB.BASEBOARD_FAB2(SCH_1):PAGE242',
 BOM_DS='NOPOP',
 TOLERANCE='20%',
 SEC_TYPE='0603V',
 MATERIAL='X6S',
 PHYS_PAGE='242',
 XY='(-3800,1850)',
 ROT='0',
 VER='1',
 VALUE='22.0UF',
 PACK_TYPE='0603V',
 PART_NUMBER='E15431-004',
 LOCATION='C5G68',
 ROOM='PVDDQ_KLM',
 GROUP='PWR_MLCC_CAP',
 SEC='1',
 CDS_LIB='dev_discrete',
 CDS_PART_NAME='CAP_A_0603V-22.0UF,4V,20%,X6S,A',
 VOLTAGE='4V',
 PRIM_FILE='./archive_libs/discrete/cap_a/chips/chips.prt';

PART_NAME
 C5G69 'CAP_A_0603V-22.0UF,4V,20%,X6S,A':
 GROUP='PWR_MLCC_CAP',
 ROOM='PVDDQ_KLM';

SECTION_NUMBER 1
 '@BASEBOARD_FAB2_LIB.BASEBOARD_FAB2(SCH_1):PAGE242_I87@DEV_DISCRETE.CAP_A(CHIPS)':
 C_PATH='@baseboard_fab2_lib.baseboard_fab2(sch_1):page242_i87@dev_discrete.cap_~
a(chips)',
 P_PATH='@baseboard_fab2_lib.baseboard_fab2(sch_1):page242_i87@dev_discrete.cap_~
a(chips)',
 PATH='I87',
 DRAWING='@BASEBOARD_FAB2_LIB.BASEBOARD_FAB2(SCH_1):PAGE242',
 BOM_DS='NOPOP',
 TOLERANCE='20%',
 SEC_TYPE='0603V',
 MATERIAL='X6S',
 PHYS_PAGE='242',
 XY='(-3400,1850)',
 ROT='0',
 VER='1',
 VALUE='22.0UF',
 PACK_TYPE='0603V',
 PART_NUMBER='E15431-004',
 LOCATION='C5G69',
 ROOM='PVDDQ_KLM',
 GROUP='PWR_MLCC_CAP',
 SEC='1',
 CDS_LIB='dev_discrete',
 CDS_PART_NAME='CAP_A_0603V-22.0UF,4V,20%,X6S,A',
 VOLTAGE='4V',
 PRIM_FILE='./archive_libs/discrete/cap_a/chips/chips.prt';

PART_NAME
 C5G70 'CAP_A_0603V-22.0UF,4V,20%,X6S,A':
 GROUP='PWR_MLCC_CAP',
 ROOM='PVDDQ_KLM';

SECTION_NUMBER 1
 '@BASEBOARD_FAB2_LIB.BASEBOARD_FAB2(SCH_1):PAGE242_I86@DEV_DISCRETE.CAP_A(CHIPS)':
 C_PATH='@baseboard_fab2_lib.baseboard_fab2(sch_1):page242_i86@dev_discrete.cap_~
a(chips)',
 P_PATH='@baseboard_fab2_lib.baseboard_fab2(sch_1):page242_i86@dev_discrete.cap_~
a(chips)',
 PATH='I86',
 DRAWING='@BASEBOARD_FAB2_LIB.BASEBOARD_FAB2(SCH_1):PAGE242',
 BOM_DS='NOPOP',
 TOLERANCE='20%',
 SEC_TYPE='0603V',
 MATERIAL='X6S',
 PHYS_PAGE='242',
 XY='(-3000,1850)',
 ROT='0',
 VER='1',
 VALUE='22.0UF',
 PACK_TYPE='0603V',
 PART_NUMBER='E15431-004',
 LOCATION='C5G70',
 ROOM='PVDDQ_KLM',
 GROUP='PWR_MLCC_CAP',
 SEC='1',
 CDS_LIB='dev_discrete',
 CDS_PART_NAME='CAP_A_0603V-22.0UF,4V,20%,X6S,A',
 VOLTAGE='4V',
 PRIM_FILE='./archive_libs/discrete/cap_a/chips/chips.prt';

PART_NAME
 C5G71 'CAP_A_0603V-22.0UF,4V,20%,X6S,A':
 GROUP='PWR_MLCC_CAP',
 ROOM='PVDDQ_KLM';

SECTION_NUMBER 1
 '@BASEBOARD_FAB2_LIB.BASEBOARD_FAB2(SCH_1):PAGE242_I85@DEV_DISCRETE.CAP_A(CHIPS)':
 C_PATH='@baseboard_fab2_lib.baseboard_fab2(sch_1):page242_i85@dev_discrete.cap_~
a(chips)',
 P_PATH='@baseboard_fab2_lib.baseboard_fab2(sch_1):page242_i85@dev_discrete.cap_~
a(chips)',
 PATH='I85',
 DRAWING='@BASEBOARD_FAB2_LIB.BASEBOARD_FAB2(SCH_1):PAGE242',
 BOM_DS='NOPOP',
 TOLERANCE='20%',
 SEC_TYPE='0603V',
 MATERIAL='X6S',
 PHYS_PAGE='242',
 XY='(-2600,1850)',
 ROT='0',
 VER='1',
 VALUE='22.0UF',
 PACK_TYPE='0603V',
 PART_NUMBER='E15431-004',
 LOCATION='C5G71',
 ROOM='PVDDQ_KLM',
 GROUP='PWR_MLCC_CAP',
 SEC='1',
 CDS_LIB='dev_discrete',
 CDS_PART_NAME='CAP_A_0603V-22.0UF,4V,20%,X6S,A',
 VOLTAGE='4V',
 PRIM_FILE='./archive_libs/discrete/cap_a/chips/chips.prt';

PART_NAME
 C5G72 'CAP_A_0603V-22.0UF,4V,20%,X6S,A':
 GROUP='PWR_MLCC_CAP',
 ROOM='PVDDQ_KLM';

SECTION_NUMBER 1
 '@BASEBOARD_FAB2_LIB.BASEBOARD_FAB2(SCH_1):PAGE242_I84@DEV_DISCRETE.CAP_A(CHIPS)':
 C_PATH='@baseboard_fab2_lib.baseboard_fab2(sch_1):page242_i84@dev_discrete.cap_~
a(chips)',
 P_PATH='@baseboard_fab2_lib.baseboard_fab2(sch_1):page242_i84@dev_discrete.cap_~
a(chips)',
 PATH='I84',
 DRAWING='@BASEBOARD_FAB2_LIB.BASEBOARD_FAB2(SCH_1):PAGE242',
 BOM_DS='NOPOP',
 TOLERANCE='20%',
 SEC_TYPE='0603V',
 MATERIAL='X6S',
 PHYS_PAGE='242',
 XY='(-2200,1850)',
 ROT='0',
 VER='1',
 VALUE='22.0UF',
 PACK_TYPE='0603V',
 PART_NUMBER='E15431-004',
 LOCATION='C5G72',
 ROOM='PVDDQ_KLM',
 GROUP='PWR_MLCC_CAP',
 SEC='1',
 CDS_LIB='dev_discrete',
 CDS_PART_NAME='CAP_A_0603V-22.0UF,4V,20%,X6S,A',
 VOLTAGE='4V',
 PRIM_FILE='./archive_libs/discrete/cap_a/chips/chips.prt';

PART_NAME
 C5G73 'CAP_A_0603V-22.0UF,4V,20%,X6S,A':
 GROUP='PWR_MLCC_CAP',
 ROOM='PVDDQ_KLM';

SECTION_NUMBER 1
 '@BASEBOARD_FAB2_LIB.BASEBOARD_FAB2(SCH_1):PAGE242_I83@DEV_DISCRETE.CAP_A(CHIPS)':
 C_PATH='@baseboard_fab2_lib.baseboard_fab2(sch_1):page242_i83@dev_discrete.cap_~
a(chips)',
 P_PATH='@baseboard_fab2_lib.baseboard_fab2(sch_1):page242_i83@dev_discrete.cap_~
a(chips)',
 PATH='I83',
 DRAWING='@BASEBOARD_FAB2_LIB.BASEBOARD_FAB2(SCH_1):PAGE242',
 BOM_DS='NOPOP',
 TOLERANCE='20%',
 SEC_TYPE='0603V',
 MATERIAL='X6S',
 PHYS_PAGE='242',
 XY='(-1800,1850)',
 ROT='0',
 VER='1',
 VALUE='22.0UF',
 PACK_TYPE='0603V',
 PART_NUMBER='E15431-004',
 LOCATION='C5G73',
 ROOM='PVDDQ_KLM',
 GROUP='PWR_MLCC_CAP',
 SEC='1',
 CDS_LIB='dev_discrete',
 CDS_PART_NAME='CAP_A_0603V-22.0UF,4V,20%,X6S,A',
 VOLTAGE='4V',
 PRIM_FILE='./archive_libs/discrete/cap_a/chips/chips.prt';

PART_NAME
 C5G74 'CAP_A_0603V-22.0UF,4V,20%,X6S,A':
 GROUP='PWR_MLCC_CAP',
 ROOM='PVDDQ_KLM';

SECTION_NUMBER 1
 '@BASEBOARD_FAB2_LIB.BASEBOARD_FAB2(SCH_1):PAGE242_I82@DEV_DISCRETE.CAP_A(CHIPS)':
 C_PATH='@baseboard_fab2_lib.baseboard_fab2(sch_1):page242_i82@dev_discrete.cap_~
a(chips)',
 P_PATH='@baseboard_fab2_lib.baseboard_fab2(sch_1):page242_i82@dev_discrete.cap_~
a(chips)',
 PATH='I82',
 DRAWING='@BASEBOARD_FAB2_LIB.BASEBOARD_FAB2(SCH_1):PAGE242',
 BOM_DS='NOPOP',
 TOLERANCE='20%',
 SEC_TYPE='0603V',
 MATERIAL='X6S',
 PHYS_PAGE='242',
 XY='(-1400,1850)',
 ROT='0',
 VER='1',
 VALUE='22.0UF',
 PACK_TYPE='0603V',
 PART_NUMBER='E15431-004',
 LOCATION='C5G74',
 ROOM='PVDDQ_KLM',
 GROUP='PWR_MLCC_CAP',
 SEC='1',
 CDS_LIB='dev_discrete',
 CDS_PART_NAME='CAP_A_0603V-22.0UF,4V,20%,X6S,A',
 VOLTAGE='4V',
 PRIM_FILE='./archive_libs/discrete/cap_a/chips/chips.prt';

PART_NAME
 C5G75 'CAP_A_0603V-22.0UF,4V,20%,X6S,A':
 GROUP='PWR_MLCC_CAP',
 ROOM='PVDDQ_KLM';

SECTION_NUMBER 1
 '@BASEBOARD_FAB2_LIB.BASEBOARD_FAB2(SCH_1):PAGE242_I81@DEV_DISCRETE.CAP_A(CHIPS)':
 C_PATH='@baseboard_fab2_lib.baseboard_fab2(sch_1):page242_i81@dev_discrete.cap_~
a(chips)',
 P_PATH='@baseboard_fab2_lib.baseboard_fab2(sch_1):page242_i81@dev_discrete.cap_~
a(chips)',
 PATH='I81',
 DRAWING='@BASEBOARD_FAB2_LIB.BASEBOARD_FAB2(SCH_1):PAGE242',
 BOM_DS='NOPOP',
 TOLERANCE='20%',
 SEC_TYPE='0603V',
 MATERIAL='X6S',
 PHYS_PAGE='242',
 XY='(-1000,1850)',
 ROT='0',
 VER='1',
 VALUE='22.0UF',
 PACK_TYPE='0603V',
 PART_NUMBER='E15431-004',
 LOCATION='C5G75',
 ROOM='PVDDQ_KLM',
 GROUP='PWR_MLCC_CAP',
 SEC='1',
 CDS_LIB='dev_discrete',
 CDS_PART_NAME='CAP_A_0603V-22.0UF,4V,20%,X6S,A',
 VOLTAGE='4V',
 PRIM_FILE='./archive_libs/discrete/cap_a/chips/chips.prt';

PART_NAME
 C5G76 'CAP_A_0603V-22.0UF,4V,20%,X6S,A':
 GROUP='PWR_MLCC_CAP',
 ROOM='PVDDQ_KLM';

SECTION_NUMBER 1
 '@BASEBOARD_FAB2_LIB.BASEBOARD_FAB2(SCH_1):PAGE242_I80@DEV_DISCRETE.CAP_A(CHIPS)':
 C_PATH='@baseboard_fab2_lib.baseboard_fab2(sch_1):page242_i80@dev_discrete.cap_~
a(chips)',
 P_PATH='@baseboard_fab2_lib.baseboard_fab2(sch_1):page242_i80@dev_discrete.cap_~
a(chips)',
 PATH='I80',
 DRAWING='@BASEBOARD_FAB2_LIB.BASEBOARD_FAB2(SCH_1):PAGE242',
 BOM_DS='NOPOP',
 TOLERANCE='20%',
 SEC_TYPE='0603V',
 MATERIAL='X6S',
 PHYS_PAGE='242',
 XY='(-600,1850)',
 ROT='0',
 VER='1',
 VALUE='22.0UF',
 PACK_TYPE='0603V',
 PART_NUMBER='E15431-004',
 LOCATION='C5G76',
 ROOM='PVDDQ_KLM',
 GROUP='PWR_MLCC_CAP',
 SEC='1',
 CDS_LIB='dev_discrete',
 CDS_PART_NAME='CAP_A_0603V-22.0UF,4V,20%,X6S,A',
 VOLTAGE='4V',
 PRIM_FILE='./archive_libs/discrete/cap_a/chips/chips.prt';

PART_NAME
 C5G77 'CAP_0805-47UF,4V,20%,X6S,C9533A':
 GROUP='PWR_MLCC_CAP',
 ROOM='PVCCIN_CPU0_DECAP_VR';

SECTION_NUMBER 1
 '@BASEBOARD_FAB2_LIB.BASEBOARD_FAB2(SCH_1):PAGE242_I89@MSTR_DISCRETE.CAP(CHIPS)':
 C_PATH='@baseboard_fab2_lib.baseboard_fab2(sch_1):page242_i89@mstr_discrete.cap~
(chips)',
 P_PATH='@baseboard_fab2_lib.baseboard_fab2(sch_1):page242_i89@mstr_discrete.cap~
(chips)',
 PATH='I89',
 DRAWING='@BASEBOARD_FAB2_LIB.BASEBOARD_FAB2(SCH_1):PAGE242',
 POP='NOPOP',
 TOLERANCE='20%',
 SEC_TYPE='0805',
 MATERIAL='X6S',
 BOM_COST='PROC_SOCKET',
 PHYS_PAGE='242',
 XY='(-3800,3775)',
 ROT='0',
 VER='1',
 VALUE='47UF',
 PACK_TYPE='0805',
 PART_NUMBER='C95333-006',
 LOCATION='C5G77',
 ROOM='PVCCIN_CPU0_DECAP_VR',
 GROUP='PWR_MLCC_CAP',
 SEC='1',
 CDS_LIB='mstr_discrete',
 CDS_PART_NAME='CAP_0805-47UF,4V,20%,X6S,C9533A',
 VOLTAGE='4V',
 PRIM_FILE='./archive_libs/mstr_discrete/cap/chips/chips.prt';

PART_NAME
 C5G78 'CAP_0805-47UF,4V,20%,X6S,C9533A':
 GROUP='PWR_MLCC_CAP',
 ROOM='PVCCIN_CPU0_DECAP_VR';

SECTION_NUMBER 1
 '@BASEBOARD_FAB2_LIB.BASEBOARD_FAB2(SCH_1):PAGE242_I91@MSTR_DISCRETE.CAP(CHIPS)':
 C_PATH='@baseboard_fab2_lib.baseboard_fab2(sch_1):page242_i91@mstr_discrete.cap~
(chips)',
 P_PATH='@baseboard_fab2_lib.baseboard_fab2(sch_1):page242_i91@mstr_discrete.cap~
(chips)',
 PATH='I91',
 DRAWING='@BASEBOARD_FAB2_LIB.BASEBOARD_FAB2(SCH_1):PAGE242',
 POP='NOPOP',
 TOLERANCE='20%',
 SEC_TYPE='0805',
 MATERIAL='X6S',
 BOM_COST='PROC_SOCKET',
 PHYS_PAGE='242',
 XY='(-3400,3775)',
 ROT='0',
 VER='1',
 VALUE='47UF',
 PACK_TYPE='0805',
 PART_NUMBER='C95333-006',
 LOCATION='C5G78',
 ROOM='PVCCIN_CPU0_DECAP_VR',
 GROUP='PWR_MLCC_CAP',
 SEC='1',
 CDS_LIB='mstr_discrete',
 CDS_PART_NAME='CAP_0805-47UF,4V,20%,X6S,C9533A',
 VOLTAGE='4V',
 PRIM_FILE='./archive_libs/mstr_discrete/cap/chips/chips.prt';

PART_NAME
 C5G79 'CAP_A_0603V-22.0UF,4V,20%,X6S,A':
 GROUP='PWR_MLCC_CAP',
 ROOM='PVDDQ_KLM';

SECTION_NUMBER 1
 '@BASEBOARD_FAB2_LIB.BASEBOARD_FAB2(SCH_1):PAGE243_I53@DEV_DISCRETE.CAP_A(CHIPS)':
 C_PATH='@baseboard_fab2_lib.baseboard_fab2(sch_1):page243_i53@dev_discrete.cap_~
a(chips)',
 P_PATH='@baseboard_fab2_lib.baseboard_fab2(sch_1):page243_i53@dev_discrete.cap_~
a(chips)',
 PATH='I53',
 DRAWING='@BASEBOARD_FAB2_LIB.BASEBOARD_FAB2(SCH_1):PAGE243',
 BOM_DS='NOPOP',
 TOLERANCE='20%',
 SEC_TYPE='0603V',
 MATERIAL='X6S',
 PHYS_PAGE='243',
 XY='(-7750,2800)',
 ROT='0',
 VER='1',
 VALUE='22.0UF',
 PACK_TYPE='0603V',
 PART_NUMBER='E15431-004',
 LOCATION='C5G79',
 ROOM='PVDDQ_KLM',
 GROUP='PWR_MLCC_CAP',
 SEC='1',
 CDS_LIB='dev_discrete',
 CDS_PART_NAME='CAP_A_0603V-22.0UF,4V,20%,X6S,A',
 VOLTAGE='4V',
 PRIM_FILE='./archive_libs/discrete/cap_a/chips/chips.prt';

PART_NAME
 C5G80 'CAP_A_0603V-22.0UF,4V,20%,X6S,A':
 GROUP='PWR_MLCC_CAP',
 ROOM='PVDDQ_KLM';

SECTION_NUMBER 1
 '@BASEBOARD_FAB2_LIB.BASEBOARD_FAB2(SCH_1):PAGE243_I61@DEV_DISCRETE.CAP_A(CHIPS)':
 C_PATH='@baseboard_fab2_lib.baseboard_fab2(sch_1):page243_i61@dev_discrete.cap_~
a(chips)',
 P_PATH='@baseboard_fab2_lib.baseboard_fab2(sch_1):page243_i61@dev_discrete.cap_~
a(chips)',
 PATH='I61',
 DRAWING='@BASEBOARD_FAB2_LIB.BASEBOARD_FAB2(SCH_1):PAGE243',
 BOM_DS='NOPOP',
 TOLERANCE='20%',
 SEC_TYPE='0603V',
 MATERIAL='X6S',
 PHYS_PAGE='243',
 XY='(-7350,2800)',
 ROT='0',
 VER='1',
 VALUE='22.0UF',
 PACK_TYPE='0603V',
 PART_NUMBER='E15431-004',
 LOCATION='C5G80',
 ROOM='PVDDQ_KLM',
 GROUP='PWR_MLCC_CAP',
 SEC='1',
 CDS_LIB='dev_discrete',
 CDS_PART_NAME='CAP_A_0603V-22.0UF,4V,20%,X6S,A',
 VOLTAGE='4V',
 PRIM_FILE='./archive_libs/discrete/cap_a/chips/chips.prt';

PART_NAME
 C5G81 'CAP_A_0603V-22.0UF,4V,20%,X6S,A':
 GROUP='PWR_MLCC_CAP',
 ROOM='PVDDQ_KLM';

SECTION_NUMBER 1
 '@BASEBOARD_FAB2_LIB.BASEBOARD_FAB2(SCH_1):PAGE243_I60@DEV_DISCRETE.CAP_A(CHIPS)':
 C_PATH='@baseboard_fab2_lib.baseboard_fab2(sch_1):page243_i60@dev_discrete.cap_~
a(chips)',
 P_PATH='@baseboard_fab2_lib.baseboard_fab2(sch_1):page243_i60@dev_discrete.cap_~
a(chips)',
 PATH='I60',
 DRAWING='@BASEBOARD_FAB2_LIB.BASEBOARD_FAB2(SCH_1):PAGE243',
 BOM_DS='NOPOP',
 TOLERANCE='20%',
 SEC_TYPE='0603V',
 MATERIAL='X6S',
 PHYS_PAGE='243',
 XY='(-6950,2800)',
 ROT='0',
 VER='1',
 VALUE='22.0UF',
 PACK_TYPE='0603V',
 PART_NUMBER='E15431-004',
 LOCATION='C5G81',
 ROOM='PVDDQ_KLM',
 GROUP='PWR_MLCC_CAP',
 SEC='1',
 CDS_LIB='dev_discrete',
 CDS_PART_NAME='CAP_A_0603V-22.0UF,4V,20%,X6S,A',
 VOLTAGE='4V',
 PRIM_FILE='./archive_libs/discrete/cap_a/chips/chips.prt';

PART_NAME
 C5G82 'CAP_A_0603V-22.0UF,4V,20%,X6S,A':
 GROUP='PWR_MLCC_CAP',
 ROOM='PVDDQ_KLM';

SECTION_NUMBER 1
 '@BASEBOARD_FAB2_LIB.BASEBOARD_FAB2(SCH_1):PAGE243_I59@DEV_DISCRETE.CAP_A(CHIPS)':
 C_PATH='@baseboard_fab2_lib.baseboard_fab2(sch_1):page243_i59@dev_discrete.cap_~
a(chips)',
 P_PATH='@baseboard_fab2_lib.baseboard_fab2(sch_1):page243_i59@dev_discrete.cap_~
a(chips)',
 PATH='I59',
 DRAWING='@BASEBOARD_FAB2_LIB.BASEBOARD_FAB2(SCH_1):PAGE243',
 BOM_DS='NOPOP',
 TOLERANCE='20%',
 SEC_TYPE='0603V',
 MATERIAL='X6S',
 PHYS_PAGE='243',
 XY='(-6550,2800)',
 ROT='0',
 VER='1',
 VALUE='22.0UF',
 PACK_TYPE='0603V',
 PART_NUMBER='E15431-004',
 LOCATION='C5G82',
 ROOM='PVDDQ_KLM',
 GROUP='PWR_MLCC_CAP',
 SEC='1',
 CDS_LIB='dev_discrete',
 CDS_PART_NAME='CAP_A_0603V-22.0UF,4V,20%,X6S,A',
 VOLTAGE='4V',
 PRIM_FILE='./archive_libs/discrete/cap_a/chips/chips.prt';

PART_NAME
 C5G83 'CAP_A_0603V-22.0UF,4V,20%,X6S,A':
 GROUP='PWR_MLCC_CAP',
 ROOM='PVDDQ_KLM';

SECTION_NUMBER 1
 '@BASEBOARD_FAB2_LIB.BASEBOARD_FAB2(SCH_1):PAGE243_I58@DEV_DISCRETE.CAP_A(CHIPS)':
 C_PATH='@baseboard_fab2_lib.baseboard_fab2(sch_1):page243_i58@dev_discrete.cap_~
a(chips)',
 P_PATH='@baseboard_fab2_lib.baseboard_fab2(sch_1):page243_i58@dev_discrete.cap_~
a(chips)',
 PATH='I58',
 DRAWING='@BASEBOARD_FAB2_LIB.BASEBOARD_FAB2(SCH_1):PAGE243',
 BOM_DS='NOPOP',
 TOLERANCE='20%',
 SEC_TYPE='0603V',
 MATERIAL='X6S',
 PHYS_PAGE='243',
 XY='(-6150,2800)',
 ROT='0',
 VER='1',
 VALUE='22.0UF',
 PACK_TYPE='0603V',
 PART_NUMBER='E15431-004',
 LOCATION='C5G83',
 ROOM='PVDDQ_KLM',
 GROUP='PWR_MLCC_CAP',
 SEC='1',
 CDS_LIB='dev_discrete',
 CDS_PART_NAME='CAP_A_0603V-22.0UF,4V,20%,X6S,A',
 VOLTAGE='4V',
 PRIM_FILE='./archive_libs/discrete/cap_a/chips/chips.prt';

PART_NAME
 C5G84 'CAP_A_0603V-22.0UF,4V,20%,X6S,A':
 GROUP='PWR_MLCC_CAP',
 ROOM='PVDDQ_KLM';

SECTION_NUMBER 1
 '@BASEBOARD_FAB2_LIB.BASEBOARD_FAB2(SCH_1):PAGE243_I57@DEV_DISCRETE.CAP_A(CHIPS)':
 C_PATH='@baseboard_fab2_lib.baseboard_fab2(sch_1):page243_i57@dev_discrete.cap_~
a(chips)',
 P_PATH='@baseboard_fab2_lib.baseboard_fab2(sch_1):page243_i57@dev_discrete.cap_~
a(chips)',
 PATH='I57',
 DRAWING='@BASEBOARD_FAB2_LIB.BASEBOARD_FAB2(SCH_1):PAGE243',
 BOM_DS='NOPOP',
 TOLERANCE='20%',
 SEC_TYPE='0603V',
 MATERIAL='X6S',
 PHYS_PAGE='243',
 XY='(-5750,2800)',
 ROT='0',
 VER='1',
 VALUE='22.0UF',
 PACK_TYPE='0603V',
 PART_NUMBER='E15431-004',
 LOCATION='C5G84',
 ROOM='PVDDQ_KLM',
 GROUP='PWR_MLCC_CAP',
 SEC='1',
 CDS_LIB='dev_discrete',
 CDS_PART_NAME='CAP_A_0603V-22.0UF,4V,20%,X6S,A',
 VOLTAGE='4V',
 PRIM_FILE='./archive_libs/discrete/cap_a/chips/chips.prt';

PART_NAME
 C5G85 'CAP_A_0603V-22.0UF,4V,20%,X6S,A':
 GROUP='PWR_MLCC_CAP',
 ROOM='PVDDQ_KLM';

SECTION_NUMBER 1
 '@BASEBOARD_FAB2_LIB.BASEBOARD_FAB2(SCH_1):PAGE243_I56@DEV_DISCRETE.CAP_A(CHIPS)':
 C_PATH='@baseboard_fab2_lib.baseboard_fab2(sch_1):page243_i56@dev_discrete.cap_~
a(chips)',
 P_PATH='@baseboard_fab2_lib.baseboard_fab2(sch_1):page243_i56@dev_discrete.cap_~
a(chips)',
 PATH='I56',
 DRAWING='@BASEBOARD_FAB2_LIB.BASEBOARD_FAB2(SCH_1):PAGE243',
 BOM_DS='NOPOP',
 TOLERANCE='20%',
 SEC_TYPE='0603V',
 MATERIAL='X6S',
 PHYS_PAGE='243',
 XY='(-5350,2800)',
 ROT='0',
 VER='1',
 VALUE='22.0UF',
 PACK_TYPE='0603V',
 PART_NUMBER='E15431-004',
 LOCATION='C5G85',
 ROOM='PVDDQ_KLM',
 GROUP='PWR_MLCC_CAP',
 SEC='1',
 CDS_LIB='dev_discrete',
 CDS_PART_NAME='CAP_A_0603V-22.0UF,4V,20%,X6S,A',
 VOLTAGE='4V',
 PRIM_FILE='./archive_libs/discrete/cap_a/chips/chips.prt';

PART_NAME
 C5G86 'CAP_A_0603V-22.0UF,4V,20%,X6S,A':
 GROUP='PWR_MLCC_CAP',
 ROOM='PVDDQ_KLM';

SECTION_NUMBER 1
 '@BASEBOARD_FAB2_LIB.BASEBOARD_FAB2(SCH_1):PAGE243_I55@DEV_DISCRETE.CAP_A(CHIPS)':
 C_PATH='@baseboard_fab2_lib.baseboard_fab2(sch_1):page243_i55@dev_discrete.cap_~
a(chips)',
 P_PATH='@baseboard_fab2_lib.baseboard_fab2(sch_1):page243_i55@dev_discrete.cap_~
a(chips)',
 PATH='I55',
 DRAWING='@BASEBOARD_FAB2_LIB.BASEBOARD_FAB2(SCH_1):PAGE243',
 BOM_DS='NOPOP',
 TOLERANCE='20%',
 SEC_TYPE='0603V',
 MATERIAL='X6S',
 PHYS_PAGE='243',
 XY='(-4950,2800)',
 ROT='0',
 VER='1',
 VALUE='22.0UF',
 PACK_TYPE='0603V',
 PART_NUMBER='E15431-004',
 LOCATION='C5G86',
 ROOM='PVDDQ_KLM',
 GROUP='PWR_MLCC_CAP',
 SEC='1',
 CDS_LIB='dev_discrete',
 CDS_PART_NAME='CAP_A_0603V-22.0UF,4V,20%,X6S,A',
 VOLTAGE='4V',
 PRIM_FILE='./archive_libs/discrete/cap_a/chips/chips.prt';

PART_NAME
 C5G87 'CAP_A_0603V-22.0UF,4V,20%,X6S,A':
 GROUP='PWR_MLCC_CAP',
 ROOM='PVDDQ_KLM';

SECTION_NUMBER 1
 '@BASEBOARD_FAB2_LIB.BASEBOARD_FAB2(SCH_1):PAGE243_I54@DEV_DISCRETE.CAP_A(CHIPS)':
 C_PATH='@baseboard_fab2_lib.baseboard_fab2(sch_1):page243_i54@dev_discrete.cap_~
a(chips)',
 P_PATH='@baseboard_fab2_lib.baseboard_fab2(sch_1):page243_i54@dev_discrete.cap_~
a(chips)',
 PATH='I54',
 DRAWING='@BASEBOARD_FAB2_LIB.BASEBOARD_FAB2(SCH_1):PAGE243',
 BOM_DS='NOPOP',
 TOLERANCE='20%',
 SEC_TYPE='0603V',
 MATERIAL='X6S',
 PHYS_PAGE='243',
 XY='(-4550,2775)',
 ROT='0',
 VER='1',
 VALUE='22.0UF',
 PACK_TYPE='0603V',
 PART_NUMBER='E15431-004',
 LOCATION='C5G87',
 ROOM='PVDDQ_KLM',
 GROUP='PWR_MLCC_CAP',
 SEC='1',
 CDS_LIB='dev_discrete',
 CDS_PART_NAME='CAP_A_0603V-22.0UF,4V,20%,X6S,A',
 VOLTAGE='4V',
 PRIM_FILE='./archive_libs/discrete/cap_a/chips/chips.prt';

PART_NAME
 C5G88 'CAP_A_0603V-22.0UF,4V,20%,X6S,A':
 GROUP='PWR_MLCC_CAP',
 ROOM='PVDDQ_KLM';

SECTION_NUMBER 1
 '@BASEBOARD_FAB2_LIB.BASEBOARD_FAB2(SCH_1):PAGE243_I70@DEV_DISCRETE.CAP_A(CHIPS)':
 C_PATH='@baseboard_fab2_lib.baseboard_fab2(sch_1):page243_i70@dev_discrete.cap_~
a(chips)',
 P_PATH='@baseboard_fab2_lib.baseboard_fab2(sch_1):page243_i70@dev_discrete.cap_~
a(chips)',
 PATH='I70',
 DRAWING='@BASEBOARD_FAB2_LIB.BASEBOARD_FAB2(SCH_1):PAGE243',
 BOM_DS='NOPOP',
 TOLERANCE='20%',
 SEC_TYPE='0603V',
 MATERIAL='X6S',
 PHYS_PAGE='243',
 XY='(-7750,1850)',
 ROT='0',
 VER='1',
 VALUE='22.0UF',
 PACK_TYPE='0603V',
 PART_NUMBER='E15431-004',
 LOCATION='C5G88',
 ROOM='PVDDQ_KLM',
 GROUP='PWR_MLCC_CAP',
 SEC='1',
 CDS_LIB='dev_discrete',
 CDS_PART_NAME='CAP_A_0603V-22.0UF,4V,20%,X6S,A',
 VOLTAGE='4V',
 PRIM_FILE='./archive_libs/discrete/cap_a/chips/chips.prt';

PART_NAME
 C5G89 'CAP_A_0603V-22.0UF,4V,20%,X6S,A':
 GROUP='PWR_MLCC_CAP',
 ROOM='PVDDQ_KLM';

SECTION_NUMBER 1
 '@BASEBOARD_FAB2_LIB.BASEBOARD_FAB2(SCH_1):PAGE243_I69@DEV_DISCRETE.CAP_A(CHIPS)':
 C_PATH='@baseboard_fab2_lib.baseboard_fab2(sch_1):page243_i69@dev_discrete.cap_~
a(chips)',
 P_PATH='@baseboard_fab2_lib.baseboard_fab2(sch_1):page243_i69@dev_discrete.cap_~
a(chips)',
 PATH='I69',
 DRAWING='@BASEBOARD_FAB2_LIB.BASEBOARD_FAB2(SCH_1):PAGE243',
 BOM_DS='NOPOP',
 TOLERANCE='20%',
 SEC_TYPE='0603V',
 MATERIAL='X6S',
 PHYS_PAGE='243',
 XY='(-7350,1850)',
 ROT='0',
 VER='1',
 VALUE='22.0UF',
 PACK_TYPE='0603V',
 PART_NUMBER='E15431-004',
 LOCATION='C5G89',
 ROOM='PVDDQ_KLM',
 GROUP='PWR_MLCC_CAP',
 SEC='1',
 CDS_LIB='dev_discrete',
 CDS_PART_NAME='CAP_A_0603V-22.0UF,4V,20%,X6S,A',
 VOLTAGE='4V',
 PRIM_FILE='./archive_libs/discrete/cap_a/chips/chips.prt';

PART_NAME
 C5G90 'CAP_A_0603V-22.0UF,4V,20%,X6S,A':
 GROUP='PWR_MLCC_CAP',
 ROOM='PVDDQ_KLM';

SECTION_NUMBER 1
 '@BASEBOARD_FAB2_LIB.BASEBOARD_FAB2(SCH_1):PAGE243_I68@DEV_DISCRETE.CAP_A(CHIPS)':
 C_PATH='@baseboard_fab2_lib.baseboard_fab2(sch_1):page243_i68@dev_discrete.cap_~
a(chips)',
 P_PATH='@baseboard_fab2_lib.baseboard_fab2(sch_1):page243_i68@dev_discrete.cap_~
a(chips)',
 PATH='I68',
 DRAWING='@BASEBOARD_FAB2_LIB.BASEBOARD_FAB2(SCH_1):PAGE243',
 BOM_DS='NOPOP',
 TOLERANCE='20%',
 SEC_TYPE='0603V',
 MATERIAL='X6S',
 PHYS_PAGE='243',
 XY='(-6950,1850)',
 ROT='0',
 VER='1',
 VALUE='22.0UF',
 PACK_TYPE='0603V',
 PART_NUMBER='E15431-004',
 LOCATION='C5G90',
 ROOM='PVDDQ_KLM',
 GROUP='PWR_MLCC_CAP',
 SEC='1',
 CDS_LIB='dev_discrete',
 CDS_PART_NAME='CAP_A_0603V-22.0UF,4V,20%,X6S,A',
 VOLTAGE='4V',
 PRIM_FILE='./archive_libs/discrete/cap_a/chips/chips.prt';

PART_NAME
 C5G91 'CAP_A_0603V-22.0UF,4V,20%,X6S,A':
 GROUP='PWR_MLCC_CAP',
 ROOM='PVDDQ_KLM';

SECTION_NUMBER 1
 '@BASEBOARD_FAB2_LIB.BASEBOARD_FAB2(SCH_1):PAGE243_I67@DEV_DISCRETE.CAP_A(CHIPS)':
 C_PATH='@baseboard_fab2_lib.baseboard_fab2(sch_1):page243_i67@dev_discrete.cap_~
a(chips)',
 P_PATH='@baseboard_fab2_lib.baseboard_fab2(sch_1):page243_i67@dev_discrete.cap_~
a(chips)',
 PATH='I67',
 DRAWING='@BASEBOARD_FAB2_LIB.BASEBOARD_FAB2(SCH_1):PAGE243',
 BOM_DS='NOPOP',
 TOLERANCE='20%',
 SEC_TYPE='0603V',
 MATERIAL='X6S',
 PHYS_PAGE='243',
 XY='(-6550,1850)',
 ROT='0',
 VER='1',
 VALUE='22.0UF',
 PACK_TYPE='0603V',
 PART_NUMBER='E15431-004',
 LOCATION='C5G91',
 ROOM='PVDDQ_KLM',
 GROUP='PWR_MLCC_CAP',
 SEC='1',
 CDS_LIB='dev_discrete',
 CDS_PART_NAME='CAP_A_0603V-22.0UF,4V,20%,X6S,A',
 VOLTAGE='4V',
 PRIM_FILE='./archive_libs/discrete/cap_a/chips/chips.prt';

PART_NAME
 C5G92 'CAP_A_0603V-22.0UF,4V,20%,X6S,A':
 GROUP='PWR_MLCC_CAP',
 ROOM='PVDDQ_KLM';

SECTION_NUMBER 1
 '@BASEBOARD_FAB2_LIB.BASEBOARD_FAB2(SCH_1):PAGE243_I66@DEV_DISCRETE.CAP_A(CHIPS)':
 C_PATH='@baseboard_fab2_lib.baseboard_fab2(sch_1):page243_i66@dev_discrete.cap_~
a(chips)',
 P_PATH='@baseboard_fab2_lib.baseboard_fab2(sch_1):page243_i66@dev_discrete.cap_~
a(chips)',
 PATH='I66',
 DRAWING='@BASEBOARD_FAB2_LIB.BASEBOARD_FAB2(SCH_1):PAGE243',
 BOM_DS='NOPOP',
 TOLERANCE='20%',
 SEC_TYPE='0603V',
 MATERIAL='X6S',
 PHYS_PAGE='243',
 XY='(-6150,1850)',
 ROT='0',
 VER='1',
 VALUE='22.0UF',
 PACK_TYPE='0603V',
 PART_NUMBER='E15431-004',
 LOCATION='C5G92',
 ROOM='PVDDQ_KLM',
 GROUP='PWR_MLCC_CAP',
 SEC='1',
 CDS_LIB='dev_discrete',
 CDS_PART_NAME='CAP_A_0603V-22.0UF,4V,20%,X6S,A',
 VOLTAGE='4V',
 PRIM_FILE='./archive_libs/discrete/cap_a/chips/chips.prt';

PART_NAME
 C5G93 'CAP_A_0603V-22.0UF,4V,20%,X6S,A':
 GROUP='PWR_MLCC_CAP',
 ROOM='PVDDQ_KLM';

SECTION_NUMBER 1
 '@BASEBOARD_FAB2_LIB.BASEBOARD_FAB2(SCH_1):PAGE243_I65@DEV_DISCRETE.CAP_A(CHIPS)':
 C_PATH='@baseboard_fab2_lib.baseboard_fab2(sch_1):page243_i65@dev_discrete.cap_~
a(chips)',
 P_PATH='@baseboard_fab2_lib.baseboard_fab2(sch_1):page243_i65@dev_discrete.cap_~
a(chips)',
 PATH='I65',
 DRAWING='@BASEBOARD_FAB2_LIB.BASEBOARD_FAB2(SCH_1):PAGE243',
 BOM_DS='NOPOP',
 TOLERANCE='20%',
 SEC_TYPE='0603V',
 MATERIAL='X6S',
 PHYS_PAGE='243',
 XY='(-5750,1850)',
 ROT='0',
 VER='1',
 VALUE='22.0UF',
 PACK_TYPE='0603V',
 PART_NUMBER='E15431-004',
 LOCATION='C5G93',
 ROOM='PVDDQ_KLM',
 GROUP='PWR_MLCC_CAP',
 SEC='1',
 CDS_LIB='dev_discrete',
 CDS_PART_NAME='CAP_A_0603V-22.0UF,4V,20%,X6S,A',
 VOLTAGE='4V',
 PRIM_FILE='./archive_libs/discrete/cap_a/chips/chips.prt';

PART_NAME
 C5G94 'CAP_A_0603V-22.0UF,4V,20%,X6S,A':
 GROUP='PWR_MLCC_CAP',
 ROOM='PVDDQ_KLM';

SECTION_NUMBER 1
 '@BASEBOARD_FAB2_LIB.BASEBOARD_FAB2(SCH_1):PAGE243_I64@DEV_DISCRETE.CAP_A(CHIPS)':
 C_PATH='@baseboard_fab2_lib.baseboard_fab2(sch_1):page243_i64@dev_discrete.cap_~
a(chips)',
 P_PATH='@baseboard_fab2_lib.baseboard_fab2(sch_1):page243_i64@dev_discrete.cap_~
a(chips)',
 PATH='I64',
 DRAWING='@BASEBOARD_FAB2_LIB.BASEBOARD_FAB2(SCH_1):PAGE243',
 BOM_DS='NOPOP',
 TOLERANCE='20%',
 SEC_TYPE='0603V',
 MATERIAL='X6S',
 PHYS_PAGE='243',
 XY='(-5350,1850)',
 ROT='0',
 VER='1',
 VALUE='22.0UF',
 PACK_TYPE='0603V',
 PART_NUMBER='E15431-004',
 LOCATION='C5G94',
 ROOM='PVDDQ_KLM',
 GROUP='PWR_MLCC_CAP',
 SEC='1',
 CDS_LIB='dev_discrete',
 CDS_PART_NAME='CAP_A_0603V-22.0UF,4V,20%,X6S,A',
 VOLTAGE='4V',
 PRIM_FILE='./archive_libs/discrete/cap_a/chips/chips.prt';

PART_NAME
 C5G95 'CAP_A_0603V-22.0UF,4V,20%,X6S,A':
 GROUP='PWR_MLCC_CAP',
 ROOM='PVDDQ_KLM';

SECTION_NUMBER 1
 '@BASEBOARD_FAB2_LIB.BASEBOARD_FAB2(SCH_1):PAGE243_I63@DEV_DISCRETE.CAP_A(CHIPS)':
 C_PATH='@baseboard_fab2_lib.baseboard_fab2(sch_1):page243_i63@dev_discrete.cap_~
a(chips)',
 P_PATH='@baseboard_fab2_lib.baseboard_fab2(sch_1):page243_i63@dev_discrete.cap_~
a(chips)',
 PATH='I63',
 DRAWING='@BASEBOARD_FAB2_LIB.BASEBOARD_FAB2(SCH_1):PAGE243',
 BOM_DS='NOPOP',
 TOLERANCE='20%',
 SEC_TYPE='0603V',
 MATERIAL='X6S',
 PHYS_PAGE='243',
 XY='(-4950,1850)',
 ROT='0',
 VER='1',
 VALUE='22.0UF',
 PACK_TYPE='0603V',
 PART_NUMBER='E15431-004',
 LOCATION='C5G95',
 ROOM='PVDDQ_KLM',
 GROUP='PWR_MLCC_CAP',
 SEC='1',
 CDS_LIB='dev_discrete',
 CDS_PART_NAME='CAP_A_0603V-22.0UF,4V,20%,X6S,A',
 VOLTAGE='4V',
 PRIM_FILE='./archive_libs/discrete/cap_a/chips/chips.prt';

PART_NAME
 C5G96 'CAP_A_0603V-22.0UF,4V,20%,X6S,A':
 GROUP='PWR_MLCC_CAP',
 ROOM='PVDDQ_KLM';

SECTION_NUMBER 1
 '@BASEBOARD_FAB2_LIB.BASEBOARD_FAB2(SCH_1):PAGE243_I62@DEV_DISCRETE.CAP_A(CHIPS)':
 C_PATH='@baseboard_fab2_lib.baseboard_fab2(sch_1):page243_i62@dev_discrete.cap_~
a(chips)',
 P_PATH='@baseboard_fab2_lib.baseboard_fab2(sch_1):page243_i62@dev_discrete.cap_~
a(chips)',
 PATH='I62',
 DRAWING='@BASEBOARD_FAB2_LIB.BASEBOARD_FAB2(SCH_1):PAGE243',
 BOM_DS='NOPOP',
 TOLERANCE='20%',
 SEC_TYPE='0603V',
 MATERIAL='X6S',
 PHYS_PAGE='243',
 XY='(-4550,1850)',
 ROT='0',
 VER='1',
 VALUE='22.0UF',
 PACK_TYPE='0603V',
 PART_NUMBER='E15431-004',
 LOCATION='C5G96',
 ROOM='PVDDQ_KLM',
 GROUP='PWR_MLCC_CAP',
 SEC='1',
 CDS_LIB='dev_discrete',
 CDS_PART_NAME='CAP_A_0603V-22.0UF,4V,20%,X6S,A',
 VOLTAGE='4V',
 PRIM_FILE='./archive_libs/discrete/cap_a/chips/chips.prt';

PART_NAME
 C5G97 'CAP_A_0603V-22.0UF,4V,20%,X6S,A':
 GROUP='PWR_MLCC_CAP',
 ROOM='PVDDQ_KLM';

SECTION_NUMBER 1
 '@BASEBOARD_FAB2_LIB.BASEBOARD_FAB2(SCH_1):PAGE243_I79@DEV_DISCRETE.CAP_A(CHIPS)':
 C_PATH='@baseboard_fab2_lib.baseboard_fab2(sch_1):page243_i79@dev_discrete.cap_~
a(chips)',
 P_PATH='@baseboard_fab2_lib.baseboard_fab2(sch_1):page243_i79@dev_discrete.cap_~
a(chips)',
 PATH='I79',
 DRAWING='@BASEBOARD_FAB2_LIB.BASEBOARD_FAB2(SCH_1):PAGE243',
 BOM_DS='NOPOP',
 TOLERANCE='20%',
 SEC_TYPE='0603V',
 MATERIAL='X6S',
 PHYS_PAGE='243',
 XY='(-3800,2800)',
 ROT='0',
 VER='1',
 VALUE='22.0UF',
 PACK_TYPE='0603V',
 PART_NUMBER='E15431-004',
 LOCATION='C5G97',
 ROOM='PVDDQ_KLM',
 GROUP='PWR_MLCC_CAP',
 SEC='1',
 CDS_LIB='dev_discrete',
 CDS_PART_NAME='CAP_A_0603V-22.0UF,4V,20%,X6S,A',
 VOLTAGE='4V',
 PRIM_FILE='./archive_libs/discrete/cap_a/chips/chips.prt';

PART_NAME
 C5G98 'CAP_A_0603V-22.0UF,4V,20%,X6S,A':
 GROUP='PWR_MLCC_CAP',
 ROOM='PVDDQ_KLM';

SECTION_NUMBER 1
 '@BASEBOARD_FAB2_LIB.BASEBOARD_FAB2(SCH_1):PAGE243_I78@DEV_DISCRETE.CAP_A(CHIPS)':
 C_PATH='@baseboard_fab2_lib.baseboard_fab2(sch_1):page243_i78@dev_discrete.cap_~
a(chips)',
 P_PATH='@baseboard_fab2_lib.baseboard_fab2(sch_1):page243_i78@dev_discrete.cap_~
a(chips)',
 PATH='I78',
 DRAWING='@BASEBOARD_FAB2_LIB.BASEBOARD_FAB2(SCH_1):PAGE243',
 BOM_DS='NOPOP',
 TOLERANCE='20%',
 SEC_TYPE='0603V',
 MATERIAL='X6S',
 PHYS_PAGE='243',
 XY='(-3400,2800)',
 ROT='0',
 VER='1',
 VALUE='22.0UF',
 PACK_TYPE='0603V',
 PART_NUMBER='E15431-004',
 LOCATION='C5G98',
 ROOM='PVDDQ_KLM',
 GROUP='PWR_MLCC_CAP',
 SEC='1',
 CDS_LIB='dev_discrete',
 CDS_PART_NAME='CAP_A_0603V-22.0UF,4V,20%,X6S,A',
 VOLTAGE='4V',
 PRIM_FILE='./archive_libs/discrete/cap_a/chips/chips.prt';

PART_NAME
 C5G99 'CAP_A_0603V-22.0UF,4V,20%,X6S,A':
 GROUP='PWR_MLCC_CAP',
 ROOM='PVDDQ_KLM';

SECTION_NUMBER 1
 '@BASEBOARD_FAB2_LIB.BASEBOARD_FAB2(SCH_1):PAGE243_I77@DEV_DISCRETE.CAP_A(CHIPS)':
 C_PATH='@baseboard_fab2_lib.baseboard_fab2(sch_1):page243_i77@dev_discrete.cap_~
a(chips)',
 P_PATH='@baseboard_fab2_lib.baseboard_fab2(sch_1):page243_i77@dev_discrete.cap_~
a(chips)',
 PATH='I77',
 DRAWING='@BASEBOARD_FAB2_LIB.BASEBOARD_FAB2(SCH_1):PAGE243',
 BOM_DS='NOPOP',
 TOLERANCE='20%',
 SEC_TYPE='0603V',
 MATERIAL='X6S',
 PHYS_PAGE='243',
 XY='(-3000,2800)',
 ROT='0',
 VER='1',
 VALUE='22.0UF',
 PACK_TYPE='0603V',
 PART_NUMBER='E15431-004',
 LOCATION='C5G99',
 ROOM='PVDDQ_KLM',
 GROUP='PWR_MLCC_CAP',
 SEC='1',
 CDS_LIB='dev_discrete',
 CDS_PART_NAME='CAP_A_0603V-22.0UF,4V,20%,X6S,A',
 VOLTAGE='4V',
 PRIM_FILE='./archive_libs/discrete/cap_a/chips/chips.prt';

PART_NAME
 C5G100 'CAP_A_0603V-22.0UF,4V,20%,X6S,A':
 GROUP='PWR_MLCC_CAP',
 ROOM='PVDDQ_KLM';

SECTION_NUMBER 1
 '@BASEBOARD_FAB2_LIB.BASEBOARD_FAB2(SCH_1):PAGE243_I76@DEV_DISCRETE.CAP_A(CHIPS)':
 C_PATH='@baseboard_fab2_lib.baseboard_fab2(sch_1):page243_i76@dev_discrete.cap_~
a(chips)',
 P_PATH='@baseboard_fab2_lib.baseboard_fab2(sch_1):page243_i76@dev_discrete.cap_~
a(chips)',
 PATH='I76',
 DRAWING='@BASEBOARD_FAB2_LIB.BASEBOARD_FAB2(SCH_1):PAGE243',
 BOM_DS='NOPOP',
 TOLERANCE='20%',
 SEC_TYPE='0603V',
 MATERIAL='X6S',
 PHYS_PAGE='243',
 XY='(-2600,2800)',
 ROT='0',
 VER='1',
 VALUE='22.0UF',
 PACK_TYPE='0603V',
 PART_NUMBER='E15431-004',
 LOCATION='C5G100',
 ROOM='PVDDQ_KLM',
 GROUP='PWR_MLCC_CAP',
 SEC='1',
 CDS_LIB='dev_discrete',
 CDS_PART_NAME='CAP_A_0603V-22.0UF,4V,20%,X6S,A',
 VOLTAGE='4V',
 PRIM_FILE='./archive_libs/discrete/cap_a/chips/chips.prt';

PART_NAME
 C5G101 'CAP_A_0603V-22.0UF,4V,20%,X6S,A':
 GROUP='PWR_MLCC_CAP',
 ROOM='PVDDQ_KLM';

SECTION_NUMBER 1
 '@BASEBOARD_FAB2_LIB.BASEBOARD_FAB2(SCH_1):PAGE243_I75@DEV_DISCRETE.CAP_A(CHIPS)':
 C_PATH='@baseboard_fab2_lib.baseboard_fab2(sch_1):page243_i75@dev_discrete.cap_~
a(chips)',
 P_PATH='@baseboard_fab2_lib.baseboard_fab2(sch_1):page243_i75@dev_discrete.cap_~
a(chips)',
 PATH='I75',
 DRAWING='@BASEBOARD_FAB2_LIB.BASEBOARD_FAB2(SCH_1):PAGE243',
 BOM_DS='NOPOP',
 TOLERANCE='20%',
 SEC_TYPE='0603V',
 MATERIAL='X6S',
 PHYS_PAGE='243',
 XY='(-2200,2800)',
 ROT='0',
 VER='1',
 VALUE='22.0UF',
 PACK_TYPE='0603V',
 PART_NUMBER='E15431-004',
 LOCATION='C5G101',
 ROOM='PVDDQ_KLM',
 GROUP='PWR_MLCC_CAP',
 SEC='1',
 CDS_LIB='dev_discrete',
 CDS_PART_NAME='CAP_A_0603V-22.0UF,4V,20%,X6S,A',
 VOLTAGE='4V',
 PRIM_FILE='./archive_libs/discrete/cap_a/chips/chips.prt';

PART_NAME
 C5G102 'CAP_A_0603V-22.0UF,4V,20%,X6S,A':
 GROUP='PWR_MLCC_CAP',
 ROOM='PVDDQ_KLM';

SECTION_NUMBER 1
 '@BASEBOARD_FAB2_LIB.BASEBOARD_FAB2(SCH_1):PAGE243_I74@DEV_DISCRETE.CAP_A(CHIPS)':
 C_PATH='@baseboard_fab2_lib.baseboard_fab2(sch_1):page243_i74@dev_discrete.cap_~
a(chips)',
 P_PATH='@baseboard_fab2_lib.baseboard_fab2(sch_1):page243_i74@dev_discrete.cap_~
a(chips)',
 PATH='I74',
 DRAWING='@BASEBOARD_FAB2_LIB.BASEBOARD_FAB2(SCH_1):PAGE243',
 BOM_DS='NOPOP',
 TOLERANCE='20%',
 SEC_TYPE='0603V',
 MATERIAL='X6S',
 PHYS_PAGE='243',
 XY='(-1800,2800)',
 ROT='0',
 VER='1',
 VALUE='22.0UF',
 PACK_TYPE='0603V',
 PART_NUMBER='E15431-004',
 LOCATION='C5G102',
 ROOM='PVDDQ_KLM',
 GROUP='PWR_MLCC_CAP',
 SEC='1',
 CDS_LIB='dev_discrete',
 CDS_PART_NAME='CAP_A_0603V-22.0UF,4V,20%,X6S,A',
 VOLTAGE='4V',
 PRIM_FILE='./archive_libs/discrete/cap_a/chips/chips.prt';

PART_NAME
 C5G103 'CAP_A_0603V-22.0UF,4V,20%,X6S,A':
 GROUP='PWR_MLCC_CAP',
 ROOM='PVDDQ_KLM';

SECTION_NUMBER 1
 '@BASEBOARD_FAB2_LIB.BASEBOARD_FAB2(SCH_1):PAGE243_I71@DEV_DISCRETE.CAP_A(CHIPS)':
 C_PATH='@baseboard_fab2_lib.baseboard_fab2(sch_1):page243_i71@dev_discrete.cap_~
a(chips)',
 P_PATH='@baseboard_fab2_lib.baseboard_fab2(sch_1):page243_i71@dev_discrete.cap_~
a(chips)',
 PATH='I71',
 DRAWING='@BASEBOARD_FAB2_LIB.BASEBOARD_FAB2(SCH_1):PAGE243',
 BOM_DS='NOPOP',
 TOLERANCE='20%',
 SEC_TYPE='0603V',
 MATERIAL='X6S',
 PHYS_PAGE='243',
 XY='(-1400,2800)',
 ROT='0',
 VER='1',
 VALUE='22.0UF',
 PACK_TYPE='0603V',
 PART_NUMBER='E15431-004',
 LOCATION='C5G103',
 ROOM='PVDDQ_KLM',
 GROUP='PWR_MLCC_CAP',
 SEC='1',
 CDS_LIB='dev_discrete',
 CDS_PART_NAME='CAP_A_0603V-22.0UF,4V,20%,X6S,A',
 VOLTAGE='4V',
 PRIM_FILE='./archive_libs/discrete/cap_a/chips/chips.prt';

PART_NAME
 C5G104 'CAP_A_0603V-22.0UF,4V,20%,X6S,A':
 GROUP='PWR_MLCC_CAP',
 ROOM='PVDDQ_KLM';

SECTION_NUMBER 1
 '@BASEBOARD_FAB2_LIB.BASEBOARD_FAB2(SCH_1):PAGE243_I72@DEV_DISCRETE.CAP_A(CHIPS)':
 C_PATH='@baseboard_fab2_lib.baseboard_fab2(sch_1):page243_i72@dev_discrete.cap_~
a(chips)',
 P_PATH='@baseboard_fab2_lib.baseboard_fab2(sch_1):page243_i72@dev_discrete.cap_~
a(chips)',
 PATH='I72',
 DRAWING='@BASEBOARD_FAB2_LIB.BASEBOARD_FAB2(SCH_1):PAGE243',
 BOM_DS='NOPOP',
 TOLERANCE='20%',
 SEC_TYPE='0603V',
 MATERIAL='X6S',
 PHYS_PAGE='243',
 XY='(-1000,2800)',
 ROT='0',
 VER='1',
 VALUE='22.0UF',
 PACK_TYPE='0603V',
 PART_NUMBER='E15431-004',
 LOCATION='C5G104',
 ROOM='PVDDQ_KLM',
 GROUP='PWR_MLCC_CAP',
 SEC='1',
 CDS_LIB='dev_discrete',
 CDS_PART_NAME='CAP_A_0603V-22.0UF,4V,20%,X6S,A',
 VOLTAGE='4V',
 PRIM_FILE='./archive_libs/discrete/cap_a/chips/chips.prt';

PART_NAME
 C5G105 'CAP_A_0603V-22.0UF,4V,20%,X6S,A':
 GROUP='PWR_MLCC_CAP',
 ROOM='PVDDQ_KLM';

SECTION_NUMBER 1
 '@BASEBOARD_FAB2_LIB.BASEBOARD_FAB2(SCH_1):PAGE243_I73@DEV_DISCRETE.CAP_A(CHIPS)':
 C_PATH='@baseboard_fab2_lib.baseboard_fab2(sch_1):page243_i73@dev_discrete.cap_~
a(chips)',
 P_PATH='@baseboard_fab2_lib.baseboard_fab2(sch_1):page243_i73@dev_discrete.cap_~
a(chips)',
 PATH='I73',
 DRAWING='@BASEBOARD_FAB2_LIB.BASEBOARD_FAB2(SCH_1):PAGE243',
 BOM_DS='NOPOP',
 TOLERANCE='20%',
 SEC_TYPE='0603V',
 MATERIAL='X6S',
 PHYS_PAGE='243',
 XY='(-600,2800)',
 ROT='0',
 VER='1',
 VALUE='22.0UF',
 PACK_TYPE='0603V',
 PART_NUMBER='E15431-004',
 LOCATION='C5G105',
 ROOM='PVDDQ_KLM',
 GROUP='PWR_MLCC_CAP',
 SEC='1',
 CDS_LIB='dev_discrete',
 CDS_PART_NAME='CAP_A_0603V-22.0UF,4V,20%,X6S,A',
 VOLTAGE='4V',
 PRIM_FILE='./archive_libs/discrete/cap_a/chips/chips.prt';

PART_NAME
 C5G106 'CAP_A_0603V-22.0UF,4V,20%,X6S,A':
 GROUP='PWR_MLCC_CAP',
 ROOM='PVDDQ_KLM';

SECTION_NUMBER 1
 '@BASEBOARD_FAB2_LIB.BASEBOARD_FAB2(SCH_1):PAGE243_I88@DEV_DISCRETE.CAP_A(CHIPS)':
 C_PATH='@baseboard_fab2_lib.baseboard_fab2(sch_1):page243_i88@dev_discrete.cap_~
a(chips)',
 P_PATH='@baseboard_fab2_lib.baseboard_fab2(sch_1):page243_i88@dev_discrete.cap_~
a(chips)',
 PATH='I88',
 DRAWING='@BASEBOARD_FAB2_LIB.BASEBOARD_FAB2(SCH_1):PAGE243',
 BOM_DS='NOPOP',
 TOLERANCE='20%',
 SEC_TYPE='0603V',
 MATERIAL='X6S',
 PHYS_PAGE='243',
 XY='(-3800,1850)',
 ROT='0',
 VER='1',
 VALUE='22.0UF',
 PACK_TYPE='0603V',
 PART_NUMBER='E15431-004',
 LOCATION='C5G106',
 ROOM='PVDDQ_KLM',
 GROUP='PWR_MLCC_CAP',
 SEC='1',
 CDS_LIB='dev_discrete',
 CDS_PART_NAME='CAP_A_0603V-22.0UF,4V,20%,X6S,A',
 VOLTAGE='4V',
 PRIM_FILE='./archive_libs/discrete/cap_a/chips/chips.prt';

PART_NAME
 C5G107 'CAP_A_0603V-22.0UF,4V,20%,X6S,A':
 GROUP='PWR_MLCC_CAP',
 ROOM='PVDDQ_KLM';

SECTION_NUMBER 1
 '@BASEBOARD_FAB2_LIB.BASEBOARD_FAB2(SCH_1):PAGE243_I87@DEV_DISCRETE.CAP_A(CHIPS)':
 C_PATH='@baseboard_fab2_lib.baseboard_fab2(sch_1):page243_i87@dev_discrete.cap_~
a(chips)',
 P_PATH='@baseboard_fab2_lib.baseboard_fab2(sch_1):page243_i87@dev_discrete.cap_~
a(chips)',
 PATH='I87',
 DRAWING='@BASEBOARD_FAB2_LIB.BASEBOARD_FAB2(SCH_1):PAGE243',
 BOM_DS='NOPOP',
 TOLERANCE='20%',
 SEC_TYPE='0603V',
 MATERIAL='X6S',
 PHYS_PAGE='243',
 XY='(-3400,1850)',
 ROT='0',
 VER='1',
 VALUE='22.0UF',
 PACK_TYPE='0603V',
 PART_NUMBER='E15431-004',
 LOCATION='C5G107',
 ROOM='PVDDQ_KLM',
 GROUP='PWR_MLCC_CAP',
 SEC='1',
 CDS_LIB='dev_discrete',
 CDS_PART_NAME='CAP_A_0603V-22.0UF,4V,20%,X6S,A',
 VOLTAGE='4V',
 PRIM_FILE='./archive_libs/discrete/cap_a/chips/chips.prt';

PART_NAME
 C5G108 'CAP_A_0603V-22.0UF,4V,20%,X6S,A':
 GROUP='PWR_MLCC_CAP',
 ROOM='PVDDQ_KLM';

SECTION_NUMBER 1
 '@BASEBOARD_FAB2_LIB.BASEBOARD_FAB2(SCH_1):PAGE243_I86@DEV_DISCRETE.CAP_A(CHIPS)':
 C_PATH='@baseboard_fab2_lib.baseboard_fab2(sch_1):page243_i86@dev_discrete.cap_~
a(chips)',
 P_PATH='@baseboard_fab2_lib.baseboard_fab2(sch_1):page243_i86@dev_discrete.cap_~
a(chips)',
 PATH='I86',
 DRAWING='@BASEBOARD_FAB2_LIB.BASEBOARD_FAB2(SCH_1):PAGE243',
 BOM_DS='NOPOP',
 TOLERANCE='20%',
 SEC_TYPE='0603V',
 MATERIAL='X6S',
 PHYS_PAGE='243',
 XY='(-3000,1850)',
 ROT='0',
 VER='1',
 VALUE='22.0UF',
 PACK_TYPE='0603V',
 PART_NUMBER='E15431-004',
 LOCATION='C5G108',
 ROOM='PVDDQ_KLM',
 GROUP='PWR_MLCC_CAP',
 SEC='1',
 CDS_LIB='dev_discrete',
 CDS_PART_NAME='CAP_A_0603V-22.0UF,4V,20%,X6S,A',
 VOLTAGE='4V',
 PRIM_FILE='./archive_libs/discrete/cap_a/chips/chips.prt';

PART_NAME
 C5G109 'CAP_A_0603V-22.0UF,4V,20%,X6S,A':
 GROUP='PWR_MLCC_CAP',
 ROOM='PVDDQ_KLM';

SECTION_NUMBER 1
 '@BASEBOARD_FAB2_LIB.BASEBOARD_FAB2(SCH_1):PAGE243_I85@DEV_DISCRETE.CAP_A(CHIPS)':
 C_PATH='@baseboard_fab2_lib.baseboard_fab2(sch_1):page243_i85@dev_discrete.cap_~
a(chips)',
 P_PATH='@baseboard_fab2_lib.baseboard_fab2(sch_1):page243_i85@dev_discrete.cap_~
a(chips)',
 PATH='I85',
 DRAWING='@BASEBOARD_FAB2_LIB.BASEBOARD_FAB2(SCH_1):PAGE243',
 BOM_DS='NOPOP',
 TOLERANCE='20%',
 SEC_TYPE='0603V',
 MATERIAL='X6S',
 PHYS_PAGE='243',
 XY='(-2600,1850)',
 ROT='0',
 VER='1',
 VALUE='22.0UF',
 PACK_TYPE='0603V',
 PART_NUMBER='E15431-004',
 LOCATION='C5G109',
 ROOM='PVDDQ_KLM',
 GROUP='PWR_MLCC_CAP',
 SEC='1',
 CDS_LIB='dev_discrete',
 CDS_PART_NAME='CAP_A_0603V-22.0UF,4V,20%,X6S,A',
 VOLTAGE='4V',
 PRIM_FILE='./archive_libs/discrete/cap_a/chips/chips.prt';

PART_NAME
 C5G110 'CAP_A_0603V-22.0UF,4V,20%,X6S,A':
 GROUP='PWR_MLCC_CAP',
 ROOM='PVDDQ_KLM';

SECTION_NUMBER 1
 '@BASEBOARD_FAB2_LIB.BASEBOARD_FAB2(SCH_1):PAGE243_I84@DEV_DISCRETE.CAP_A(CHIPS)':
 C_PATH='@baseboard_fab2_lib.baseboard_fab2(sch_1):page243_i84@dev_discrete.cap_~
a(chips)',
 P_PATH='@baseboard_fab2_lib.baseboard_fab2(sch_1):page243_i84@dev_discrete.cap_~
a(chips)',
 PATH='I84',
 DRAWING='@BASEBOARD_FAB2_LIB.BASEBOARD_FAB2(SCH_1):PAGE243',
 BOM_DS='NOPOP',
 TOLERANCE='20%',
 SEC_TYPE='0603V',
 MATERIAL='X6S',
 PHYS_PAGE='243',
 XY='(-2200,1850)',
 ROT='0',
 VER='1',
 VALUE='22.0UF',
 PACK_TYPE='0603V',
 PART_NUMBER='E15431-004',
 LOCATION='C5G110',
 ROOM='PVDDQ_KLM',
 GROUP='PWR_MLCC_CAP',
 SEC='1',
 CDS_LIB='dev_discrete',
 CDS_PART_NAME='CAP_A_0603V-22.0UF,4V,20%,X6S,A',
 VOLTAGE='4V',
 PRIM_FILE='./archive_libs/discrete/cap_a/chips/chips.prt';

PART_NAME
 C5G111 'CAP_A_0603V-22.0UF,4V,20%,X6S,A':
 GROUP='PWR_MLCC_CAP',
 ROOM='PVDDQ_KLM';

SECTION_NUMBER 1
 '@BASEBOARD_FAB2_LIB.BASEBOARD_FAB2(SCH_1):PAGE243_I83@DEV_DISCRETE.CAP_A(CHIPS)':
 C_PATH='@baseboard_fab2_lib.baseboard_fab2(sch_1):page243_i83@dev_discrete.cap_~
a(chips)',
 P_PATH='@baseboard_fab2_lib.baseboard_fab2(sch_1):page243_i83@dev_discrete.cap_~
a(chips)',
 PATH='I83',
 DRAWING='@BASEBOARD_FAB2_LIB.BASEBOARD_FAB2(SCH_1):PAGE243',
 BOM_DS='NOPOP',
 TOLERANCE='20%',
 SEC_TYPE='0603V',
 MATERIAL='X6S',
 PHYS_PAGE='243',
 XY='(-1800,1850)',
 ROT='0',
 VER='1',
 VALUE='22.0UF',
 PACK_TYPE='0603V',
 PART_NUMBER='E15431-004',
 LOCATION='C5G111',
 ROOM='PVDDQ_KLM',
 GROUP='PWR_MLCC_CAP',
 SEC='1',
 CDS_LIB='dev_discrete',
 CDS_PART_NAME='CAP_A_0603V-22.0UF,4V,20%,X6S,A',
 VOLTAGE='4V',
 PRIM_FILE='./archive_libs/discrete/cap_a/chips/chips.prt';

PART_NAME
 C5G112 'CAP_A_0603V-22.0UF,4V,20%,X6S,A':
 GROUP='PWR_MLCC_CAP',
 ROOM='PVDDQ_KLM';

SECTION_NUMBER 1
 '@BASEBOARD_FAB2_LIB.BASEBOARD_FAB2(SCH_1):PAGE243_I82@DEV_DISCRETE.CAP_A(CHIPS)':
 C_PATH='@baseboard_fab2_lib.baseboard_fab2(sch_1):page243_i82@dev_discrete.cap_~
a(chips)',
 P_PATH='@baseboard_fab2_lib.baseboard_fab2(sch_1):page243_i82@dev_discrete.cap_~
a(chips)',
 PATH='I82',
 DRAWING='@BASEBOARD_FAB2_LIB.BASEBOARD_FAB2(SCH_1):PAGE243',
 BOM_DS='NOPOP',
 TOLERANCE='20%',
 SEC_TYPE='0603V',
 MATERIAL='X6S',
 PHYS_PAGE='243',
 XY='(-1400,1850)',
 ROT='0',
 VER='1',
 VALUE='22.0UF',
 PACK_TYPE='0603V',
 PART_NUMBER='E15431-004',
 LOCATION='C5G112',
 ROOM='PVDDQ_KLM',
 GROUP='PWR_MLCC_CAP',
 SEC='1',
 CDS_LIB='dev_discrete',
 CDS_PART_NAME='CAP_A_0603V-22.0UF,4V,20%,X6S,A',
 VOLTAGE='4V',
 PRIM_FILE='./archive_libs/discrete/cap_a/chips/chips.prt';

PART_NAME
 C5G113 'CAP_A_0603V-22.0UF,4V,20%,X6S,A':
 GROUP='PWR_MLCC_CAP',
 ROOM='PVDDQ_KLM';

SECTION_NUMBER 1
 '@BASEBOARD_FAB2_LIB.BASEBOARD_FAB2(SCH_1):PAGE243_I81@DEV_DISCRETE.CAP_A(CHIPS)':
 C_PATH='@baseboard_fab2_lib.baseboard_fab2(sch_1):page243_i81@dev_discrete.cap_~
a(chips)',
 P_PATH='@baseboard_fab2_lib.baseboard_fab2(sch_1):page243_i81@dev_discrete.cap_~
a(chips)',
 PATH='I81',
 DRAWING='@BASEBOARD_FAB2_LIB.BASEBOARD_FAB2(SCH_1):PAGE243',
 BOM_DS='NOPOP',
 TOLERANCE='20%',
 SEC_TYPE='0603V',
 MATERIAL='X6S',
 PHYS_PAGE='243',
 XY='(-1000,1850)',
 ROT='0',
 VER='1',
 VALUE='22.0UF',
 PACK_TYPE='0603V',
 PART_NUMBER='E15431-004',
 LOCATION='C5G113',
 ROOM='PVDDQ_KLM',
 GROUP='PWR_MLCC_CAP',
 SEC='1',
 CDS_LIB='dev_discrete',
 CDS_PART_NAME='CAP_A_0603V-22.0UF,4V,20%,X6S,A',
 VOLTAGE='4V',
 PRIM_FILE='./archive_libs/discrete/cap_a/chips/chips.prt';

PART_NAME
 C5G114 'CAP_A_0603V-22.0UF,4V,20%,X6S,A':
 GROUP='PWR_MLCC_CAP',
 ROOM='PVDDQ_KLM';

SECTION_NUMBER 1
 '@BASEBOARD_FAB2_LIB.BASEBOARD_FAB2(SCH_1):PAGE243_I80@DEV_DISCRETE.CAP_A(CHIPS)':
 C_PATH='@baseboard_fab2_lib.baseboard_fab2(sch_1):page243_i80@dev_discrete.cap_~
a(chips)',
 P_PATH='@baseboard_fab2_lib.baseboard_fab2(sch_1):page243_i80@dev_discrete.cap_~
a(chips)',
 PATH='I80',
 DRAWING='@BASEBOARD_FAB2_LIB.BASEBOARD_FAB2(SCH_1):PAGE243',
 BOM_DS='NOPOP',
 TOLERANCE='20%',
 SEC_TYPE='0603V',
 MATERIAL='X6S',
 PHYS_PAGE='243',
 XY='(-600,1850)',
 ROT='0',
 VER='1',
 VALUE='22.0UF',
 PACK_TYPE='0603V',
 PART_NUMBER='E15431-004',
 LOCATION='C5G114',
 ROOM='PVDDQ_KLM',
 GROUP='PWR_MLCC_CAP',
 SEC='1',
 CDS_LIB='dev_discrete',
 CDS_PART_NAME='CAP_A_0603V-22.0UF,4V,20%,X6S,A',
 VOLTAGE='4V',
 PRIM_FILE='./archive_libs/discrete/cap_a/chips/chips.prt';

PART_NAME
 C5G115 'CAP_0805-47UF,4V,20%,X6S,C9533A':
 GROUP='PWR_MLCC_CAP',
 ROOM='PVCCIN_CPU0_DECAP_VR';

SECTION_NUMBER 1
 '@BASEBOARD_FAB2_LIB.BASEBOARD_FAB2(SCH_1):PAGE243_I89@MSTR_DISCRETE.CAP(CHIPS)':
 C_PATH='@baseboard_fab2_lib.baseboard_fab2(sch_1):page243_i89@mstr_discrete.cap~
(chips)',
 P_PATH='@baseboard_fab2_lib.baseboard_fab2(sch_1):page243_i89@mstr_discrete.cap~
(chips)',
 PATH='I89',
 DRAWING='@BASEBOARD_FAB2_LIB.BASEBOARD_FAB2(SCH_1):PAGE243',
 POP='NOPOP',
 TOLERANCE='20%',
 SEC_TYPE='0805',
 MATERIAL='X6S',
 BOM_COST='PROC_SOCKET',
 PHYS_PAGE='243',
 XY='(-3800,3775)',
 ROT='0',
 VER='1',
 VALUE='47UF',
 PACK_TYPE='0805',
 PART_NUMBER='C95333-006',
 LOCATION='C5G115',
 ROOM='PVCCIN_CPU0_DECAP_VR',
 GROUP='PWR_MLCC_CAP',
 SEC='1',
 CDS_LIB='mstr_discrete',
 CDS_PART_NAME='CAP_0805-47UF,4V,20%,X6S,C9533A',
 VOLTAGE='4V',
 PRIM_FILE='./archive_libs/mstr_discrete/cap/chips/chips.prt';

PART_NAME
 C5G116 'CAP_0805-47UF,4V,20%,X6S,C9533A':
 GROUP='PWR_MLCC_CAP',
 ROOM='PVCCIN_CPU0_DECAP_VR';

SECTION_NUMBER 1
 '@BASEBOARD_FAB2_LIB.BASEBOARD_FAB2(SCH_1):PAGE243_I90@MSTR_DISCRETE.CAP(CHIPS)':
 C_PATH='@baseboard_fab2_lib.baseboard_fab2(sch_1):page243_i90@mstr_discrete.cap~
(chips)',
 P_PATH='@baseboard_fab2_lib.baseboard_fab2(sch_1):page243_i90@mstr_discrete.cap~
(chips)',
 PATH='I90',
 DRAWING='@BASEBOARD_FAB2_LIB.BASEBOARD_FAB2(SCH_1):PAGE243',
 POP='NOPOP',
 TOLERANCE='20%',
 SEC_TYPE='0805',
 MATERIAL='X6S',
 BOM_COST='PROC_SOCKET',
 PHYS_PAGE='243',
 XY='(-3400,3775)',
 ROT='0',
 VER='1',
 VALUE='47UF',
 PACK_TYPE='0805',
 PART_NUMBER='C95333-006',
 LOCATION='C5G116',
 ROOM='PVCCIN_CPU0_DECAP_VR',
 GROUP='PWR_MLCC_CAP',
 SEC='1',
 CDS_LIB='mstr_discrete',
 CDS_PART_NAME='CAP_0805-47UF,4V,20%,X6S,C9533A',
 VOLTAGE='4V',
 PRIM_FILE='./archive_libs/mstr_discrete/cap/chips/chips.prt';

PART_NAME
 C5G117 'CAP_0805-47UF,4V,20%,X6S,C9533A':
 GROUP='PWR_MLCC_CAP',
 ROOM='PVCCIN_CPU0_DECAP_VR';

SECTION_NUMBER 1
 '@BASEBOARD_FAB2_LIB.BASEBOARD_FAB2(SCH_1):PAGE243_I92@MSTR_DISCRETE.CAP(CHIPS)':
 C_PATH='@baseboard_fab2_lib.baseboard_fab2(sch_1):page243_i92@mstr_discrete.cap~
(chips)',
 P_PATH='@baseboard_fab2_lib.baseboard_fab2(sch_1):page243_i92@mstr_discrete.cap~
(chips)',
 PATH='I92',
 DRAWING='@BASEBOARD_FAB2_LIB.BASEBOARD_FAB2(SCH_1):PAGE243',
 POP='NOPOP',
 TOLERANCE='20%',
 SEC_TYPE='0805',
 MATERIAL='X6S',
 BOM_COST='PROC_SOCKET',
 PHYS_PAGE='243',
 XY='(-7750,3750)',
 ROT='0',
 VER='1',
 VALUE='47UF',
 PACK_TYPE='0805',
 PART_NUMBER='C95333-006',
 LOCATION='C5G117',
 ROOM='PVCCIN_CPU0_DECAP_VR',
 GROUP='PWR_MLCC_CAP',
 SEC='1',
 CDS_LIB='mstr_discrete',
 CDS_PART_NAME='CAP_0805-47UF,4V,20%,X6S,C9533A',
 VOLTAGE='4V',
 PRIM_FILE='./archive_libs/mstr_discrete/cap/chips/chips.prt';

PART_NAME
 C5G118 'CAP_0805-47UF,4V,20%,X6S,C9533A':
 GROUP='PWR_MLCC_CAP',
 ROOM='PVCCIN_CPU0_DECAP_VR';

SECTION_NUMBER 1
 '@BASEBOARD_FAB2_LIB.BASEBOARD_FAB2(SCH_1):PAGE243_I91@MSTR_DISCRETE.CAP(CHIPS)':
 C_PATH='@baseboard_fab2_lib.baseboard_fab2(sch_1):page243_i91@mstr_discrete.cap~
(chips)',
 P_PATH='@baseboard_fab2_lib.baseboard_fab2(sch_1):page243_i91@mstr_discrete.cap~
(chips)',
 PATH='I91',
 DRAWING='@BASEBOARD_FAB2_LIB.BASEBOARD_FAB2(SCH_1):PAGE243',
 POP='NOPOP',
 TOLERANCE='20%',
 SEC_TYPE='0805',
 MATERIAL='X6S',
 BOM_COST='PROC_SOCKET',
 PHYS_PAGE='243',
 XY='(-7350,3750)',
 ROT='0',
 VER='1',
 VALUE='47UF',
 PACK_TYPE='0805',
 PART_NUMBER='C95333-006',
 LOCATION='C5G118',
 ROOM='PVCCIN_CPU0_DECAP_VR',
 GROUP='PWR_MLCC_CAP',
 SEC='1',
 CDS_LIB='mstr_discrete',
 CDS_PART_NAME='CAP_0805-47UF,4V,20%,X6S,C9533A',
 VOLTAGE='4V',
 PRIM_FILE='./archive_libs/mstr_discrete/cap/chips/chips.prt';

PART_NAME
 C5L1 'CAP_0805-100UF,4V,20%,X5R,6024A':
 GROUP='PWR_MLCC_CAP',
 ROOM='VDDQ_ABC_PWR_VR';

SECTION_NUMBER 1
 '@BASEBOARD_FAB2_LIB.BASEBOARD_FAB2(SCH_1):PAGE220_I309@MSTR_DISCRETE.CAP(CHIPS)':
 C_PATH='@baseboard_fab2_lib.baseboard_fab2(sch_1):page220_i309@mstr_discrete.ca~
p(chips)',
 P_PATH='@baseboard_fab2_lib.baseboard_fab2(sch_1):page220_i309@mstr_discrete.ca~
p(chips)',
 PATH='I309',
 DRAWING='@BASEBOARD_FAB2_LIB.BASEBOARD_FAB2(SCH_1):PAGE220',
 NEW_PN='078.1071T.M002',
 NEW_MATERIAL='X6S',
 BOM_SS='NOPOP',
 TOLERANCE='20%',
 SEC_TYPE='0805',
 MATERIAL='X5R',
 BOM_COST='MEM_VRD_PVDDQ_CD',
 PHYS_PAGE='220',
 XY='(3150,2825)',
 ROT='0',
 VER='1',
 VALUE='100UF',
 PACK_TYPE='0805',
 PART_NUMBER='602433-112',
 LOCATION='C5L1',
 ROOM='VDDQ_ABC_PWR_VR',
 GROUP='PWR_MLCC_CAP',
 SEC='1',
 CDS_LIB='mstr_discrete',
 CDS_PART_NAME='CAP_0805-100UF,4V,20%,X5R,6024A',
 VOLTAGE='4V',
 PRIM_FILE='./archive_libs/mstr_discrete/cap/chips/chips.prt';

PART_NAME
 C5L2 'CAP_0805-100UF,4V,20%,X5R,6024A':
 GROUP='PWR_MLCC_CAP',
 ROOM='VDDQ_ABC_PWR_VR';

SECTION_NUMBER 1
 '@BASEBOARD_FAB2_LIB.BASEBOARD_FAB2(SCH_1):PAGE220_I311@MSTR_DISCRETE.CAP(CHIPS)':
 C_PATH='@baseboard_fab2_lib.baseboard_fab2(sch_1):page220_i311@mstr_discrete.ca~
p(chips)',
 P_PATH='@baseboard_fab2_lib.baseboard_fab2(sch_1):page220_i311@mstr_discrete.ca~
p(chips)',
 PATH='I311',
 DRAWING='@BASEBOARD_FAB2_LIB.BASEBOARD_FAB2(SCH_1):PAGE220',
 NEW_PN='078.1071T.M002',
 NEW_MATERIAL='X6S',
 BOM_SS='NOPOP',
 TOLERANCE='20%',
 MATERIAL='X5R',
 BOM_COST='MEM_VRD_PVDDQ_CD',
 PHYS_PAGE='220',
 XY='(3500,2825)',
 ROT='0',
 VER='1',
 VALUE='100UF',
 PACK_TYPE='0805',
 PART_NUMBER='602433-112',
 LOCATION='C5L2',
 ROOM='VDDQ_ABC_PWR_VR',
 GROUP='PWR_MLCC_CAP',
 CDS_LIB='mstr_discrete',
 CDS_PART_NAME='CAP_0805-100UF,4V,20%,X5R,6024A',
 VOLTAGE='4V',
 PRIM_FILE='./archive_libs/mstr_discrete/cap/chips/chips.prt';

PART_NAME
 C5L3 'CAP_0805-100UF,4V,20%,X5R,6024A':
 GROUP='PWR_MLCC_CAP',
 ROOM='VDDQ_ABC_PWR_VR';

SECTION_NUMBER 1
 '@BASEBOARD_FAB2_LIB.BASEBOARD_FAB2(SCH_1):PAGE220_I310@MSTR_DISCRETE.CAP(CHIPS)':
 C_PATH='@baseboard_fab2_lib.baseboard_fab2(sch_1):page220_i310@mstr_discrete.ca~
p(chips)',
 P_PATH='@baseboard_fab2_lib.baseboard_fab2(sch_1):page220_i310@mstr_discrete.ca~
p(chips)',
 PATH='I310',
 DRAWING='@BASEBOARD_FAB2_LIB.BASEBOARD_FAB2(SCH_1):PAGE220',
 NEW_PN='078.1071T.M002',
 NEW_MATERIAL='X6S',
 BOM_SS='NOPOP',
 TOLERANCE='20%',
 SEC_TYPE='0805',
 MATERIAL='X5R',
 BOM_COST='MEM_VRD_PVDDQ_CD',
 PHYS_PAGE='220',
 XY='(3850,2825)',
 ROT='0',
 VER='1',
 VALUE='100UF',
 PACK_TYPE='0805',
 PART_NUMBER='602433-112',
 LOCATION='C5L3',
 ROOM='VDDQ_ABC_PWR_VR',
 GROUP='PWR_MLCC_CAP',
 SEC='1',
 CDS_LIB='mstr_discrete',
 CDS_PART_NAME='CAP_0805-100UF,4V,20%,X5R,6024A',
 VOLTAGE='4V',
 PRIM_FILE='./archive_libs/mstr_discrete/cap/chips/chips.prt';

PART_NAME
 C5L4 'CAP_0805-100UF,4V,20%,X5R,6024A':
 GROUP='PWR_MLCC_CAP',
 ROOM='VDDQ_ABC_PWR_VR';

SECTION_NUMBER 1
 '@BASEBOARD_FAB2_LIB.BASEBOARD_FAB2(SCH_1):PAGE222_I45@MSTR_DISCRETE.CAP(CHIPS)':
 C_PATH='@baseboard_fab2_lib.baseboard_fab2(sch_1):page222_i45@mstr_discrete.cap~
(chips)',
 P_PATH='@baseboard_fab2_lib.baseboard_fab2(sch_1):page222_i45@mstr_discrete.cap~
(chips)',
 PATH='I45',
 DRAWING='@BASEBOARD_FAB2_LIB.BASEBOARD_FAB2(SCH_1):PAGE222',
 NEW_PN='078.1071T.M002',
 NEW_MATERIAL='X6S',
 TOLERANCE='20%',
 SEC_TYPE='0805',
 MATERIAL='X5R',
 BOM_COST='MEM_VRD_PVDDQ_CD',
 PHYS_PAGE='222',
 XY='(2750,2825)',
 ROT='0',
 VER='1',
 VALUE='100UF',
 PACK_TYPE='0805',
 PART_NUMBER='602433-112',
 LOCATION='C5L4',
 ROOM='VDDQ_ABC_PWR_VR',
 GROUP='PWR_MLCC_CAP',
 SEC='1',
 CDS_LIB='mstr_discrete',
 CDS_PART_NAME='CAP_0805-100UF,4V,20%,X5R,6024A',
 VOLTAGE='4V',
 PRIM_FILE='./archive_libs/mstr_discrete/cap/chips/chips.prt';

PART_NAME
 C5L5 'CAP_0805-100UF,4V,20%,X5R,6024A':
 GROUP='PWR_MLCC_CAP',
 ROOM='VDDQ_ABC_PWR_VR';

SECTION_NUMBER 1
 '@BASEBOARD_FAB2_LIB.BASEBOARD_FAB2(SCH_1):PAGE222_I44@MSTR_DISCRETE.CAP(CHIPS)':
 C_PATH='@baseboard_fab2_lib.baseboard_fab2(sch_1):page222_i44@mstr_discrete.cap~
(chips)',
 P_PATH='@baseboard_fab2_lib.baseboard_fab2(sch_1):page222_i44@mstr_discrete.cap~
(chips)',
 PATH='I44',
 DRAWING='@BASEBOARD_FAB2_LIB.BASEBOARD_FAB2(SCH_1):PAGE222',
 NEW_PN='078.1071T.M002',
 NEW_MATERIAL='X6S',
 TOLERANCE='20%',
 SEC_TYPE='0805',
 MATERIAL='X5R',
 BOM_COST='MEM_VRD_PVDDQ_CD',
 PHYS_PAGE='222',
 XY='(3100,2825)',
 ROT='0',
 VER='1',
 VALUE='100UF',
 PACK_TYPE='0805',
 PART_NUMBER='602433-112',
 LOCATION='C5L5',
 ROOM='VDDQ_ABC_PWR_VR',
 GROUP='PWR_MLCC_CAP',
 SEC='1',
 CDS_LIB='mstr_discrete',
 CDS_PART_NAME='CAP_0805-100UF,4V,20%,X5R,6024A',
 VOLTAGE='4V',
 PRIM_FILE='./archive_libs/mstr_discrete/cap/chips/chips.prt';

PART_NAME
 C5L6 'CAP_A_0603V-47UF,4V,20%,X5R,60A':
 GROUP='PWR_MLCC_CAP';

SECTION_NUMBER 1
 '@BASEBOARD_FAB2_LIB.BASEBOARD_FAB2(SCH_1):PAGE220_I278@DEV_DISCRETE.CAP_A(CHIPS)':
 C_PATH='@baseboard_fab2_lib.baseboard_fab2(sch_1):page220_i278@dev_discrete.cap~
_a(chips)',
 P_PATH='@baseboard_fab2_lib.baseboard_fab2(sch_1):page220_i278@dev_discrete.cap~
_a(chips)',
 PATH='I278',
 DRAWING='@BASEBOARD_FAB2_LIB.BASEBOARD_FAB2(SCH_1):PAGE220',
 BOM_SS='E15431-004',
 TOLERANCE='20%',
 SEC_TYPE='0603V',
 MATERIAL='X5R',
 PHYS_PAGE='220',
 XY='(-2150,-650)',
 ROT='0',
 VER='1',
 VALUE='47UF',
 PACK_TYPE='0603V',
 PART_NUMBER='602433-106',
 LOCATION='C5L6',
 GROUP='PWR_MLCC_CAP',
 SEC='1',
 CDS_LIB='dev_discrete',
 CDS_PART_NAME='CAP_A_0603V-47UF,4V,20%,X5R,60A',
 VOLTAGE='4V',
 PRIM_FILE='./archive_libs/discrete/cap_a/chips/chips.prt';

PART_NAME
 C5L7 'CAP_A_0603V-47UF,4V,20%,X5R,60A':
 GROUP='PWR_MLCC_CAP';

SECTION_NUMBER 1
 '@BASEBOARD_FAB2_LIB.BASEBOARD_FAB2(SCH_1):PAGE220_I279@DEV_DISCRETE.CAP_A(CHIPS)':
 C_PATH='@baseboard_fab2_lib.baseboard_fab2(sch_1):page220_i279@dev_discrete.cap~
_a(chips)',
 P_PATH='@baseboard_fab2_lib.baseboard_fab2(sch_1):page220_i279@dev_discrete.cap~
_a(chips)',
 PATH='I279',
 DRAWING='@BASEBOARD_FAB2_LIB.BASEBOARD_FAB2(SCH_1):PAGE220',
 BOM_SS='E15431-004',
 TOLERANCE='20%',
 SEC_TYPE='0603V',
 MATERIAL='X5R',
 PHYS_PAGE='220',
 XY='(-1850,-650)',
 ROT='0',
 VER='1',
 VALUE='47UF',
 PACK_TYPE='0603V',
 PART_NUMBER='602433-106',
 LOCATION='C5L7',
 GROUP='PWR_MLCC_CAP',
 SEC='1',
 CDS_LIB='dev_discrete',
 CDS_PART_NAME='CAP_A_0603V-47UF,4V,20%,X5R,60A',
 VOLTAGE='4V',
 PRIM_FILE='./archive_libs/discrete/cap_a/chips/chips.prt';

PART_NAME
 C5L8 'CAP_A_0603V-47UF,4V,20%,X5R,60A':
 GROUP='PWR_MLCC_CAP';

SECTION_NUMBER 1
 '@BASEBOARD_FAB2_LIB.BASEBOARD_FAB2(SCH_1):PAGE220_I280@DEV_DISCRETE.CAP_A(CHIPS)':
 C_PATH='@baseboard_fab2_lib.baseboard_fab2(sch_1):page220_i280@dev_discrete.cap~
_a(chips)',
 P_PATH='@baseboard_fab2_lib.baseboard_fab2(sch_1):page220_i280@dev_discrete.cap~
_a(chips)',
 PATH='I280',
 DRAWING='@BASEBOARD_FAB2_LIB.BASEBOARD_FAB2(SCH_1):PAGE220',
 BOM_SS='E15431-004',
 TOLERANCE='20%',
 SEC_TYPE='0603V',
 MATERIAL='X5R',
 PHYS_PAGE='220',
 XY='(-1550,-650)',
 ROT='0',
 VER='1',
 VALUE='47UF',
 PACK_TYPE='0603V',
 PART_NUMBER='602433-106',
 LOCATION='C5L8',
 GROUP='PWR_MLCC_CAP',
 SEC='1',
 CDS_LIB='dev_discrete',
 CDS_PART_NAME='CAP_A_0603V-47UF,4V,20%,X5R,60A',
 VOLTAGE='4V',
 PRIM_FILE='./archive_libs/discrete/cap_a/chips/chips.prt';

PART_NAME
 C5L9 'CAP_A_0603V-47UF,4V,20%,X5R,60A':
 GROUP='PWR_MLCC_CAP';

SECTION_NUMBER 1
 '@BASEBOARD_FAB2_LIB.BASEBOARD_FAB2(SCH_1):PAGE220_I281@DEV_DISCRETE.CAP_A(CHIPS)':
 C_PATH='@baseboard_fab2_lib.baseboard_fab2(sch_1):page220_i281@dev_discrete.cap~
_a(chips)',
 P_PATH='@baseboard_fab2_lib.baseboard_fab2(sch_1):page220_i281@dev_discrete.cap~
_a(chips)',
 PATH='I281',
 DRAWING='@BASEBOARD_FAB2_LIB.BASEBOARD_FAB2(SCH_1):PAGE220',
 BOM_SS='E15431-004',
 TOLERANCE='20%',
 SEC_TYPE='0603V',
 MATERIAL='X5R',
 PHYS_PAGE='220',
 XY='(-1275,-650)',
 ROT='0',
 VER='1',
 VALUE='47UF',
 PACK_TYPE='0603V',
 PART_NUMBER='602433-106',
 LOCATION='C5L9',
 GROUP='PWR_MLCC_CAP',
 SEC='1',
 CDS_LIB='dev_discrete',
 CDS_PART_NAME='CAP_A_0603V-47UF,4V,20%,X5R,60A',
 VOLTAGE='4V',
 PRIM_FILE='./archive_libs/discrete/cap_a/chips/chips.prt';

PART_NAME
 C5L10 'CAP_A_0603V-47UF,4V,20%,X5R,60A':
 GROUP='PWR_MLCC_CAP';

SECTION_NUMBER 1
 '@BASEBOARD_FAB2_LIB.BASEBOARD_FAB2(SCH_1):PAGE220_I282@DEV_DISCRETE.CAP_A(CHIPS)':
 C_PATH='@baseboard_fab2_lib.baseboard_fab2(sch_1):page220_i282@dev_discrete.cap~
_a(chips)',
 P_PATH='@baseboard_fab2_lib.baseboard_fab2(sch_1):page220_i282@dev_discrete.cap~
_a(chips)',
 PATH='I282',
 DRAWING='@BASEBOARD_FAB2_LIB.BASEBOARD_FAB2(SCH_1):PAGE220',
 BOM_SS='E15431-004',
 TOLERANCE='20%',
 SEC_TYPE='0603V',
 MATERIAL='X5R',
 PHYS_PAGE='220',
 XY='(-1000,-650)',
 ROT='0',
 VER='1',
 VALUE='47UF',
 PACK_TYPE='0603V',
 PART_NUMBER='602433-106',
 LOCATION='C5L10',
 GROUP='PWR_MLCC_CAP',
 SEC='1',
 CDS_LIB='dev_discrete',
 CDS_PART_NAME='CAP_A_0603V-47UF,4V,20%,X5R,60A',
 VOLTAGE='4V',
 PRIM_FILE='./archive_libs/discrete/cap_a/chips/chips.prt';

PART_NAME
 C5L11 'CAP_A_0603V-47UF,4V,20%,X5R,60A':
 GROUP='PWR_MLCC_CAP';

SECTION_NUMBER 1
 '@BASEBOARD_FAB2_LIB.BASEBOARD_FAB2(SCH_1):PAGE220_I283@DEV_DISCRETE.CAP_A(CHIPS)':
 C_PATH='@baseboard_fab2_lib.baseboard_fab2(sch_1):page220_i283@dev_discrete.cap~
_a(chips)',
 P_PATH='@baseboard_fab2_lib.baseboard_fab2(sch_1):page220_i283@dev_discrete.cap~
_a(chips)',
 PATH='I283',
 DRAWING='@BASEBOARD_FAB2_LIB.BASEBOARD_FAB2(SCH_1):PAGE220',
 BOM_SS='E15431-004',
 TOLERANCE='20%',
 SEC_TYPE='0603V',
 MATERIAL='X5R',
 PHYS_PAGE='220',
 XY='(-700,-650)',
 ROT='0',
 VER='1',
 VALUE='47UF',
 PACK_TYPE='0603V',
 PART_NUMBER='602433-106',
 LOCATION='C5L11',
 GROUP='PWR_MLCC_CAP',
 SEC='1',
 CDS_LIB='dev_discrete',
 CDS_PART_NAME='CAP_A_0603V-47UF,4V,20%,X5R,60A',
 VOLTAGE='4V',
 PRIM_FILE='./archive_libs/discrete/cap_a/chips/chips.prt';

PART_NAME
 C5L12 'CAP_A_0603V-47UF,4V,20%,X5R,60A':
 GROUP='PWR_MLCC_CAP';

SECTION_NUMBER 1
 '@BASEBOARD_FAB2_LIB.BASEBOARD_FAB2(SCH_1):PAGE220_I284@DEV_DISCRETE.CAP_A(CHIPS)':
 C_PATH='@baseboard_fab2_lib.baseboard_fab2(sch_1):page220_i284@dev_discrete.cap~
_a(chips)',
 P_PATH='@baseboard_fab2_lib.baseboard_fab2(sch_1):page220_i284@dev_discrete.cap~
_a(chips)',
 PATH='I284',
 DRAWING='@BASEBOARD_FAB2_LIB.BASEBOARD_FAB2(SCH_1):PAGE220',
 BOM_SS='E15431-004',
 TOLERANCE='20%',
 SEC_TYPE='0603V',
 MATERIAL='X5R',
 PHYS_PAGE='220',
 XY='(-400,-650)',
 ROT='0',
 VER='1',
 VALUE='47UF',
 PACK_TYPE='0603V',
 PART_NUMBER='602433-106',
 LOCATION='C5L12',
 GROUP='PWR_MLCC_CAP',
 SEC='1',
 CDS_LIB='dev_discrete',
 CDS_PART_NAME='CAP_A_0603V-47UF,4V,20%,X5R,60A',
 VOLTAGE='4V',
 PRIM_FILE='./archive_libs/discrete/cap_a/chips/chips.prt';

PART_NAME
 C5L13 'CAP_A_0603V-47UF,4V,20%,X5R,60A':
 GROUP='PWR_MLCC_CAP';

SECTION_NUMBER 1
 '@BASEBOARD_FAB2_LIB.BASEBOARD_FAB2(SCH_1):PAGE220_I285@DEV_DISCRETE.CAP_A(CHIPS)':
 C_PATH='@baseboard_fab2_lib.baseboard_fab2(sch_1):page220_i285@dev_discrete.cap~
_a(chips)',
 P_PATH='@baseboard_fab2_lib.baseboard_fab2(sch_1):page220_i285@dev_discrete.cap~
_a(chips)',
 PATH='I285',
 DRAWING='@BASEBOARD_FAB2_LIB.BASEBOARD_FAB2(SCH_1):PAGE220',
 BOM_SS='E15431-004',
 TOLERANCE='20%',
 SEC_TYPE='0603V',
 MATERIAL='X5R',
 PHYS_PAGE='220',
 XY='(-125,-650)',
 ROT='0',
 VER='1',
 VALUE='47UF',
 PACK_TYPE='0603V',
 PART_NUMBER='602433-106',
 LOCATION='C5L13',
 GROUP='PWR_MLCC_CAP',
 SEC='1',
 CDS_LIB='dev_discrete',
 CDS_PART_NAME='CAP_A_0603V-47UF,4V,20%,X5R,60A',
 VOLTAGE='4V',
 PRIM_FILE='./archive_libs/discrete/cap_a/chips/chips.prt';

PART_NAME
 C5L14 'CAP_0805-100UF,4V,20%,X5R,6024A':
 GROUP='PWR_MLCC_CAP',
 ROOM='VDDQ_ABC_PWR_VR';

SECTION_NUMBER 1
 '@BASEBOARD_FAB2_LIB.BASEBOARD_FAB2(SCH_1):PAGE220_I313@MSTR_DISCRETE.CAP(CHIPS)':
 C_PATH='@baseboard_fab2_lib.baseboard_fab2(sch_1):page220_i313@mstr_discrete.ca~
p(chips)',
 P_PATH='@baseboard_fab2_lib.baseboard_fab2(sch_1):page220_i313@mstr_discrete.ca~
p(chips)',
 PATH='I313',
 DRAWING='@BASEBOARD_FAB2_LIB.BASEBOARD_FAB2(SCH_1):PAGE220',
 NEW_PN='078.1071T.M002',
 NEW_MATERIAL='X6S',
 BOM_SS='NOPOP',
 TOLERANCE='20%',
 SEC_TYPE='0805',
 MATERIAL='X5R',
 BOM_COST='MEM_VRD_PVDDQ_CD',
 PHYS_PAGE='220',
 XY='(4600,2825)',
 ROT='0',
 VER='1',
 VALUE='100UF',
 PACK_TYPE='0805',
 PART_NUMBER='602433-112',
 LOCATION='C5L14',
 ROOM='VDDQ_ABC_PWR_VR',
 GROUP='PWR_MLCC_CAP',
 SEC='1',
 CDS_LIB='mstr_discrete',
 CDS_PART_NAME='CAP_0805-100UF,4V,20%,X5R,6024A',
 VOLTAGE='4V',
 PRIM_FILE='./archive_libs/mstr_discrete/cap/chips/chips.prt';

PART_NAME
 C5L15 'CAP_A_0603V-47UF,4V,20%,X5R,60A':
 GROUP='PWR_MLCC_CAP';

SECTION_NUMBER 1
 '@BASEBOARD_FAB2_LIB.BASEBOARD_FAB2(SCH_1):PAGE220_I192@DEV_DISCRETE.CAP_A(CHIPS)':
 C_PATH='@baseboard_fab2_lib.baseboard_fab2(sch_1):page220_i192@dev_discrete.cap~
_a(chips)',
 P_PATH='@baseboard_fab2_lib.baseboard_fab2(sch_1):page220_i192@dev_discrete.cap~
_a(chips)',
 PATH='I192',
 DRAWING='@BASEBOARD_FAB2_LIB.BASEBOARD_FAB2(SCH_1):PAGE220',
 BOM_SS='NOPOP',
 TOLERANCE='20%',
 SEC_TYPE='0603V',
 MATERIAL='X5R',
 PHYS_PAGE='220',
 XY='(2650,950)',
 ROT='0',
 VER='1',
 VALUE='47UF',
 PACK_TYPE='0603V',
 PART_NUMBER='602433-106',
 LOCATION='C5L15',
 GROUP='PWR_MLCC_CAP',
 SEC='1',
 CDS_LIB='dev_discrete',
 CDS_PART_NAME='CAP_A_0603V-47UF,4V,20%,X5R,60A',
 VOLTAGE='4V',
 PRIM_FILE='./archive_libs/discrete/cap_a/chips/chips.prt';

PART_NAME
 C5M1 'CAP_A_0603V-47UF,4V,20%,X5R,60A':
 GROUP='PWR_MLCC_CAP';

SECTION_NUMBER 1
 '@BASEBOARD_FAB2_LIB.BASEBOARD_FAB2(SCH_1):PAGE220_I291@DEV_DISCRETE.CAP_A(CHIPS)':
 C_PATH='@baseboard_fab2_lib.baseboard_fab2(sch_1):page220_i291@dev_discrete.cap~
_a(chips)',
 P_PATH='@baseboard_fab2_lib.baseboard_fab2(sch_1):page220_i291@dev_discrete.cap~
_a(chips)',
 PATH='I291',
 DRAWING='@BASEBOARD_FAB2_LIB.BASEBOARD_FAB2(SCH_1):PAGE220',
 BOM_SS='E15431-004',
 TOLERANCE='20%',
 SEC_TYPE='0603V',
 MATERIAL='X5R',
 PHYS_PAGE='220',
 XY='(1650,-650)',
 ROT='0',
 VER='1',
 VALUE='47UF',
 PACK_TYPE='0603V',
 PART_NUMBER='602433-106',
 LOCATION='C5M1',
 GROUP='PWR_MLCC_CAP',
 SEC='1',
 CDS_LIB='dev_discrete',
 CDS_PART_NAME='CAP_A_0603V-47UF,4V,20%,X5R,60A',
 VOLTAGE='4V',
 PRIM_FILE='./archive_libs/discrete/cap_a/chips/chips.prt';

PART_NAME
 C5M2 'CAP_A_0603V-47UF,4V,20%,X5R,60A':
 GROUP='PWR_MLCC_CAP';

SECTION_NUMBER 1
 '@BASEBOARD_FAB2_LIB.BASEBOARD_FAB2(SCH_1):PAGE220_I290@DEV_DISCRETE.CAP_A(CHIPS)':
 C_PATH='@baseboard_fab2_lib.baseboard_fab2(sch_1):page220_i290@dev_discrete.cap~
_a(chips)',
 P_PATH='@baseboard_fab2_lib.baseboard_fab2(sch_1):page220_i290@dev_discrete.cap~
_a(chips)',
 PATH='I290',
 DRAWING='@BASEBOARD_FAB2_LIB.BASEBOARD_FAB2(SCH_1):PAGE220',
 BOM_SS='E15431-004',
 TOLERANCE='20%',
 SEC_TYPE='0603V',
 MATERIAL='X5R',
 PHYS_PAGE='220',
 XY='(1350,-650)',
 ROT='0',
 VER='1',
 VALUE='47UF',
 PACK_TYPE='0603V',
 PART_NUMBER='602433-106',
 LOCATION='C5M2',
 GROUP='PWR_MLCC_CAP',
 SEC='1',
 CDS_LIB='dev_discrete',
 CDS_PART_NAME='CAP_A_0603V-47UF,4V,20%,X5R,60A',
 VOLTAGE='4V',
 PRIM_FILE='./archive_libs/discrete/cap_a/chips/chips.prt';

PART_NAME
 C5M3 'CAP_A_0603V-47UF,4V,20%,X5R,60A':
 GROUP='PWR_MLCC_CAP';

SECTION_NUMBER 1
 '@BASEBOARD_FAB2_LIB.BASEBOARD_FAB2(SCH_1):PAGE220_I199@DEV_DISCRETE.CAP_A(CHIPS)':
 C_PATH='@baseboard_fab2_lib.baseboard_fab2(sch_1):page220_i199@dev_discrete.cap~
_a(chips)',
 P_PATH='@baseboard_fab2_lib.baseboard_fab2(sch_1):page220_i199@dev_discrete.cap~
_a(chips)',
 PATH='I199',
 DRAWING='@BASEBOARD_FAB2_LIB.BASEBOARD_FAB2(SCH_1):PAGE220',
 BOM_SS='NOPOP',
 TOLERANCE='20%',
 SEC_TYPE='0603V',
 MATERIAL='X5R',
 PHYS_PAGE='220',
 XY='(3425,1675)',
 ROT='0',
 VER='1',
 VALUE='47UF',
 PACK_TYPE='0603V',
 PART_NUMBER='602433-106',
 LOCATION='C5M3',
 GROUP='PWR_MLCC_CAP',
 SEC='1',
 CDS_LIB='dev_discrete',
 CDS_PART_NAME='CAP_A_0603V-47UF,4V,20%,X5R,60A',
 VOLTAGE='4V',
 PRIM_FILE='./archive_libs/discrete/cap_a/chips/chips.prt';

PART_NAME
 C5M4 'CAP_A_0603V-47UF,4V,20%,X5R,60A':
 GROUP='PWR_MLCC_CAP';

SECTION_NUMBER 1
 '@BASEBOARD_FAB2_LIB.BASEBOARD_FAB2(SCH_1):PAGE220_I289@DEV_DISCRETE.CAP_A(CHIPS)':
 C_PATH='@baseboard_fab2_lib.baseboard_fab2(sch_1):page220_i289@dev_discrete.cap~
_a(chips)',
 P_PATH='@baseboard_fab2_lib.baseboard_fab2(sch_1):page220_i289@dev_discrete.cap~
_a(chips)',
 PATH='I289',
 DRAWING='@BASEBOARD_FAB2_LIB.BASEBOARD_FAB2(SCH_1):PAGE220',
 BOM_SS='E15431-004',
 TOLERANCE='20%',
 SEC_TYPE='0603V',
 MATERIAL='X5R',
 PHYS_PAGE='220',
 XY='(1075,-650)',
 ROT='0',
 VER='1',
 VALUE='47UF',
 PACK_TYPE='0603V',
 PART_NUMBER='602433-106',
 LOCATION='C5M4',
 GROUP='PWR_MLCC_CAP',
 SEC='1',
 CDS_LIB='dev_discrete',
 CDS_PART_NAME='CAP_A_0603V-47UF,4V,20%,X5R,60A',
 VOLTAGE='4V',
 PRIM_FILE='./archive_libs/discrete/cap_a/chips/chips.prt';

PART_NAME
 C5M5 'CAP_A_0603V-47UF,4V,20%,X5R,60A':
 GROUP='PWR_MLCC_CAP';

SECTION_NUMBER 1
 '@BASEBOARD_FAB2_LIB.BASEBOARD_FAB2(SCH_1):PAGE220_I288@DEV_DISCRETE.CAP_A(CHIPS)':
 C_PATH='@baseboard_fab2_lib.baseboard_fab2(sch_1):page220_i288@dev_discrete.cap~
_a(chips)',
 P_PATH='@baseboard_fab2_lib.baseboard_fab2(sch_1):page220_i288@dev_discrete.cap~
_a(chips)',
 PATH='I288',
 DRAWING='@BASEBOARD_FAB2_LIB.BASEBOARD_FAB2(SCH_1):PAGE220',
 BOM_SS='E15431-004',
 TOLERANCE='20%',
 SEC_TYPE='0603V',
 MATERIAL='X5R',
 PHYS_PAGE='220',
 XY='(800,-650)',
 ROT='0',
 VER='1',
 VALUE='47UF',
 PACK_TYPE='0603V',
 PART_NUMBER='602433-106',
 LOCATION='C5M5',
 GROUP='PWR_MLCC_CAP',
 SEC='1',
 CDS_LIB='dev_discrete',
 CDS_PART_NAME='CAP_A_0603V-47UF,4V,20%,X5R,60A',
 VOLTAGE='4V',
 PRIM_FILE='./archive_libs/discrete/cap_a/chips/chips.prt';

PART_NAME
 C5M6 'CAP_A_0603V-47UF,4V,20%,X5R,60A':
 GROUP='PWR_MLCC_CAP';

SECTION_NUMBER 1
 '@BASEBOARD_FAB2_LIB.BASEBOARD_FAB2(SCH_1):PAGE220_I287@DEV_DISCRETE.CAP_A(CHIPS)':
 C_PATH='@baseboard_fab2_lib.baseboard_fab2(sch_1):page220_i287@dev_discrete.cap~
_a(chips)',
 P_PATH='@baseboard_fab2_lib.baseboard_fab2(sch_1):page220_i287@dev_discrete.cap~
_a(chips)',
 PATH='I287',
 DRAWING='@BASEBOARD_FAB2_LIB.BASEBOARD_FAB2(SCH_1):PAGE220',
 BOM_SS='E15431-004',
 TOLERANCE='20%',
 SEC_TYPE='0603V',
 MATERIAL='X5R',
 PHYS_PAGE='220',
 XY='(500,-650)',
 ROT='0',
 VER='1',
 VALUE='47UF',
 PACK_TYPE='0603V',
 PART_NUMBER='602433-106',
 LOCATION='C5M6',
 GROUP='PWR_MLCC_CAP',
 SEC='1',
 CDS_LIB='dev_discrete',
 CDS_PART_NAME='CAP_A_0603V-47UF,4V,20%,X5R,60A',
 VOLTAGE='4V',
 PRIM_FILE='./archive_libs/discrete/cap_a/chips/chips.prt';

PART_NAME
 C5M7 'CAP_A_0603V-47UF,4V,20%,X5R,60A':
 GROUP='PWR_MLCC_CAP';

SECTION_NUMBER 1
 '@BASEBOARD_FAB2_LIB.BASEBOARD_FAB2(SCH_1):PAGE220_I286@DEV_DISCRETE.CAP_A(CHIPS)':
 C_PATH='@baseboard_fab2_lib.baseboard_fab2(sch_1):page220_i286@dev_discrete.cap~
_a(chips)',
 P_PATH='@baseboard_fab2_lib.baseboard_fab2(sch_1):page220_i286@dev_discrete.cap~
_a(chips)',
 PATH='I286',
 DRAWING='@BASEBOARD_FAB2_LIB.BASEBOARD_FAB2(SCH_1):PAGE220',
 BOM_SS='E15431-004',
 TOLERANCE='20%',
 SEC_TYPE='0603V',
 MATERIAL='X5R',
 PHYS_PAGE='220',
 XY='(200,-650)',
 ROT='0',
 VER='1',
 VALUE='47UF',
 PACK_TYPE='0603V',
 PART_NUMBER='602433-106',
 LOCATION='C5M7',
 GROUP='PWR_MLCC_CAP',
 SEC='1',
 CDS_LIB='dev_discrete',
 CDS_PART_NAME='CAP_A_0603V-47UF,4V,20%,X5R,60A',
 VOLTAGE='4V',
 PRIM_FILE='./archive_libs/discrete/cap_a/chips/chips.prt';

PART_NAME
 C5M8 'CAP_0805-100UF,4V,20%,X5R,6024A':
 GROUP='PWR_MLCC_CAP',
 ROOM='VDDQ_ABC_PWR_VR';

SECTION_NUMBER 1
 '@BASEBOARD_FAB2_LIB.BASEBOARD_FAB2(SCH_1):PAGE220_I314@MSTR_DISCRETE.CAP(CHIPS)':
 C_PATH='@baseboard_fab2_lib.baseboard_fab2(sch_1):page220_i314@mstr_discrete.ca~
p(chips)',
 P_PATH='@baseboard_fab2_lib.baseboard_fab2(sch_1):page220_i314@mstr_discrete.ca~
p(chips)',
 PATH='I314',
 DRAWING='@BASEBOARD_FAB2_LIB.BASEBOARD_FAB2(SCH_1):PAGE220',
 NEW_PN='078.1071T.M002',
 NEW_MATERIAL='X6S',
 BOM_SS='NOPOP',
 TOLERANCE='20%',
 SEC_TYPE='0805',
 MATERIAL='X5R',
 BOM_COST='MEM_VRD_PVDDQ_CD',
 PHYS_PAGE='220',
 XY='(5000,2825)',
 ROT='0',
 VER='1',
 VALUE='100UF',
 PACK_TYPE='0805',
 PART_NUMBER='602433-112',
 LOCATION='C5M8',
 ROOM='VDDQ_ABC_PWR_VR',
 GROUP='PWR_MLCC_CAP',
 SEC='1',
 CDS_LIB='mstr_discrete',
 CDS_PART_NAME='CAP_0805-100UF,4V,20%,X5R,6024A',
 VOLTAGE='4V',
 PRIM_FILE='./archive_libs/mstr_discrete/cap/chips/chips.prt';

PART_NAME
 C5M9 'CAP_A_0603V-47UF,4V,20%,X5R,60A':
 GROUP='PWR_MLCC_CAP';

SECTION_NUMBER 1
 '@BASEBOARD_FAB2_LIB.BASEBOARD_FAB2(SCH_1):PAGE220_I195@DEV_DISCRETE.CAP_A(CHIPS)':
 C_PATH='@baseboard_fab2_lib.baseboard_fab2(sch_1):page220_i195@dev_discrete.cap~
_a(chips)',
 P_PATH='@baseboard_fab2_lib.baseboard_fab2(sch_1):page220_i195@dev_discrete.cap~
_a(chips)',
 PATH='I195',
 DRAWING='@BASEBOARD_FAB2_LIB.BASEBOARD_FAB2(SCH_1):PAGE220',
 BOM_SS='NOPOP',
 TOLERANCE='20%',
 SEC_TYPE='0603V',
 MATERIAL='X5R',
 PHYS_PAGE='220',
 XY='(4125,1675)',
 ROT='0',
 VER='1',
 VALUE='47UF',
 PACK_TYPE='0603V',
 PART_NUMBER='602433-106',
 LOCATION='C5M9',
 GROUP='PWR_MLCC_CAP',
 SEC='1',
 CDS_LIB='dev_discrete',
 CDS_PART_NAME='CAP_A_0603V-47UF,4V,20%,X5R,60A',
 VOLTAGE='4V',
 PRIM_FILE='./archive_libs/discrete/cap_a/chips/chips.prt';

PART_NAME
 C5M10 'CAP_A_0603V-47UF,4V,20%,X5R,60A':
 GROUP='PWR_MLCC_CAP';

SECTION_NUMBER 1
 '@BASEBOARD_FAB2_LIB.BASEBOARD_FAB2(SCH_1):PAGE220_I198@DEV_DISCRETE.CAP_A(CHIPS)':
 C_PATH='@baseboard_fab2_lib.baseboard_fab2(sch_1):page220_i198@dev_discrete.cap~
_a(chips)',
 P_PATH='@baseboard_fab2_lib.baseboard_fab2(sch_1):page220_i198@dev_discrete.cap~
_a(chips)',
 PATH='I198',
 DRAWING='@BASEBOARD_FAB2_LIB.BASEBOARD_FAB2(SCH_1):PAGE220',
 BOM_SS='NOPOP',
 TOLERANCE='20%',
 SEC_TYPE='0603V',
 MATERIAL='X5R',
 PHYS_PAGE='220',
 XY='(3025,1675)',
 ROT='0',
 VER='1',
 VALUE='47UF',
 PACK_TYPE='0603V',
 PART_NUMBER='602433-106',
 LOCATION='C5M10',
 GROUP='PWR_MLCC_CAP',
 SEC='1',
 CDS_LIB='dev_discrete',
 CDS_PART_NAME='CAP_A_0603V-47UF,4V,20%,X5R,60A',
 VOLTAGE='4V',
 PRIM_FILE='./archive_libs/discrete/cap_a/chips/chips.prt';

PART_NAME
 C5M11 'CAP_A_0603V-47UF,4V,20%,X5R,60A':
 GROUP='PWR_MLCC_CAP';

SECTION_NUMBER 1
 '@BASEBOARD_FAB2_LIB.BASEBOARD_FAB2(SCH_1):PAGE220_I200@DEV_DISCRETE.CAP_A(CHIPS)':
 C_PATH='@baseboard_fab2_lib.baseboard_fab2(sch_1):page220_i200@dev_discrete.cap~
_a(chips)',
 P_PATH='@baseboard_fab2_lib.baseboard_fab2(sch_1):page220_i200@dev_discrete.cap~
_a(chips)',
 PATH='I200',
 DRAWING='@BASEBOARD_FAB2_LIB.BASEBOARD_FAB2(SCH_1):PAGE220',
 BOM_SS='NOPOP',
 TOLERANCE='20%',
 SEC_TYPE='0603V',
 MATERIAL='X5R',
 PHYS_PAGE='220',
 XY='(4525,1675)',
 ROT='0',
 VER='1',
 VALUE='47UF',
 PACK_TYPE='0603V',
 PART_NUMBER='602433-106',
 LOCATION='C5M11',
 GROUP='PWR_MLCC_CAP',
 SEC='1',
 CDS_LIB='dev_discrete',
 CDS_PART_NAME='CAP_A_0603V-47UF,4V,20%,X5R,60A',
 VOLTAGE='4V',
 PRIM_FILE='./archive_libs/discrete/cap_a/chips/chips.prt';

PART_NAME
 C5M12 'CAP_0805-100UF,4V,20%,X5R,6024A':
 GROUP='PWR_MLCC_CAP',
 ROOM='VDDQ_ABC_PWR_VR';

SECTION_NUMBER 1
 '@BASEBOARD_FAB2_LIB.BASEBOARD_FAB2(SCH_1):PAGE220_I312@MSTR_DISCRETE.CAP(CHIPS)':
 C_PATH='@baseboard_fab2_lib.baseboard_fab2(sch_1):page220_i312@mstr_discrete.ca~
p(chips)',
 P_PATH='@baseboard_fab2_lib.baseboard_fab2(sch_1):page220_i312@mstr_discrete.ca~
p(chips)',
 PATH='I312',
 DRAWING='@BASEBOARD_FAB2_LIB.BASEBOARD_FAB2(SCH_1):PAGE220',
 NEW_PN='078.1071T.M002',
 NEW_MATERIAL='X6S',
 BOM_SS='NOPOP',
 TOLERANCE='20%',
 SEC_TYPE='0805',
 MATERIAL='X5R',
 BOM_COST='MEM_VRD_PVDDQ_CD',
 PHYS_PAGE='220',
 XY='(4250,2825)',
 ROT='0',
 VER='1',
 VALUE='100UF',
 PACK_TYPE='0805',
 PART_NUMBER='602433-112',
 LOCATION='C5M12',
 ROOM='VDDQ_ABC_PWR_VR',
 GROUP='PWR_MLCC_CAP',
 SEC='1',
 CDS_LIB='mstr_discrete',
 CDS_PART_NAME='CAP_0805-100UF,4V,20%,X5R,6024A',
 VOLTAGE='4V',
 PRIM_FILE='./archive_libs/mstr_discrete/cap/chips/chips.prt';

PART_NAME
 C5M13 'CAP_A_0603V-47UF,4V,20%,X5R,60A':
 GROUP='PWR_MLCC_CAP';

SECTION_NUMBER 1
 '@BASEBOARD_FAB2_LIB.BASEBOARD_FAB2(SCH_1):PAGE222_I41@DEV_DISCRETE.CAP_A(CHIPS)':
 C_PATH='@baseboard_fab2_lib.baseboard_fab2(sch_1):page222_i41@dev_discrete.cap_~
a(chips)',
 P_PATH='@baseboard_fab2_lib.baseboard_fab2(sch_1):page222_i41@dev_discrete.cap_~
a(chips)',
 PATH='I41',
 DRAWING='@BASEBOARD_FAB2_LIB.BASEBOARD_FAB2(SCH_1):PAGE222',
 TOLERANCE='20%',
 SEC_TYPE='0603V',
 MATERIAL='X5R',
 PHYS_PAGE='222',
 XY='(3500,2825)',
 ROT='0',
 VER='1',
 VALUE='47UF',
 PACK_TYPE='0603V',
 PART_NUMBER='602433-106',
 LOCATION='C5M13',
 GROUP='PWR_MLCC_CAP',
 SEC='1',
 CDS_LIB='dev_discrete',
 CDS_PART_NAME='CAP_A_0603V-47UF,4V,20%,X5R,60A',
 VOLTAGE='4V',
 PRIM_FILE='./archive_libs/discrete/cap_a/chips/chips.prt';

PART_NAME
 C5P1 'CAP_0805-100UF,4V,20%,X5R,6024A':
 GROUP='PWR_MLCC_CAP',
 ROOM='VDDQ_ABC_PWR_VR';

SECTION_NUMBER 1
 '@BASEBOARD_FAB2_LIB.BASEBOARD_FAB2(SCH_1):PAGE220_I320@MSTR_DISCRETE.CAP(CHIPS)':
 C_PATH='@baseboard_fab2_lib.baseboard_fab2(sch_1):page220_i320@mstr_discrete.ca~
p(chips)',
 P_PATH='@baseboard_fab2_lib.baseboard_fab2(sch_1):page220_i320@mstr_discrete.ca~
p(chips)',
 PATH='I320',
 DRAWING='@BASEBOARD_FAB2_LIB.BASEBOARD_FAB2(SCH_1):PAGE220',
 NEW_PN='078.1071T.M002',
 NEW_MATERIAL='X6S',
 BOM_SS='NOPOP',
 TOLERANCE='20%',
 SEC_TYPE='0805',
 MATERIAL='X5R',
 BOM_COST='MEM_VRD_PVDDQ_CD',
 PHYS_PAGE='220',
 XY='(-1950,2975)',
 ROT='0',
 VER='1',
 VALUE='100UF',
 PACK_TYPE='0805',
 PART_NUMBER='602433-112',
 LOCATION='C5P1',
 ROOM='VDDQ_ABC_PWR_VR',
 GROUP='PWR_MLCC_CAP',
 SEC='1',
 CDS_LIB='mstr_discrete',
 CDS_PART_NAME='CAP_0805-100UF,4V,20%,X5R,6024A',
 VOLTAGE='4V',
 PRIM_FILE='./archive_libs/mstr_discrete/cap/chips/chips.prt';

PART_NAME
 C5P2 'CAP_0805-100UF,4V,20%,X5R,6024A':
 GROUP='PWR_MLCC_CAP',
 ROOM='VDDQ_ABC_PWR_VR';

SECTION_NUMBER 1
 '@BASEBOARD_FAB2_LIB.BASEBOARD_FAB2(SCH_1):PAGE220_I319@MSTR_DISCRETE.CAP(CHIPS)':
 C_PATH='@baseboard_fab2_lib.baseboard_fab2(sch_1):page220_i319@mstr_discrete.ca~
p(chips)',
 P_PATH='@baseboard_fab2_lib.baseboard_fab2(sch_1):page220_i319@mstr_discrete.ca~
p(chips)',
 PATH='I319',
 DRAWING='@BASEBOARD_FAB2_LIB.BASEBOARD_FAB2(SCH_1):PAGE220',
 NEW_PN='078.1071T.M002',
 NEW_MATERIAL='X6S',
 BOM_SS='NOPOP',
 TOLERANCE='20%',
 SEC_TYPE='0805',
 MATERIAL='X5R',
 BOM_COST='MEM_VRD_PVDDQ_CD',
 PHYS_PAGE='220',
 XY='(-2300,2975)',
 ROT='0',
 VER='1',
 VALUE='100UF',
 PACK_TYPE='0805',
 PART_NUMBER='602433-112',
 LOCATION='C5P2',
 ROOM='VDDQ_ABC_PWR_VR',
 GROUP='PWR_MLCC_CAP',
 SEC='1',
 CDS_LIB='mstr_discrete',
 CDS_PART_NAME='CAP_0805-100UF,4V,20%,X5R,6024A',
 VOLTAGE='4V',
 PRIM_FILE='./archive_libs/mstr_discrete/cap/chips/chips.prt';

PART_NAME
 C5P3 'CAP_0805-100UF,4V,20%,X5R,6024A':
 GROUP='PWR_MLCC_CAP',
 ROOM='VDDQ_ABC_PWR_VR';

SECTION_NUMBER 1
 '@BASEBOARD_FAB2_LIB.BASEBOARD_FAB2(SCH_1):PAGE220_I315@MSTR_DISCRETE.CAP(CHIPS)':
 C_PATH='@baseboard_fab2_lib.baseboard_fab2(sch_1):page220_i315@mstr_discrete.ca~
p(chips)',
 P_PATH='@baseboard_fab2_lib.baseboard_fab2(sch_1):page220_i315@mstr_discrete.ca~
p(chips)',
 PATH='I315',
 DRAWING='@BASEBOARD_FAB2_LIB.BASEBOARD_FAB2(SCH_1):PAGE220',
 NEW_PN='078.1071T.M002',
 NEW_MATERIAL='X6S',
 BOM_SS='NOPOP',
 TOLERANCE='20%',
 SEC_TYPE='0805',
 MATERIAL='X5R',
 BOM_COST='MEM_VRD_PVDDQ_CD',
 PHYS_PAGE='220',
 XY='(1600,2950)',
 ROT='0',
 VER='1',
 VALUE='100UF',
 PACK_TYPE='0805',
 PART_NUMBER='602433-112',
 LOCATION='C5P3',
 ROOM='VDDQ_ABC_PWR_VR',
 GROUP='PWR_MLCC_CAP',
 SEC='1',
 CDS_LIB='mstr_discrete',
 CDS_PART_NAME='CAP_0805-100UF,4V,20%,X5R,6024A',
 VOLTAGE='4V',
 PRIM_FILE='./archive_libs/mstr_discrete/cap/chips/chips.prt';

PART_NAME
 C5P4 'CAP_0805-100UF,4V,20%,X5R,6024A':
 GROUP='PWR_MLCC_CAP',
 ROOM='VDDQ_ABC_PWR_VR';

SECTION_NUMBER 1
 '@BASEBOARD_FAB2_LIB.BASEBOARD_FAB2(SCH_1):PAGE220_I318@MSTR_DISCRETE.CAP(CHIPS)':
 C_PATH='@baseboard_fab2_lib.baseboard_fab2(sch_1):page220_i318@mstr_discrete.ca~
p(chips)',
 P_PATH='@baseboard_fab2_lib.baseboard_fab2(sch_1):page220_i318@mstr_discrete.ca~
p(chips)',
 PATH='I318',
 DRAWING='@BASEBOARD_FAB2_LIB.BASEBOARD_FAB2(SCH_1):PAGE220',
 NEW_PN='078.1071T.M002',
 NEW_MATERIAL='X6S',
 BOM_SS='NOPOP',
 TOLERANCE='20%',
 SEC_TYPE='0805',
 MATERIAL='X5R',
 BOM_COST='MEM_VRD_PVDDQ_CD',
 PHYS_PAGE='220',
 XY='(800,2925)',
 ROT='0',
 VER='1',
 VALUE='100UF',
 PACK_TYPE='0805',
 PART_NUMBER='602433-112',
 LOCATION='C5P4',
 ROOM='VDDQ_ABC_PWR_VR',
 GROUP='PWR_MLCC_CAP',
 SEC='1',
 CDS_LIB='mstr_discrete',
 CDS_PART_NAME='CAP_0805-100UF,4V,20%,X5R,6024A',
 VOLTAGE='4V',
 PRIM_FILE='./archive_libs/mstr_discrete/cap/chips/chips.prt';

PART_NAME
 C5P5 'CAP_0805-100UF,4V,20%,X5R,6024A':
 GROUP='PWR_MLCC_CAP',
 ROOM='VDDQ_ABC_PWR_VR';

SECTION_NUMBER 1
 '@BASEBOARD_FAB2_LIB.BASEBOARD_FAB2(SCH_1):PAGE220_I317@MSTR_DISCRETE.CAP(CHIPS)':
 C_PATH='@baseboard_fab2_lib.baseboard_fab2(sch_1):page220_i317@mstr_discrete.ca~
p(chips)',
 P_PATH='@baseboard_fab2_lib.baseboard_fab2(sch_1):page220_i317@mstr_discrete.ca~
p(chips)',
 PATH='I317',
 DRAWING='@BASEBOARD_FAB2_LIB.BASEBOARD_FAB2(SCH_1):PAGE220',
 NEW_PN='078.1071T.M002',
 NEW_MATERIAL='X6S',
 BOM_SS='NOPOP',
 TOLERANCE='20%',
 SEC_TYPE='0805',
 MATERIAL='X5R',
 BOM_COST='MEM_VRD_PVDDQ_CD',
 PHYS_PAGE='220',
 XY='(500,2925)',
 ROT='0',
 VER='1',
 VALUE='100UF',
 PACK_TYPE='0805',
 PART_NUMBER='602433-112',
 LOCATION='C5P5',
 ROOM='VDDQ_ABC_PWR_VR',
 GROUP='PWR_MLCC_CAP',
 SEC='1',
 CDS_LIB='mstr_discrete',
 CDS_PART_NAME='CAP_0805-100UF,4V,20%,X5R,6024A',
 VOLTAGE='4V',
 PRIM_FILE='./archive_libs/mstr_discrete/cap/chips/chips.prt';

PART_NAME
 C5P6 'CAP_0805-100UF,4V,20%,X5R,6024A':
 GROUP='PWR_MLCC_CAP',
 ROOM='VDDQ_ABC_PWR_VR';

SECTION_NUMBER 1
 '@BASEBOARD_FAB2_LIB.BASEBOARD_FAB2(SCH_1):PAGE220_I316@MSTR_DISCRETE.CAP(CHIPS)':
 C_PATH='@baseboard_fab2_lib.baseboard_fab2(sch_1):page220_i316@mstr_discrete.ca~
p(chips)',
 P_PATH='@baseboard_fab2_lib.baseboard_fab2(sch_1):page220_i316@mstr_discrete.ca~
p(chips)',
 PATH='I316',
 DRAWING='@BASEBOARD_FAB2_LIB.BASEBOARD_FAB2(SCH_1):PAGE220',
 NEW_PN='078.1071T.M002',
 NEW_MATERIAL='X6S',
 BOM_SS='NOPOP',
 TOLERANCE='20%',
 SEC_TYPE='0805',
 MATERIAL='X5R',
 BOM_COST='MEM_VRD_PVDDQ_CD',
 PHYS_PAGE='220',
 XY='(175,2925)',
 ROT='0',
 VER='1',
 VALUE='100UF',
 PACK_TYPE='0805',
 PART_NUMBER='602433-112',
 LOCATION='C5P6',
 ROOM='VDDQ_ABC_PWR_VR',
 GROUP='PWR_MLCC_CAP',
 SEC='1',
 CDS_LIB='mstr_discrete',
 CDS_PART_NAME='CAP_0805-100UF,4V,20%,X5R,6024A',
 VOLTAGE='4V',
 PRIM_FILE='./archive_libs/mstr_discrete/cap/chips/chips.prt';

PART_NAME
 C5P7 'CAP_0805LF-22UF,4V,20%,X6S,C95A':
 GROUP='PWR_MLCC_CAP',
 ROOM='PVCCIN_CPU0_DECAP_VR';

SECTION_NUMBER 1
 '@BASEBOARD_FAB2_LIB.BASEBOARD_FAB2(SCH_1):PAGE42_I25@MSTR_DISCRETE.CAP(CHIPS)':
 C_PATH='@baseboard_fab2_lib.baseboard_fab2(sch_1):page42_i25@mstr_discrete.cap(~
chips)',
 P_PATH='@baseboard_fab2_lib.baseboard_fab2(sch_1):page42_i25@mstr_discrete.cap(~
chips)',
 PATH='I25',
 DRAWING='@BASEBOARD_FAB2_LIB.BASEBOARD_FAB2(SCH_1):PAGE42',
 TOLERANCE='20%',
 MATERIAL='X6S',
 BOM_COST='PROC_SOCKET',
 PHYS_PAGE='42',
 XY='(-4450,950)',
 ROT='0',
 VER='1',
 VALUE='22UF',
 PACK_TYPE='0805LF',
 PART_NUMBER='C95333-002',
 LOCATION='C5P7',
 ROOM='PVCCIN_CPU0_DECAP_VR',
 GROUP='PWR_MLCC_CAP',
 CDS_LIB='mstr_discrete',
 CDS_PART_NAME='CAP_0805LF-22UF,4V,20%,X6S,C95A',
 VOLTAGE='4V',
 PRIM_FILE='./archive_libs/mstr_discrete/cap/chips/chips.prt';

PART_NAME
 C5P8 'CAP_0805LF-22UF,4V,20%,X6S,C95A':
 GROUP='PWR_MLCC_CAP',
 ROOM='PVCCIN_CPU0_DECAP_VR';

SECTION_NUMBER 1
 '@BASEBOARD_FAB2_LIB.BASEBOARD_FAB2(SCH_1):PAGE42_I214@MSTR_DISCRETE.CAP(CHIPS)':
 C_PATH='@baseboard_fab2_lib.baseboard_fab2(sch_1):page42_i214@mstr_discrete.cap~
(chips)',
 P_PATH='@baseboard_fab2_lib.baseboard_fab2(sch_1):page42_i214@mstr_discrete.cap~
(chips)',
 PATH='I214',
 DRAWING='@BASEBOARD_FAB2_LIB.BASEBOARD_FAB2(SCH_1):PAGE42',
 TOLERANCE='20%',
 MATERIAL='X6S',
 BOM_COST='PROC_SOCKET',
 PHYS_PAGE='42',
 XY='(-4150,950)',
 ROT='0',
 VER='1',
 VALUE='22UF',
 PACK_TYPE='0805LF',
 PART_NUMBER='C95333-002',
 LOCATION='C5P8',
 ROOM='PVCCIN_CPU0_DECAP_VR',
 GROUP='PWR_MLCC_CAP',
 CDS_LIB='mstr_discrete',
 CDS_PART_NAME='CAP_0805LF-22UF,4V,20%,X6S,C95A',
 VOLTAGE='4V',
 PRIM_FILE='./archive_libs/mstr_discrete/cap/chips/chips.prt';

PART_NAME
 C5P9 'CAP_0805LF-22UF,4V,20%,X6S,C95A':
 GROUP='PWR_MLCC_CAP',
 ROOM='PVCCIN_CPU0_DECAP_VR';

SECTION_NUMBER 1
 '@BASEBOARD_FAB2_LIB.BASEBOARD_FAB2(SCH_1):PAGE42_I215@MSTR_DISCRETE.CAP(CHIPS)':
 C_PATH='@baseboard_fab2_lib.baseboard_fab2(sch_1):page42_i215@mstr_discrete.cap~
(chips)',
 P_PATH='@baseboard_fab2_lib.baseboard_fab2(sch_1):page42_i215@mstr_discrete.cap~
(chips)',
 PATH='I215',
 DRAWING='@BASEBOARD_FAB2_LIB.BASEBOARD_FAB2(SCH_1):PAGE42',
 TOLERANCE='20%',
 MATERIAL='X6S',
 BOM_COST='PROC_SOCKET',
 PHYS_PAGE='42',
 XY='(-3850,950)',
 ROT='0',
 VER='1',
 VALUE='22UF',
 PACK_TYPE='0805LF',
 PART_NUMBER='C95333-002',
 LOCATION='C5P9',
 ROOM='PVCCIN_CPU0_DECAP_VR',
 GROUP='PWR_MLCC_CAP',
 CDS_LIB='mstr_discrete',
 CDS_PART_NAME='CAP_0805LF-22UF,4V,20%,X6S,C95A',
 VOLTAGE='4V',
 PRIM_FILE='./archive_libs/mstr_discrete/cap/chips/chips.prt';

PART_NAME
 C5P10 'CAP_0805-100UF,4V,20%,X5R,6024A':
 GROUP='PWR_MCP_CAP',
 ROOM='VDDQ_ABC_PWR_VR';

SECTION_NUMBER 1
 '@BASEBOARD_FAB2_LIB.BASEBOARD_FAB2(SCH_1):PAGE42_I226@MSTR_DISCRETE.CAP(CHIPS)':
 C_PATH='@baseboard_fab2_lib.baseboard_fab2(sch_1):page42_i226@mstr_discrete.cap~
(chips)',
 P_PATH='@baseboard_fab2_lib.baseboard_fab2(sch_1):page42_i226@mstr_discrete.cap~
(chips)',
 PATH='I226',
 DRAWING='@BASEBOARD_FAB2_LIB.BASEBOARD_FAB2(SCH_1):PAGE42',
 NEW_PN='078.1071T.M002',
 NEW_MATERIAL='X6S',
 TOLERANCE='20%',
 SEC_TYPE='0805',
 MATERIAL='X5R',
 BOM_COST='MEM_VRD_PVDDQ_CD',
 PHYS_PAGE='42',
 XY='(-3250,2225)',
 ROT='0',
 VER='1',
 VALUE='100UF',
 PACK_TYPE='0805',
 PART_NUMBER='602433-112',
 LOCATION='C5P10',
 ROOM='VDDQ_ABC_PWR_VR',
 GROUP='PWR_MCP_CAP',
 SEC='1',
 CDS_LIB='mstr_discrete',
 CDS_PART_NAME='CAP_0805-100UF,4V,20%,X5R,6024A',
 VOLTAGE='4V',
 PRIM_FILE='./archive_libs/mstr_discrete/cap/chips/chips.prt';

PART_NAME
 C5P11 'CAP_0805-100UF,4V,20%,X5R,6024A':
 GROUP='PWR_MCP_CAP',
 ROOM='VDDQ_ABC_PWR_VR';

SECTION_NUMBER 1
 '@BASEBOARD_FAB2_LIB.BASEBOARD_FAB2(SCH_1):PAGE42_I227@MSTR_DISCRETE.CAP(CHIPS)':
 C_PATH='@baseboard_fab2_lib.baseboard_fab2(sch_1):page42_i227@mstr_discrete.cap~
(chips)',
 P_PATH='@baseboard_fab2_lib.baseboard_fab2(sch_1):page42_i227@mstr_discrete.cap~
(chips)',
 PATH='I227',
 DRAWING='@BASEBOARD_FAB2_LIB.BASEBOARD_FAB2(SCH_1):PAGE42',
 NEW_PN='078.1071T.M002',
 NEW_MATERIAL='X6S',
 TOLERANCE='20%',
 SEC_TYPE='0805',
 MATERIAL='X5R',
 BOM_COST='MEM_VRD_PVDDQ_CD',
 PHYS_PAGE='42',
 XY='(-3000,2225)',
 ROT='0',
 VER='1',
 VALUE='100UF',
 PACK_TYPE='0805',
 PART_NUMBER='602433-112',
 LOCATION='C5P11',
 ROOM='VDDQ_ABC_PWR_VR',
 GROUP='PWR_MCP_CAP',
 SEC='1',
 CDS_LIB='mstr_discrete',
 CDS_PART_NAME='CAP_0805-100UF,4V,20%,X5R,6024A',
 VOLTAGE='4V',
 PRIM_FILE='./archive_libs/mstr_discrete/cap/chips/chips.prt';

PART_NAME
 C5P12 'CAP_0805-100UF,4V,20%,X5R,6024A':
 GROUP='PWR_MCP_CAP',
 ROOM='VDDQ_ABC_PWR_VR';

SECTION_NUMBER 1
 '@BASEBOARD_FAB2_LIB.BASEBOARD_FAB2(SCH_1):PAGE42_I236@MSTR_DISCRETE.CAP(CHIPS)':
 C_PATH='@baseboard_fab2_lib.baseboard_fab2(sch_1):page42_i236@mstr_discrete.cap~
(chips)',
 P_PATH='@baseboard_fab2_lib.baseboard_fab2(sch_1):page42_i236@mstr_discrete.cap~
(chips)',
 PATH='I236',
 DRAWING='@BASEBOARD_FAB2_LIB.BASEBOARD_FAB2(SCH_1):PAGE42',
 NEW_PN='078.1071T.M002',
 NEW_MATERIAL='X6S',
 TOLERANCE='20%',
 SEC_TYPE='0805',
 MATERIAL='X5R',
 BOM_COST='MEM_VRD_PVDDQ_CD',
 PHYS_PAGE='42',
 XY='(-750,2225)',
 ROT='0',
 VER='1',
 VALUE='100UF',
 PACK_TYPE='0805',
 PART_NUMBER='602433-112',
 LOCATION='C5P12',
 ROOM='VDDQ_ABC_PWR_VR',
 GROUP='PWR_MCP_CAP',
 SEC='1',
 CDS_LIB='mstr_discrete',
 CDS_PART_NAME='CAP_0805-100UF,4V,20%,X5R,6024A',
 VOLTAGE='4V',
 PRIM_FILE='./archive_libs/mstr_discrete/cap/chips/chips.prt';

PART_NAME
 C5P13 'CAP_0805-100UF,4V,20%,X5R,6024A':
 GROUP='PWR_MCP_CAP',
 ROOM='VDDQ_ABC_PWR_VR';

SECTION_NUMBER 1
 '@BASEBOARD_FAB2_LIB.BASEBOARD_FAB2(SCH_1):PAGE42_I232@MSTR_DISCRETE.CAP(CHIPS)':
 C_PATH='@baseboard_fab2_lib.baseboard_fab2(sch_1):page42_i232@mstr_discrete.cap~
(chips)',
 P_PATH='@baseboard_fab2_lib.baseboard_fab2(sch_1):page42_i232@mstr_discrete.cap~
(chips)',
 PATH='I232',
 DRAWING='@BASEBOARD_FAB2_LIB.BASEBOARD_FAB2(SCH_1):PAGE42',
 NEW_PN='078.1071T.M002',
 NEW_MATERIAL='X6S',
 TOLERANCE='20%',
 SEC_TYPE='0805',
 MATERIAL='X5R',
 BOM_COST='MEM_VRD_PVDDQ_CD',
 PHYS_PAGE='42',
 XY='(-1500,2225)',
 ROT='0',
 VER='1',
 VALUE='100UF',
 PACK_TYPE='0805',
 PART_NUMBER='602433-112',
 LOCATION='C5P13',
 ROOM='VDDQ_ABC_PWR_VR',
 GROUP='PWR_MCP_CAP',
 SEC='1',
 CDS_LIB='mstr_discrete',
 CDS_PART_NAME='CAP_0805-100UF,4V,20%,X5R,6024A',
 VOLTAGE='4V',
 PRIM_FILE='./archive_libs/mstr_discrete/cap/chips/chips.prt';

PART_NAME
 C5P14 'CAP_0805-47UF,4V,20%,X6S,C9533A':
 GROUP='PWR_MLCC_CAP',
 ROOM='PVCCIN_CPU0_DECAP_VR';

SECTION_NUMBER 1
 '@BASEBOARD_FAB2_LIB.BASEBOARD_FAB2(SCH_1):PAGE42_I41@MSTR_DISCRETE.CAP(CHIPS)':
 C_PATH='@baseboard_fab2_lib.baseboard_fab2(sch_1):page42_i41@mstr_discrete.cap(~
chips)',
 P_PATH='@baseboard_fab2_lib.baseboard_fab2(sch_1):page42_i41@mstr_discrete.cap(~
chips)',
 PATH='I41',
 DRAWING='@BASEBOARD_FAB2_LIB.BASEBOARD_FAB2(SCH_1):PAGE42',
 TOLERANCE='20%',
 MATERIAL='X6S',
 BOM_COST='PROC_SOCKET',
 PHYS_PAGE='42',
 XY='(-6550,2250)',
 ROT='0',
 VER='1',
 VALUE='47UF',
 PACK_TYPE='0805',
 PART_NUMBER='C95333-006',
 LOCATION='C5P14',
 ROOM='PVCCIN_CPU0_DECAP_VR',
 GROUP='PWR_MLCC_CAP',
 CDS_LIB='mstr_discrete',
 CDS_PART_NAME='CAP_0805-47UF,4V,20%,X6S,C9533A',
 VOLTAGE='4V',
 PRIM_FILE='./archive_libs/mstr_discrete/cap/chips/chips.prt';

PART_NAME
 C5P15 'CAP_0805-47UF,4V,20%,X6S,C9533A':
 GROUP='PWR_MLCC_CAP',
 ROOM='PVCCIN_CPU0_DECAP_VR';

SECTION_NUMBER 1
 '@BASEBOARD_FAB2_LIB.BASEBOARD_FAB2(SCH_1):PAGE42_I187@MSTR_DISCRETE.CAP(CHIPS)':
 C_PATH='@baseboard_fab2_lib.baseboard_fab2(sch_1):page42_i187@mstr_discrete.cap~
(chips)',
 P_PATH='@baseboard_fab2_lib.baseboard_fab2(sch_1):page42_i187@mstr_discrete.cap~
(chips)',
 PATH='I187',
 DRAWING='@BASEBOARD_FAB2_LIB.BASEBOARD_FAB2(SCH_1):PAGE42',
 TOLERANCE='20%',
 SEC_TYPE='0805',
 MATERIAL='X6S',
 BOM_COST='PROC_SOCKET',
 PHYS_PAGE='42',
 XY='(-6850,1550)',
 ROT='0',
 VER='1',
 VALUE='47UF',
 PACK_TYPE='0805',
 PART_NUMBER='C95333-006',
 LOCATION='C5P15',
 ROOM='PVCCIN_CPU0_DECAP_VR',
 GROUP='PWR_MLCC_CAP',
 SEC='1',
 CDS_LIB='mstr_discrete',
 CDS_PART_NAME='CAP_0805-47UF,4V,20%,X6S,C9533A',
 VOLTAGE='4V',
 PRIM_FILE='./archive_libs/mstr_discrete/cap/chips/chips.prt';

PART_NAME
 C5P16 'CAP_0805-47UF,4V,20%,X6S,C9533A':
 GROUP='PWR_MLCC_CAP',
 ROOM='PVCCIN_CPU0_DECAP_VR';

SECTION_NUMBER 1
 '@BASEBOARD_FAB2_LIB.BASEBOARD_FAB2(SCH_1):PAGE42_I188@MSTR_DISCRETE.CAP(CHIPS)':
 C_PATH='@baseboard_fab2_lib.baseboard_fab2(sch_1):page42_i188@mstr_discrete.cap~
(chips)',
 P_PATH='@baseboard_fab2_lib.baseboard_fab2(sch_1):page42_i188@mstr_discrete.cap~
(chips)',
 PATH='I188',
 DRAWING='@BASEBOARD_FAB2_LIB.BASEBOARD_FAB2(SCH_1):PAGE42',
 TOLERANCE='20%',
 SEC_TYPE='0805',
 MATERIAL='X6S',
 BOM_COST='PROC_SOCKET',
 PHYS_PAGE='42',
 XY='(-6850,2250)',
 ROT='0',
 VER='1',
 VALUE='47UF',
 PACK_TYPE='0805',
 PART_NUMBER='C95333-006',
 LOCATION='C5P16',
 ROOM='PVCCIN_CPU0_DECAP_VR',
 GROUP='PWR_MLCC_CAP',
 SEC='1',
 CDS_LIB='mstr_discrete',
 CDS_PART_NAME='CAP_0805-47UF,4V,20%,X6S,C9533A',
 VOLTAGE='4V',
 PRIM_FILE='./archive_libs/mstr_discrete/cap/chips/chips.prt';

PART_NAME
 C5P17 'CAP_0805-47UF,4V,20%,X6S,C9533A':
 GROUP='PWR_MLCC_CAP',
 ROOM='PVCCIN_CPU0_DECAP_VR';

SECTION_NUMBER 1
 '@BASEBOARD_FAB2_LIB.BASEBOARD_FAB2(SCH_1):PAGE42_I190@MSTR_DISCRETE.CAP(CHIPS)':
 C_PATH='@baseboard_fab2_lib.baseboard_fab2(sch_1):page42_i190@mstr_discrete.cap~
(chips)',
 P_PATH='@baseboard_fab2_lib.baseboard_fab2(sch_1):page42_i190@mstr_discrete.cap~
(chips)',
 PATH='I190',
 DRAWING='@BASEBOARD_FAB2_LIB.BASEBOARD_FAB2(SCH_1):PAGE42',
 TOLERANCE='20%',
 SEC_TYPE='0805',
 MATERIAL='X6S',
 BOM_COST='PROC_SOCKET',
 PHYS_PAGE='42',
 XY='(-6550,1550)',
 ROT='0',
 VER='1',
 VALUE='47UF',
 PACK_TYPE='0805',
 PART_NUMBER='C95333-006',
 LOCATION='C5P17',
 ROOM='PVCCIN_CPU0_DECAP_VR',
 GROUP='PWR_MLCC_CAP',
 SEC='1',
 CDS_LIB='mstr_discrete',
 CDS_PART_NAME='CAP_0805-47UF,4V,20%,X6S,C9533A',
 VOLTAGE='4V',
 PRIM_FILE='./archive_libs/mstr_discrete/cap/chips/chips.prt';

PART_NAME
 C5P18 'CAP_0805-100UF,4V,20%,X5R,6024A':
 GROUP='PWR_MCP_CAP',
 ROOM='VDDQ_ABC_PWR_VR';

SECTION_NUMBER 1
 '@BASEBOARD_FAB2_LIB.BASEBOARD_FAB2(SCH_1):PAGE42_I228@MSTR_DISCRETE.CAP(CHIPS)':
 C_PATH='@baseboard_fab2_lib.baseboard_fab2(sch_1):page42_i228@mstr_discrete.cap~
(chips)',
 P_PATH='@baseboard_fab2_lib.baseboard_fab2(sch_1):page42_i228@mstr_discrete.cap~
(chips)',
 PATH='I228',
 DRAWING='@BASEBOARD_FAB2_LIB.BASEBOARD_FAB2(SCH_1):PAGE42',
 NEW_PN='078.1071T.M002',
 NEW_MATERIAL='X6S',
 TOLERANCE='20%',
 SEC_TYPE='0805',
 MATERIAL='X5R',
 BOM_COST='MEM_VRD_PVDDQ_CD',
 PHYS_PAGE='42',
 XY='(-2500,2225)',
 ROT='0',
 VER='1',
 VALUE='100UF',
 PACK_TYPE='0805',
 PART_NUMBER='602433-112',
 LOCATION='C5P18',
 ROOM='VDDQ_ABC_PWR_VR',
 GROUP='PWR_MCP_CAP',
 SEC='1',
 CDS_LIB='mstr_discrete',
 CDS_PART_NAME='CAP_0805-100UF,4V,20%,X5R,6024A',
 VOLTAGE='4V',
 PRIM_FILE='./archive_libs/mstr_discrete/cap/chips/chips.prt';

PART_NAME
 C5P19 'CAP_0805-100UF,4V,20%,X5R,6024A':
 GROUP='PWR_MCP_CAP',
 ROOM='VDDQ_ABC_PWR_VR';

SECTION_NUMBER 1
 '@BASEBOARD_FAB2_LIB.BASEBOARD_FAB2(SCH_1):PAGE42_I222@MSTR_DISCRETE.CAP(CHIPS)':
 C_PATH='@baseboard_fab2_lib.baseboard_fab2(sch_1):page42_i222@mstr_discrete.cap~
(chips)',
 P_PATH='@baseboard_fab2_lib.baseboard_fab2(sch_1):page42_i222@mstr_discrete.cap~
(chips)',
 PATH='I222',
 DRAWING='@BASEBOARD_FAB2_LIB.BASEBOARD_FAB2(SCH_1):PAGE42',
 NEW_PN='078.1071T.M002',
 NEW_MATERIAL='X6S',
 TOLERANCE='20%',
 SEC_TYPE='0805',
 MATERIAL='X5R',
 BOM_COST='MEM_VRD_PVDDQ_CD',
 PHYS_PAGE='42',
 XY='(-4000,2225)',
 ROT='0',
 VER='1',
 VALUE='100UF',
 PACK_TYPE='0805',
 PART_NUMBER='602433-112',
 LOCATION='C5P19',
 ROOM='VDDQ_ABC_PWR_VR',
 GROUP='PWR_MCP_CAP',
 SEC='1',
 CDS_LIB='mstr_discrete',
 CDS_PART_NAME='CAP_0805-100UF,4V,20%,X5R,6024A',
 VOLTAGE='4V',
 PRIM_FILE='./archive_libs/mstr_discrete/cap/chips/chips.prt';

PART_NAME
 C5P20 'CAP_0805-100UF,4V,20%,X5R,6024A':
 GROUP='PWR_MCP_CAP',
 ROOM='VDDQ_ABC_PWR_VR';

SECTION_NUMBER 1
 '@BASEBOARD_FAB2_LIB.BASEBOARD_FAB2(SCH_1):PAGE42_I234@MSTR_DISCRETE.CAP(CHIPS)':
 C_PATH='@baseboard_fab2_lib.baseboard_fab2(sch_1):page42_i234@mstr_discrete.cap~
(chips)',
 P_PATH='@baseboard_fab2_lib.baseboard_fab2(sch_1):page42_i234@mstr_discrete.cap~
(chips)',
 PATH='I234',
 DRAWING='@BASEBOARD_FAB2_LIB.BASEBOARD_FAB2(SCH_1):PAGE42',
 NEW_PN='078.1071T.M002',
 NEW_MATERIAL='X6S',
 TOLERANCE='20%',
 SEC_TYPE='0805',
 MATERIAL='X5R',
 BOM_COST='MEM_VRD_PVDDQ_CD',
 PHYS_PAGE='42',
 XY='(-1250,2225)',
 ROT='0',
 VER='1',
 VALUE='100UF',
 PACK_TYPE='0805',
 PART_NUMBER='602433-112',
 LOCATION='C5P20',
 ROOM='VDDQ_ABC_PWR_VR',
 GROUP='PWR_MCP_CAP',
 SEC='1',
 CDS_LIB='mstr_discrete',
 CDS_PART_NAME='CAP_0805-100UF,4V,20%,X5R,6024A',
 VOLTAGE='4V',
 PRIM_FILE='./archive_libs/mstr_discrete/cap/chips/chips.prt';

PART_NAME
 C5P21 'CAP_0805-100UF,4V,20%,X5R,6024A':
 GROUP='PWR_MCP_CAP',
 ROOM='VDDQ_ABC_PWR_VR';

SECTION_NUMBER 1
 '@BASEBOARD_FAB2_LIB.BASEBOARD_FAB2(SCH_1):PAGE42_I235@MSTR_DISCRETE.CAP(CHIPS)':
 C_PATH='@baseboard_fab2_lib.baseboard_fab2(sch_1):page42_i235@mstr_discrete.cap~
(chips)',
 P_PATH='@baseboard_fab2_lib.baseboard_fab2(sch_1):page42_i235@mstr_discrete.cap~
(chips)',
 PATH='I235',
 DRAWING='@BASEBOARD_FAB2_LIB.BASEBOARD_FAB2(SCH_1):PAGE42',
 NEW_PN='078.1071T.M002',
 NEW_MATERIAL='X6S',
 TOLERANCE='20%',
 SEC_TYPE='0805',
 MATERIAL='X5R',
 BOM_COST='MEM_VRD_PVDDQ_CD',
 PHYS_PAGE='42',
 XY='(-1000,2225)',
 ROT='0',
 VER='1',
 VALUE='100UF',
 PACK_TYPE='0805',
 PART_NUMBER='602433-112',
 LOCATION='C5P21',
 ROOM='VDDQ_ABC_PWR_VR',
 GROUP='PWR_MCP_CAP',
 SEC='1',
 CDS_LIB='mstr_discrete',
 CDS_PART_NAME='CAP_0805-100UF,4V,20%,X5R,6024A',
 VOLTAGE='4V',
 PRIM_FILE='./archive_libs/mstr_discrete/cap/chips/chips.prt';

PART_NAME
 C5P22 'CAP_0805-47UF,4V,20%,X6S,C9533A':
 GROUP='PWR_MLCC_CAP',
 ROOM='PVCCIN_CPU0_DECAP_VR';

SECTION_NUMBER 1
 '@BASEBOARD_FAB2_LIB.BASEBOARD_FAB2(SCH_1):PAGE42_I55@MSTR_DISCRETE.CAP(CHIPS)':
 C_PATH='@baseboard_fab2_lib.baseboard_fab2(sch_1):page42_i55@mstr_discrete.cap(~
chips)',
 P_PATH='@baseboard_fab2_lib.baseboard_fab2(sch_1):page42_i55@mstr_discrete.cap(~
chips)',
 PATH='I55',
 DRAWING='@BASEBOARD_FAB2_LIB.BASEBOARD_FAB2(SCH_1):PAGE42',
 TOLERANCE='20%',
 MATERIAL='X6S',
 BOM_COST='PROC_SOCKET',
 PHYS_PAGE='42',
 XY='(-5650,850)',
 ROT='0',
 VER='1',
 VALUE='47UF',
 PACK_TYPE='0805',
 PART_NUMBER='C95333-006',
 LOCATION='C5P22',
 ROOM='PVCCIN_CPU0_DECAP_VR',
 GROUP='PWR_MLCC_CAP',
 CDS_LIB='mstr_discrete',
 CDS_PART_NAME='CAP_0805-47UF,4V,20%,X6S,C9533A',
 VOLTAGE='4V',
 PRIM_FILE='./archive_libs/mstr_discrete/cap/chips/chips.prt';

PART_NAME
 C5P23 'CAP_0805-47UF,4V,20%,X6S,C9533A':
 GROUP='PWR_MLCC_CAP',
 ROOM='PVCCIN_CPU0_DECAP_VR';

SECTION_NUMBER 1
 '@BASEBOARD_FAB2_LIB.BASEBOARD_FAB2(SCH_1):PAGE42_I28@MSTR_DISCRETE.CAP(CHIPS)':
 C_PATH='@baseboard_fab2_lib.baseboard_fab2(sch_1):page42_i28@mstr_discrete.cap(~
chips)',
 P_PATH='@baseboard_fab2_lib.baseboard_fab2(sch_1):page42_i28@mstr_discrete.cap(~
chips)',
 PATH='I28',
 DRAWING='@BASEBOARD_FAB2_LIB.BASEBOARD_FAB2(SCH_1):PAGE42',
 TOLERANCE='20%',
 MATERIAL='X6S',
 BOM_COST='PROC_SOCKET',
 PHYS_PAGE='42',
 XY='(-5350,2250)',
 ROT='0',
 VER='1',
 VALUE='47UF',
 PACK_TYPE='0805',
 PART_NUMBER='C95333-006',
 LOCATION='C5P23',
 ROOM='PVCCIN_CPU0_DECAP_VR',
 GROUP='PWR_MLCC_CAP',
 CDS_LIB='mstr_discrete',
 CDS_PART_NAME='CAP_0805-47UF,4V,20%,X6S,C9533A',
 VOLTAGE='4V',
 PRIM_FILE='./archive_libs/mstr_discrete/cap/chips/chips.prt';

PART_NAME
 C5P24 'CAP_0805-47UF,4V,20%,X6S,C9533A':
 GROUP='PWR_MLCC_CAP',
 ROOM='PVCCIN_CPU0_DECAP_VR';

SECTION_NUMBER 1
 '@BASEBOARD_FAB2_LIB.BASEBOARD_FAB2(SCH_1):PAGE42_I33@MSTR_DISCRETE.CAP(CHIPS)':
 C_PATH='@baseboard_fab2_lib.baseboard_fab2(sch_1):page42_i33@mstr_discrete.cap(~
chips)',
 P_PATH='@baseboard_fab2_lib.baseboard_fab2(sch_1):page42_i33@mstr_discrete.cap(~
chips)',
 PATH='I33',
 DRAWING='@BASEBOARD_FAB2_LIB.BASEBOARD_FAB2(SCH_1):PAGE42',
 TOLERANCE='20%',
 MATERIAL='X6S',
 BOM_COST='PROC_SOCKET',
 PHYS_PAGE='42',
 XY='(-5050,1550)',
 ROT='0',
 VER='1',
 VALUE='47UF',
 PACK_TYPE='0805',
 PART_NUMBER='C95333-006',
 LOCATION='C5P24',
 ROOM='PVCCIN_CPU0_DECAP_VR',
 GROUP='PWR_MLCC_CAP',
 CDS_LIB='mstr_discrete',
 CDS_PART_NAME='CAP_0805-47UF,4V,20%,X6S,C9533A',
 VOLTAGE='4V',
 PRIM_FILE='./archive_libs/mstr_discrete/cap/chips/chips.prt';

PART_NAME
 C5P25 'CAP_0805-47UF,4V,20%,X6S,C9533A':
 GROUP='PWR_MLCC_CAP',
 ROOM='PVCCIN_CPU0_DECAP_VR';

SECTION_NUMBER 1
 '@BASEBOARD_FAB2_LIB.BASEBOARD_FAB2(SCH_1):PAGE42_I37@MSTR_DISCRETE.CAP(CHIPS)':
 C_PATH='@baseboard_fab2_lib.baseboard_fab2(sch_1):page42_i37@mstr_discrete.cap(~
chips)',
 P_PATH='@baseboard_fab2_lib.baseboard_fab2(sch_1):page42_i37@mstr_discrete.cap(~
chips)',
 PATH='I37',
 DRAWING='@BASEBOARD_FAB2_LIB.BASEBOARD_FAB2(SCH_1):PAGE42',
 TOLERANCE='20%',
 MATERIAL='X6S',
 BOM_COST='PROC_SOCKET',
 PHYS_PAGE='42',
 XY='(-5350,850)',
 ROT='0',
 VER='1',
 VALUE='47UF',
 PACK_TYPE='0805',
 PART_NUMBER='C95333-006',
 LOCATION='C5P25',
 ROOM='PVCCIN_CPU0_DECAP_VR',
 GROUP='PWR_MLCC_CAP',
 CDS_LIB='mstr_discrete',
 CDS_PART_NAME='CAP_0805-47UF,4V,20%,X6S,C9533A',
 VOLTAGE='4V',
 PRIM_FILE='./archive_libs/mstr_discrete/cap/chips/chips.prt';

PART_NAME
 C5P26 'CAP_0805-47UF,4V,20%,X6S,C9533A':
 GROUP='PWR_MLCC_CAP',
 ROOM='PVCCIN_CPU0_DECAP_VR';

SECTION_NUMBER 1
 '@BASEBOARD_FAB2_LIB.BASEBOARD_FAB2(SCH_1):PAGE42_I56@MSTR_DISCRETE.CAP(CHIPS)':
 C_PATH='@baseboard_fab2_lib.baseboard_fab2(sch_1):page42_i56@mstr_discrete.cap(~
chips)',
 P_PATH='@baseboard_fab2_lib.baseboard_fab2(sch_1):page42_i56@mstr_discrete.cap(~
chips)',
 PATH='I56',
 DRAWING='@BASEBOARD_FAB2_LIB.BASEBOARD_FAB2(SCH_1):PAGE42',
 TOLERANCE='20%',
 MATERIAL='X6S',
 BOM_COST='PROC_SOCKET',
 PHYS_PAGE='42',
 XY='(-5950,850)',
 ROT='0',
 VER='1',
 VALUE='47UF',
 PACK_TYPE='0805',
 PART_NUMBER='C95333-006',
 LOCATION='C5P26',
 ROOM='PVCCIN_CPU0_DECAP_VR',
 GROUP='PWR_MLCC_CAP',
 CDS_LIB='mstr_discrete',
 CDS_PART_NAME='CAP_0805-47UF,4V,20%,X6S,C9533A',
 VOLTAGE='4V',
 PRIM_FILE='./archive_libs/mstr_discrete/cap/chips/chips.prt';

PART_NAME
 C5P27 'CAP_0805-47UF,4V,20%,X6S,C9533A':
 GROUP='PWR_MLCC_CAP',
 ROOM='PVCCIN_CPU0_DECAP_VR';

SECTION_NUMBER 1
 '@BASEBOARD_FAB2_LIB.BASEBOARD_FAB2(SCH_1):PAGE42_I44@MSTR_DISCRETE.CAP(CHIPS)':
 C_PATH='@baseboard_fab2_lib.baseboard_fab2(sch_1):page42_i44@mstr_discrete.cap(~
chips)',
 P_PATH='@baseboard_fab2_lib.baseboard_fab2(sch_1):page42_i44@mstr_discrete.cap(~
chips)',
 PATH='I44',
 DRAWING='@BASEBOARD_FAB2_LIB.BASEBOARD_FAB2(SCH_1):PAGE42',
 TOLERANCE='20%',
 MATERIAL='X6S',
 BOM_COST='PROC_SOCKET',
 PHYS_PAGE='42',
 XY='(-5950,1550)',
 ROT='0',
 VER='1',
 VALUE='47UF',
 PACK_TYPE='0805',
 PART_NUMBER='C95333-006',
 LOCATION='C5P27',
 ROOM='PVCCIN_CPU0_DECAP_VR',
 GROUP='PWR_MLCC_CAP',
 CDS_LIB='mstr_discrete',
 CDS_PART_NAME='CAP_0805-47UF,4V,20%,X6S,C9533A',
 VOLTAGE='4V',
 PRIM_FILE='./archive_libs/mstr_discrete/cap/chips/chips.prt';

PART_NAME
 C5P28 'CAP_0805-100UF,4V,20%,X5R,6024A':
 GROUP='PWR_MCP_CAP',
 ROOM='VDDQ_ABC_PWR_VR';

SECTION_NUMBER 1
 '@BASEBOARD_FAB2_LIB.BASEBOARD_FAB2(SCH_1):PAGE42_I229@MSTR_DISCRETE.CAP(CHIPS)':
 C_PATH='@baseboard_fab2_lib.baseboard_fab2(sch_1):page42_i229@mstr_discrete.cap~
(chips)',
 P_PATH='@baseboard_fab2_lib.baseboard_fab2(sch_1):page42_i229@mstr_discrete.cap~
(chips)',
 PATH='I229',
 DRAWING='@BASEBOARD_FAB2_LIB.BASEBOARD_FAB2(SCH_1):PAGE42',
 NEW_PN='078.1071T.M002',
 NEW_MATERIAL='X6S',
 TOLERANCE='20%',
 SEC_TYPE='0805',
 MATERIAL='X5R',
 BOM_COST='MEM_VRD_PVDDQ_CD',
 PHYS_PAGE='42',
 XY='(-2750,2225)',
 ROT='0',
 VER='1',
 VALUE='100UF',
 PACK_TYPE='0805',
 PART_NUMBER='602433-112',
 LOCATION='C5P28',
 ROOM='VDDQ_ABC_PWR_VR',
 GROUP='PWR_MCP_CAP',
 SEC='1',
 CDS_LIB='mstr_discrete',
 CDS_PART_NAME='CAP_0805-100UF,4V,20%,X5R,6024A',
 VOLTAGE='4V',
 PRIM_FILE='./archive_libs/mstr_discrete/cap/chips/chips.prt';

PART_NAME
 C5P29 'CAP_0805-100UF,4V,20%,X5R,6024A':
 GROUP='PWR_MCP_CAP',
 ROOM='VDDQ_ABC_PWR_VR';

SECTION_NUMBER 1
 '@BASEBOARD_FAB2_LIB.BASEBOARD_FAB2(SCH_1):PAGE42_I220@MSTR_DISCRETE.CAP(CHIPS)':
 C_PATH='@baseboard_fab2_lib.baseboard_fab2(sch_1):page42_i220@mstr_discrete.cap~
(chips)',
 P_PATH='@baseboard_fab2_lib.baseboard_fab2(sch_1):page42_i220@mstr_discrete.cap~
(chips)',
 PATH='I220',
 DRAWING='@BASEBOARD_FAB2_LIB.BASEBOARD_FAB2(SCH_1):PAGE42',
 NEW_PN='078.1071T.M002',
 NEW_MATERIAL='X6S',
 TOLERANCE='20%',
 SEC_TYPE='0805',
 MATERIAL='X5R',
 BOM_COST='MEM_VRD_PVDDQ_CD',
 PHYS_PAGE='42',
 XY='(-4750,2225)',
 ROT='0',
 VER='1',
 VALUE='100UF',
 PACK_TYPE='0805',
 PART_NUMBER='602433-112',
 LOCATION='C5P29',
 ROOM='VDDQ_ABC_PWR_VR',
 GROUP='PWR_MCP_CAP',
 SEC='1',
 CDS_LIB='mstr_discrete',
 CDS_PART_NAME='CAP_0805-100UF,4V,20%,X5R,6024A',
 VOLTAGE='4V',
 PRIM_FILE='./archive_libs/mstr_discrete/cap/chips/chips.prt';

PART_NAME
 C5P30 'CAP_0805-100UF,4V,20%,X5R,6024A':
 GROUP='PWR_MCP_CAP',
 ROOM='VDDQ_ABC_PWR_VR';

SECTION_NUMBER 1
 '@BASEBOARD_FAB2_LIB.BASEBOARD_FAB2(SCH_1):PAGE42_I221@MSTR_DISCRETE.CAP(CHIPS)':
 C_PATH='@baseboard_fab2_lib.baseboard_fab2(sch_1):page42_i221@mstr_discrete.cap~
(chips)',
 P_PATH='@baseboard_fab2_lib.baseboard_fab2(sch_1):page42_i221@mstr_discrete.cap~
(chips)',
 PATH='I221',
 DRAWING='@BASEBOARD_FAB2_LIB.BASEBOARD_FAB2(SCH_1):PAGE42',
 NEW_PN='078.1071T.M002',
 NEW_MATERIAL='X6S',
 TOLERANCE='20%',
 SEC_TYPE='0805',
 MATERIAL='X5R',
 BOM_COST='MEM_VRD_PVDDQ_CD',
 PHYS_PAGE='42',
 XY='(-4500,2225)',
 ROT='0',
 VER='1',
 VALUE='100UF',
 PACK_TYPE='0805',
 PART_NUMBER='602433-112',
 LOCATION='C5P30',
 ROOM='VDDQ_ABC_PWR_VR',
 GROUP='PWR_MCP_CAP',
 SEC='1',
 CDS_LIB='mstr_discrete',
 CDS_PART_NAME='CAP_0805-100UF,4V,20%,X5R,6024A',
 VOLTAGE='4V',
 PRIM_FILE='./archive_libs/mstr_discrete/cap/chips/chips.prt';

PART_NAME
 C5P31 'CAP_0805-100UF,4V,20%,X5R,6024A':
 GROUP='PWR_MCP_CAP',
 ROOM='VDDQ_ABC_PWR_VR';

SECTION_NUMBER 1
 '@BASEBOARD_FAB2_LIB.BASEBOARD_FAB2(SCH_1):PAGE42_I231@MSTR_DISCRETE.CAP(CHIPS)':
 C_PATH='@baseboard_fab2_lib.baseboard_fab2(sch_1):page42_i231@mstr_discrete.cap~
(chips)',
 P_PATH='@baseboard_fab2_lib.baseboard_fab2(sch_1):page42_i231@mstr_discrete.cap~
(chips)',
 PATH='I231',
 DRAWING='@BASEBOARD_FAB2_LIB.BASEBOARD_FAB2(SCH_1):PAGE42',
 NEW_PN='078.1071T.M002',
 NEW_MATERIAL='X6S',
 TOLERANCE='20%',
 SEC_TYPE='0805',
 MATERIAL='X5R',
 BOM_COST='MEM_VRD_PVDDQ_CD',
 PHYS_PAGE='42',
 XY='(-2250,2225)',
 ROT='0',
 VER='1',
 VALUE='100UF',
 PACK_TYPE='0805',
 PART_NUMBER='602433-112',
 LOCATION='C5P31',
 ROOM='VDDQ_ABC_PWR_VR',
 GROUP='PWR_MCP_CAP',
 SEC='1',
 CDS_LIB='mstr_discrete',
 CDS_PART_NAME='CAP_0805-100UF,4V,20%,X5R,6024A',
 VOLTAGE='4V',
 PRIM_FILE='./archive_libs/mstr_discrete/cap/chips/chips.prt';

PART_NAME
 C5P32 'CAP_0805-47UF,4V,20%,X6S,C9533A':
 GROUP='PWR_MLCC_CAP',
 ROOM='PVCCIN_CPU0_DECAP_VR';

SECTION_NUMBER 1
 '@BASEBOARD_FAB2_LIB.BASEBOARD_FAB2(SCH_1):PAGE42_I53@MSTR_DISCRETE.CAP(CHIPS)':
 C_PATH='@baseboard_fab2_lib.baseboard_fab2(sch_1):page42_i53@mstr_discrete.cap(~
chips)',
 P_PATH='@baseboard_fab2_lib.baseboard_fab2(sch_1):page42_i53@mstr_discrete.cap(~
chips)',
 PATH='I53',
 DRAWING='@BASEBOARD_FAB2_LIB.BASEBOARD_FAB2(SCH_1):PAGE42',
 TOLERANCE='20%',
 MATERIAL='X6S',
 BOM_COST='PROC_SOCKET',
 PHYS_PAGE='42',
 XY='(-7150,1550)',
 ROT='0',
 VER='1',
 VALUE='47UF',
 PACK_TYPE='0805',
 PART_NUMBER='C95333-006',
 LOCATION='C5P32',
 ROOM='PVCCIN_CPU0_DECAP_VR',
 GROUP='PWR_MLCC_CAP',
 CDS_LIB='mstr_discrete',
 CDS_PART_NAME='CAP_0805-47UF,4V,20%,X6S,C9533A',
 VOLTAGE='4V',
 PRIM_FILE='./archive_libs/mstr_discrete/cap/chips/chips.prt';

PART_NAME
 C5P33 'CAP_0805-47UF,4V,20%,X6S,C9533A':
 GROUP='PWR_MLCC_CAP',
 ROOM='PVCCIN_CPU0_DECAP_VR';

SECTION_NUMBER 1
 '@BASEBOARD_FAB2_LIB.BASEBOARD_FAB2(SCH_1):PAGE42_I50@MSTR_DISCRETE.CAP(CHIPS)':
 C_PATH='@baseboard_fab2_lib.baseboard_fab2(sch_1):page42_i50@mstr_discrete.cap(~
chips)',
 P_PATH='@baseboard_fab2_lib.baseboard_fab2(sch_1):page42_i50@mstr_discrete.cap(~
chips)',
 PATH='I50',
 DRAWING='@BASEBOARD_FAB2_LIB.BASEBOARD_FAB2(SCH_1):PAGE42',
 TOLERANCE='20%',
 MATERIAL='X6S',
 BOM_COST='PROC_SOCKET',
 PHYS_PAGE='42',
 XY='(-7150,2250)',
 ROT='0',
 VER='1',
 VALUE='47UF',
 PACK_TYPE='0805',
 PART_NUMBER='C95333-006',
 LOCATION='C5P33',
 ROOM='PVCCIN_CPU0_DECAP_VR',
 GROUP='PWR_MLCC_CAP',
 CDS_LIB='mstr_discrete',
 CDS_PART_NAME='CAP_0805-47UF,4V,20%,X6S,C9533A',
 VOLTAGE='4V',
 PRIM_FILE='./archive_libs/mstr_discrete/cap/chips/chips.prt';

PART_NAME
 C5P34 'CAP_0805-47UF,4V,20%,X6S,C9533A':
 GROUP='PWR_MLCC_CAP',
 ROOM='PVCCIN_CPU0_DECAP_VR';

SECTION_NUMBER 1
 '@BASEBOARD_FAB2_LIB.BASEBOARD_FAB2(SCH_1):PAGE42_I54@MSTR_DISCRETE.CAP(CHIPS)':
 C_PATH='@baseboard_fab2_lib.baseboard_fab2(sch_1):page42_i54@mstr_discrete.cap(~
chips)',
 P_PATH='@baseboard_fab2_lib.baseboard_fab2(sch_1):page42_i54@mstr_discrete.cap(~
chips)',
 PATH='I54',
 DRAWING='@BASEBOARD_FAB2_LIB.BASEBOARD_FAB2(SCH_1):PAGE42',
 TOLERANCE='20%',
 MATERIAL='X6S',
 BOM_COST='PROC_SOCKET',
 PHYS_PAGE='42',
 XY='(-7450,1550)',
 ROT='0',
 VER='1',
 VALUE='47UF',
 PACK_TYPE='0805',
 PART_NUMBER='C95333-006',
 LOCATION='C5P34',
 ROOM='PVCCIN_CPU0_DECAP_VR',
 GROUP='PWR_MLCC_CAP',
 CDS_LIB='mstr_discrete',
 CDS_PART_NAME='CAP_0805-47UF,4V,20%,X6S,C9533A',
 VOLTAGE='4V',
 PRIM_FILE='./archive_libs/mstr_discrete/cap/chips/chips.prt';

PART_NAME
 C5P35 'CAP_0805-47UF,4V,20%,X6S,C9533A':
 GROUP='PWR_MLCC_CAP',
 ROOM='PVCCIN_CPU0_DECAP_VR';

SECTION_NUMBER 1
 '@BASEBOARD_FAB2_LIB.BASEBOARD_FAB2(SCH_1):PAGE42_I51@MSTR_DISCRETE.CAP(CHIPS)':
 C_PATH='@baseboard_fab2_lib.baseboard_fab2(sch_1):page42_i51@mstr_discrete.cap(~
chips)',
 P_PATH='@baseboard_fab2_lib.baseboard_fab2(sch_1):page42_i51@mstr_discrete.cap(~
chips)',
 PATH='I51',
 DRAWING='@BASEBOARD_FAB2_LIB.BASEBOARD_FAB2(SCH_1):PAGE42',
 TOLERANCE='20%',
 MATERIAL='X6S',
 BOM_COST='PROC_SOCKET',
 PHYS_PAGE='42',
 XY='(-7450,2250)',
 ROT='0',
 VER='1',
 VALUE='47UF',
 PACK_TYPE='0805',
 PART_NUMBER='C95333-006',
 LOCATION='C5P35',
 ROOM='PVCCIN_CPU0_DECAP_VR',
 GROUP='PWR_MLCC_CAP',
 CDS_LIB='mstr_discrete',
 CDS_PART_NAME='CAP_0805-47UF,4V,20%,X6S,C9533A',
 VOLTAGE='4V',
 PRIM_FILE='./archive_libs/mstr_discrete/cap/chips/chips.prt';

PART_NAME
 C5P36 'CAP_0805-47UF,4V,20%,X6S,C9533A':
 GROUP='PWR_MLCC_CAP',
 ROOM='PVCCIN_CPU0_DECAP_VR';

SECTION_NUMBER 1
 '@BASEBOARD_FAB2_LIB.BASEBOARD_FAB2(SCH_1):PAGE42_I65@MSTR_DISCRETE.CAP(CHIPS)':
 C_PATH='@baseboard_fab2_lib.baseboard_fab2(sch_1):page42_i65@mstr_discrete.cap(~
chips)',
 P_PATH='@baseboard_fab2_lib.baseboard_fab2(sch_1):page42_i65@mstr_discrete.cap(~
chips)',
 PATH='I65',
 DRAWING='@BASEBOARD_FAB2_LIB.BASEBOARD_FAB2(SCH_1):PAGE42',
 TOLERANCE='20%',
 MATERIAL='X6S',
 BOM_COST='PROC_SOCKET',
 PHYS_PAGE='42',
 XY='(-7750,1550)',
 ROT='0',
 VER='1',
 VALUE='47UF',
 PACK_TYPE='0805',
 PART_NUMBER='C95333-006',
 LOCATION='C5P36',
 ROOM='PVCCIN_CPU0_DECAP_VR',
 GROUP='PWR_MLCC_CAP',
 CDS_LIB='mstr_discrete',
 CDS_PART_NAME='CAP_0805-47UF,4V,20%,X6S,C9533A',
 VOLTAGE='4V',
 PRIM_FILE='./archive_libs/mstr_discrete/cap/chips/chips.prt';

PART_NAME
 C5P37 'CAP_0805-47UF,4V,20%,X6S,C9533A':
 GROUP='PWR_MLCC_CAP',
 ROOM='PVCCIN_CPU0_DECAP_VR';

SECTION_NUMBER 1
 '@BASEBOARD_FAB2_LIB.BASEBOARD_FAB2(SCH_1):PAGE42_I63@MSTR_DISCRETE.CAP(CHIPS)':
 C_PATH='@baseboard_fab2_lib.baseboard_fab2(sch_1):page42_i63@mstr_discrete.cap(~
chips)',
 P_PATH='@baseboard_fab2_lib.baseboard_fab2(sch_1):page42_i63@mstr_discrete.cap(~
chips)',
 PATH='I63',
 DRAWING='@BASEBOARD_FAB2_LIB.BASEBOARD_FAB2(SCH_1):PAGE42',
 TOLERANCE='20%',
 MATERIAL='X6S',
 BOM_COST='PROC_SOCKET',
 PHYS_PAGE='42',
 XY='(-7750,2250)',
 ROT='0',
 VER='1',
 VALUE='47UF',
 PACK_TYPE='0805',
 PART_NUMBER='C95333-006',
 LOCATION='C5P37',
 ROOM='PVCCIN_CPU0_DECAP_VR',
 GROUP='PWR_MLCC_CAP',
 CDS_LIB='mstr_discrete',
 CDS_PART_NAME='CAP_0805-47UF,4V,20%,X6S,C9533A',
 VOLTAGE='4V',
 PRIM_FILE='./archive_libs/mstr_discrete/cap/chips/chips.prt';

PART_NAME
 C5P38 'CAP_0805-100UF,4V,20%,X5R,6024A':
 GROUP='PWR_MLCC_CAP',
 ROOM='VDDQ_ABC_PWR_VR';

SECTION_NUMBER 1
 '@BASEBOARD_FAB2_LIB.BASEBOARD_FAB2(SCH_1):PAGE217_I327@MSTR_DISCRETE.CAP(CHIPS)':
 C_PATH='@baseboard_fab2_lib.baseboard_fab2(sch_1):page217_i327@mstr_discrete.ca~
p(chips)',
 P_PATH='@baseboard_fab2_lib.baseboard_fab2(sch_1):page217_i327@mstr_discrete.ca~
p(chips)',
 PATH='I327',
 DRAWING='@BASEBOARD_FAB2_LIB.BASEBOARD_FAB2(SCH_1):PAGE217',
 NEW_PN='078.1071T.M002',
 NEW_MATERIAL='X6S',
 BOM_SS='NOPOP',
 TOLERANCE='20%',
 SEC_TYPE='0805',
 MATERIAL='X5R',
 BOM_COST='MEM_VRD_PVDDQ_CD',
 PHYS_PAGE='217',
 XY='(-1400,2850)',
 ROT='0',
 VER='1',
 VALUE='100UF',
 PACK_TYPE='0805',
 PART_NUMBER='602433-112',
 LOCATION='C5P38',
 ROOM='VDDQ_ABC_PWR_VR',
 GROUP='PWR_MLCC_CAP',
 SEC='1',
 CDS_LIB='mstr_discrete',
 CDS_PART_NAME='CAP_0805-100UF,4V,20%,X5R,6024A',
 VOLTAGE='4V',
 PRIM_FILE='./archive_libs/mstr_discrete/cap/chips/chips.prt';

PART_NAME
 C5P39 'CAP_0805-100UF,4V,20%,X5R,6024A':
 GROUP='PWR_MLCC_CAP',
 ROOM='VDDQ_ABC_PWR_VR';

SECTION_NUMBER 1
 '@BASEBOARD_FAB2_LIB.BASEBOARD_FAB2(SCH_1):PAGE217_I328@MSTR_DISCRETE.CAP(CHIPS)':
 C_PATH='@baseboard_fab2_lib.baseboard_fab2(sch_1):page217_i328@mstr_discrete.ca~
p(chips)',
 P_PATH='@baseboard_fab2_lib.baseboard_fab2(sch_1):page217_i328@mstr_discrete.ca~
p(chips)',
 PATH='I328',
 DRAWING='@BASEBOARD_FAB2_LIB.BASEBOARD_FAB2(SCH_1):PAGE217',
 NEW_PN='078.1071T.M002',
 NEW_MATERIAL='X6S',
 BOM_SS='NOPOP',
 TOLERANCE='20%',
 SEC_TYPE='0805',
 MATERIAL='X5R',
 BOM_COST='MEM_VRD_PVDDQ_CD',
 PHYS_PAGE='217',
 XY='(-1750,2850)',
 ROT='0',
 VER='1',
 VALUE='100UF',
 PACK_TYPE='0805',
 PART_NUMBER='602433-112',
 LOCATION='C5P39',
 ROOM='VDDQ_ABC_PWR_VR',
 GROUP='PWR_MLCC_CAP',
 SEC='1',
 CDS_LIB='mstr_discrete',
 CDS_PART_NAME='CAP_0805-100UF,4V,20%,X5R,6024A',
 VOLTAGE='4V',
 PRIM_FILE='./archive_libs/mstr_discrete/cap/chips/chips.prt';

PART_NAME
 C5P40 'CAP_0805-47UF,4V,20%,X6S,C9533A':
 GROUP='PWR_MLCC_CAP',
 ROOM='PVCCIN_CPU0_DECAP_VR';

SECTION_NUMBER 1
 '@BASEBOARD_FAB2_LIB.BASEBOARD_FAB2(SCH_1):PAGE42_I57@MSTR_DISCRETE.CAP(CHIPS)':
 C_PATH='@baseboard_fab2_lib.baseboard_fab2(sch_1):page42_i57@mstr_discrete.cap(~
chips)',
 P_PATH='@baseboard_fab2_lib.baseboard_fab2(sch_1):page42_i57@mstr_discrete.cap(~
chips)',
 PATH='I57',
 DRAWING='@BASEBOARD_FAB2_LIB.BASEBOARD_FAB2(SCH_1):PAGE42',
 TOLERANCE='20%',
 MATERIAL='X6S',
 BOM_COST='PROC_SOCKET',
 PHYS_PAGE='42',
 XY='(-6550,850)',
 ROT='0',
 VER='1',
 VALUE='47UF',
 PACK_TYPE='0805',
 PART_NUMBER='C95333-006',
 LOCATION='C5P40',
 ROOM='PVCCIN_CPU0_DECAP_VR',
 GROUP='PWR_MLCC_CAP',
 CDS_LIB='mstr_discrete',
 CDS_PART_NAME='CAP_0805-47UF,4V,20%,X6S,C9533A',
 VOLTAGE='4V',
 PRIM_FILE='./archive_libs/mstr_discrete/cap/chips/chips.prt';

PART_NAME
 C5P41 'CAP_0805-100UF,4V,20%,X5R,6024A':
 GROUP='PWR_MLCC_CAP',
 ROOM='VDDQ_ABC_PWR_VR';

SECTION_NUMBER 1
 '@BASEBOARD_FAB2_LIB.BASEBOARD_FAB2(SCH_1):PAGE217_I323@MSTR_DISCRETE.CAP(CHIPS)':
 C_PATH='@baseboard_fab2_lib.baseboard_fab2(sch_1):page217_i323@mstr_discrete.ca~
p(chips)',
 P_PATH='@baseboard_fab2_lib.baseboard_fab2(sch_1):page217_i323@mstr_discrete.ca~
p(chips)',
 PATH='I323',
 DRAWING='@BASEBOARD_FAB2_LIB.BASEBOARD_FAB2(SCH_1):PAGE217',
 NEW_PN='078.1071T.M002',
 NEW_MATERIAL='X6S',
 BOM_SS='NOPOP',
 TOLERANCE='20%',
 SEC_TYPE='0805',
 MATERIAL='X5R',
 BOM_COST='MEM_VRD_PVDDQ_CD',
 PHYS_PAGE='217',
 XY='(2000,2875)',
 ROT='0',
 VER='1',
 VALUE='100UF',
 PACK_TYPE='0805',
 PART_NUMBER='602433-112',
 LOCATION='C5P41',
 ROOM='VDDQ_ABC_PWR_VR',
 GROUP='PWR_MLCC_CAP',
 SEC='1',
 CDS_LIB='mstr_discrete',
 CDS_PART_NAME='CAP_0805-100UF,4V,20%,X5R,6024A',
 VOLTAGE='4V',
 PRIM_FILE='./archive_libs/mstr_discrete/cap/chips/chips.prt';

PART_NAME
 C5P42 'CAP_0805-100UF,4V,20%,X5R,6024A':
 GROUP='PWR_MLCC_CAP',
 ROOM='VDDQ_ABC_PWR_VR';

SECTION_NUMBER 1
 '@BASEBOARD_FAB2_LIB.BASEBOARD_FAB2(SCH_1):PAGE217_I325@MSTR_DISCRETE.CAP(CHIPS)':
 C_PATH='@baseboard_fab2_lib.baseboard_fab2(sch_1):page217_i325@mstr_discrete.ca~
p(chips)',
 P_PATH='@baseboard_fab2_lib.baseboard_fab2(sch_1):page217_i325@mstr_discrete.ca~
p(chips)',
 PATH='I325',
 DRAWING='@BASEBOARD_FAB2_LIB.BASEBOARD_FAB2(SCH_1):PAGE217',
 NEW_PN='078.1071T.M002',
 NEW_MATERIAL='X6S',
 BOM_SS='NOPOP',
 TOLERANCE='20%',
 MATERIAL='X5R',
 BOM_COST='MEM_VRD_PVDDQ_CD',
 PHYS_PAGE='217',
 XY='(1375,2850)',
 ROT='0',
 VER='1',
 VALUE='100UF',
 PACK_TYPE='0805',
 PART_NUMBER='602433-112',
 LOCATION='C5P42',
 ROOM='VDDQ_ABC_PWR_VR',
 GROUP='PWR_MLCC_CAP',
 CDS_LIB='mstr_discrete',
 CDS_PART_NAME='CAP_0805-100UF,4V,20%,X5R,6024A',
 VOLTAGE='4V',
 PRIM_FILE='./archive_libs/mstr_discrete/cap/chips/chips.prt';

PART_NAME
 C5P43 'CAP_0805-100UF,4V,20%,X5R,6024A':
 GROUP='PWR_MLCC_CAP',
 ROOM='VDDQ_ABC_PWR_VR';

SECTION_NUMBER 1
 '@BASEBOARD_FAB2_LIB.BASEBOARD_FAB2(SCH_1):PAGE217_I326@MSTR_DISCRETE.CAP(CHIPS)':
 C_PATH='@baseboard_fab2_lib.baseboard_fab2(sch_1):page217_i326@mstr_discrete.ca~
p(chips)',
 P_PATH='@baseboard_fab2_lib.baseboard_fab2(sch_1):page217_i326@mstr_discrete.ca~
p(chips)',
 PATH='I326',
 DRAWING='@BASEBOARD_FAB2_LIB.BASEBOARD_FAB2(SCH_1):PAGE217',
 NEW_PN='078.1071T.M002',
 NEW_MATERIAL='X6S',
 BOM_SS='NOPOP',
 TOLERANCE='20%',
 MATERIAL='X5R',
 BOM_COST='MEM_VRD_PVDDQ_CD',
 PHYS_PAGE='217',
 XY='(1025,2850)',
 ROT='0',
 VER='1',
 VALUE='100UF',
 PACK_TYPE='0805',
 PART_NUMBER='602433-112',
 LOCATION='C5P43',
 ROOM='VDDQ_ABC_PWR_VR',
 GROUP='PWR_MLCC_CAP',
 CDS_LIB='mstr_discrete',
 CDS_PART_NAME='CAP_0805-100UF,4V,20%,X5R,6024A',
 VOLTAGE='4V',
 PRIM_FILE='./archive_libs/mstr_discrete/cap/chips/chips.prt';

PART_NAME
 C5P44 'CAP_0805-100UF,4V,20%,X5R,6024A':
 GROUP='PWR_MLCC_CAP',
 ROOM='VDDQ_ABC_PWR_VR';

SECTION_NUMBER 1
 '@BASEBOARD_FAB2_LIB.BASEBOARD_FAB2(SCH_1):PAGE217_I324@MSTR_DISCRETE.CAP(CHIPS)':
 C_PATH='@baseboard_fab2_lib.baseboard_fab2(sch_1):page217_i324@mstr_discrete.ca~
p(chips)',
 P_PATH='@baseboard_fab2_lib.baseboard_fab2(sch_1):page217_i324@mstr_discrete.ca~
p(chips)',
 PATH='I324',
 DRAWING='@BASEBOARD_FAB2_LIB.BASEBOARD_FAB2(SCH_1):PAGE217',
 NEW_PN='078.1071T.M002',
 NEW_MATERIAL='X6S',
 BOM_SS='NOPOP',
 TOLERANCE='20%',
 SEC_TYPE='0805',
 MATERIAL='X5R',
 BOM_COST='MEM_VRD_PVDDQ_CD',
 PHYS_PAGE='217',
 XY='(700,2850)',
 ROT='0',
 VER='1',
 VALUE='100UF',
 PACK_TYPE='0805',
 PART_NUMBER='602433-112',
 LOCATION='C5P44',
 ROOM='VDDQ_ABC_PWR_VR',
 GROUP='PWR_MLCC_CAP',
 SEC='1',
 CDS_LIB='mstr_discrete',
 CDS_PART_NAME='CAP_0805-100UF,4V,20%,X5R,6024A',
 VOLTAGE='4V',
 PRIM_FILE='./archive_libs/mstr_discrete/cap/chips/chips.prt';

PART_NAME
 C5T1 'CAP_A_0603V-47UF,4V,20%,X5R,60A':
 GROUP='PWR_MLCC_CAP';

SECTION_NUMBER 1
 '@BASEBOARD_FAB2_LIB.BASEBOARD_FAB2(SCH_1):PAGE217_I212@DEV_DISCRETE.CAP_A(CHIPS)':
 C_PATH='@baseboard_fab2_lib.baseboard_fab2(sch_1):page217_i212@dev_discrete.cap~
_a(chips)',
 P_PATH='@baseboard_fab2_lib.baseboard_fab2(sch_1):page217_i212@dev_discrete.cap~
_a(chips)',
 PATH='I212',
 DRAWING='@BASEBOARD_FAB2_LIB.BASEBOARD_FAB2(SCH_1):PAGE217',
 BOM_SS='NOPOP',
 TOLERANCE='20%',
 SEC_TYPE='0603V',
 MATERIAL='X5R',
 PHYS_PAGE='217',
 XY='(3250,1725)',
 ROT='0',
 VER='1',
 VALUE='47UF',
 PACK_TYPE='0603V',
 PART_NUMBER='602433-106',
 LOCATION='C5T1',
 GROUP='PWR_MLCC_CAP',
 SEC='1',
 CDS_LIB='dev_discrete',
 CDS_PART_NAME='CAP_A_0603V-47UF,4V,20%,X5R,60A',
 VOLTAGE='4V',
 PRIM_FILE='./archive_libs/discrete/cap_a/chips/chips.prt';

PART_NAME
 C5T2 'CAP_A_0603V-47UF,4V,20%,X5R,60A':
 GROUP='PWR_MLCC_CAP';

SECTION_NUMBER 1
 '@BASEBOARD_FAB2_LIB.BASEBOARD_FAB2(SCH_1):PAGE217_I208@DEV_DISCRETE.CAP_A(CHIPS)':
 C_PATH='@baseboard_fab2_lib.baseboard_fab2(sch_1):page217_i208@dev_discrete.cap~
_a(chips)',
 P_PATH='@baseboard_fab2_lib.baseboard_fab2(sch_1):page217_i208@dev_discrete.cap~
_a(chips)',
 PATH='I208',
 DRAWING='@BASEBOARD_FAB2_LIB.BASEBOARD_FAB2(SCH_1):PAGE217',
 BOM_SS='NOPOP',
 TOLERANCE='20%',
 SEC_TYPE='0603V',
 MATERIAL='X5R',
 PHYS_PAGE='217',
 XY='(4000,1725)',
 ROT='0',
 VER='1',
 VALUE='47UF',
 PACK_TYPE='0603V',
 PART_NUMBER='602433-106',
 LOCATION='C5T2',
 GROUP='PWR_MLCC_CAP',
 SEC='1',
 CDS_LIB='dev_discrete',
 CDS_PART_NAME='CAP_A_0603V-47UF,4V,20%,X5R,60A',
 VOLTAGE='4V',
 PRIM_FILE='./archive_libs/discrete/cap_a/chips/chips.prt';

PART_NAME
 C5T3 'CAP_A_0603V-47UF,4V,20%,X5R,60A':
 GROUP='PWR_MLCC_CAP';

SECTION_NUMBER 1
 '@BASEBOARD_FAB2_LIB.BASEBOARD_FAB2(SCH_1):PAGE221_I40@DEV_DISCRETE.CAP_A(CHIPS)':
 C_PATH='@baseboard_fab2_lib.baseboard_fab2(sch_1):page221_i40@dev_discrete.cap_~
a(chips)',
 P_PATH='@baseboard_fab2_lib.baseboard_fab2(sch_1):page221_i40@dev_discrete.cap_~
a(chips)',
 PATH='I40',
 DRAWING='@BASEBOARD_FAB2_LIB.BASEBOARD_FAB2(SCH_1):PAGE221',
 TOLERANCE='20%',
 SEC_TYPE='0603V',
 MATERIAL='X5R',
 PHYS_PAGE='221',
 XY='(4075,3300)',
 ROT='0',
 VER='1',
 VALUE='47UF',
 PACK_TYPE='0603V',
 PART_NUMBER='602433-106',
 LOCATION='C5T3',
 GROUP='PWR_MLCC_CAP',
 SEC='1',
 CDS_LIB='dev_discrete',
 CDS_PART_NAME='CAP_A_0603V-47UF,4V,20%,X5R,60A',
 VOLTAGE='4V',
 PRIM_FILE='./archive_libs/discrete/cap_a/chips/chips.prt';

PART_NAME
 C5T4 'CAP_A_0603V-47UF,4V,20%,X5R,60A':
 GROUP='PWR_MLCC_CAP';

SECTION_NUMBER 1
 '@BASEBOARD_FAB2_LIB.BASEBOARD_FAB2(SCH_1):PAGE217_I211@DEV_DISCRETE.CAP_A(CHIPS)':
 C_PATH='@baseboard_fab2_lib.baseboard_fab2(sch_1):page217_i211@dev_discrete.cap~
_a(chips)',
 P_PATH='@baseboard_fab2_lib.baseboard_fab2(sch_1):page217_i211@dev_discrete.cap~
_a(chips)',
 PATH='I211',
 DRAWING='@BASEBOARD_FAB2_LIB.BASEBOARD_FAB2(SCH_1):PAGE217',
 BOM_SS='078.1061T.M001',
 TOLERANCE='20%',
 SEC_TYPE='0603V',
 MATERIAL='X5R',
 PHYS_PAGE='217',
 XY='(3650,1725)',
 ROT='0',
 VER='1',
 VALUE='47UF',
 PACK_TYPE='0603V',
 PART_NUMBER='602433-106',
 LOCATION='C5T4',
 GROUP='PWR_MLCC_CAP',
 SEC='1',
 CDS_LIB='dev_discrete',
 CDS_PART_NAME='CAP_A_0603V-47UF,4V,20%,X5R,60A',
 VOLTAGE='4V',
 PRIM_FILE='./archive_libs/discrete/cap_a/chips/chips.prt';

PART_NAME
 C5T5 'CAP_A_0603V-47UF,4V,20%,X5R,60A':
 GROUP='PWR_MLCC_CAP';

SECTION_NUMBER 1
 '@BASEBOARD_FAB2_LIB.BASEBOARD_FAB2(SCH_1):PAGE217_I298@DEV_DISCRETE.CAP_A(CHIPS)':
 C_PATH='@baseboard_fab2_lib.baseboard_fab2(sch_1):page217_i298@dev_discrete.cap~
_a(chips)',
 P_PATH='@baseboard_fab2_lib.baseboard_fab2(sch_1):page217_i298@dev_discrete.cap~
_a(chips)',
 PATH='I298',
 DRAWING='@BASEBOARD_FAB2_LIB.BASEBOARD_FAB2(SCH_1):PAGE217',
 BOM_SS='E15431-004',
 TOLERANCE='20%',
 SEC_TYPE='0603V',
 MATERIAL='X5R',
 PHYS_PAGE='217',
 XY='(2550,50)',
 ROT='0',
 VER='1',
 VALUE='47UF',
 PACK_TYPE='0603V',
 PART_NUMBER='602433-106',
 LOCATION='C5T5',
 GROUP='PWR_MLCC_CAP',
 SEC='1',
 CDS_LIB='dev_discrete',
 CDS_PART_NAME='CAP_A_0603V-47UF,4V,20%,X5R,60A',
 VOLTAGE='4V',
 PRIM_FILE='./archive_libs/discrete/cap_a/chips/chips.prt';

PART_NAME
 C5T6 'CAP_A_0603V-47UF,4V,20%,X5R,60A':
 GROUP='PWR_MLCC_CAP';

SECTION_NUMBER 1
 '@BASEBOARD_FAB2_LIB.BASEBOARD_FAB2(SCH_1):PAGE217_I297@DEV_DISCRETE.CAP_A(CHIPS)':
 C_PATH='@baseboard_fab2_lib.baseboard_fab2(sch_1):page217_i297@dev_discrete.cap~
_a(chips)',
 P_PATH='@baseboard_fab2_lib.baseboard_fab2(sch_1):page217_i297@dev_discrete.cap~
_a(chips)',
 PATH='I297',
 DRAWING='@BASEBOARD_FAB2_LIB.BASEBOARD_FAB2(SCH_1):PAGE217',
 BOM_SS='E15431-004',
 TOLERANCE='20%',
 SEC_TYPE='0603V',
 MATERIAL='X5R',
 PHYS_PAGE='217',
 XY='(2275,50)',
 ROT='0',
 VER='1',
 VALUE='47UF',
 PACK_TYPE='0603V',
 PART_NUMBER='602433-106',
 LOCATION='C5T6',
 GROUP='PWR_MLCC_CAP',
 SEC='1',
 CDS_LIB='dev_discrete',
 CDS_PART_NAME='CAP_A_0603V-47UF,4V,20%,X5R,60A',
 VOLTAGE='4V',
 PRIM_FILE='./archive_libs/discrete/cap_a/chips/chips.prt';

PART_NAME
 C5T7 'CAP_A_0603V-47UF,4V,20%,X5R,60A':
 GROUP='PWR_MLCC_CAP';

SECTION_NUMBER 1
 '@BASEBOARD_FAB2_LIB.BASEBOARD_FAB2(SCH_1):PAGE217_I296@DEV_DISCRETE.CAP_A(CHIPS)':
 C_PATH='@baseboard_fab2_lib.baseboard_fab2(sch_1):page217_i296@dev_discrete.cap~
_a(chips)',
 P_PATH='@baseboard_fab2_lib.baseboard_fab2(sch_1):page217_i296@dev_discrete.cap~
_a(chips)',
 PATH='I296',
 DRAWING='@BASEBOARD_FAB2_LIB.BASEBOARD_FAB2(SCH_1):PAGE217',
 BOM_SS='E15431-004',
 TOLERANCE='20%',
 SEC_TYPE='0603V',
 MATERIAL='X5R',
 PHYS_PAGE='217',
 XY='(1975,50)',
 ROT='0',
 VER='1',
 VALUE='47UF',
 PACK_TYPE='0603V',
 PART_NUMBER='602433-106',
 LOCATION='C5T7',
 GROUP='PWR_MLCC_CAP',
 SEC='1',
 CDS_LIB='dev_discrete',
 CDS_PART_NAME='CAP_A_0603V-47UF,4V,20%,X5R,60A',
 VOLTAGE='4V',
 PRIM_FILE='./archive_libs/discrete/cap_a/chips/chips.prt';

PART_NAME
 C5T8 'CAP_A_0603V-47UF,4V,20%,X5R,60A':
 GROUP='PWR_MLCC_CAP';

SECTION_NUMBER 1
 '@BASEBOARD_FAB2_LIB.BASEBOARD_FAB2(SCH_1):PAGE217_I295@DEV_DISCRETE.CAP_A(CHIPS)':
 C_PATH='@baseboard_fab2_lib.baseboard_fab2(sch_1):page217_i295@dev_discrete.cap~
_a(chips)',
 P_PATH='@baseboard_fab2_lib.baseboard_fab2(sch_1):page217_i295@dev_discrete.cap~
_a(chips)',
 PATH='I295',
 DRAWING='@BASEBOARD_FAB2_LIB.BASEBOARD_FAB2(SCH_1):PAGE217',
 BOM_SS='E15431-004',
 TOLERANCE='20%',
 SEC_TYPE='0603V',
 MATERIAL='X5R',
 PHYS_PAGE='217',
 XY='(1675,50)',
 ROT='0',
 VER='1',
 VALUE='47UF',
 PACK_TYPE='0603V',
 PART_NUMBER='602433-106',
 LOCATION='C5T8',
 GROUP='PWR_MLCC_CAP',
 SEC='1',
 CDS_LIB='dev_discrete',
 CDS_PART_NAME='CAP_A_0603V-47UF,4V,20%,X5R,60A',
 VOLTAGE='4V',
 PRIM_FILE='./archive_libs/discrete/cap_a/chips/chips.prt';

PART_NAME
 C5T9 'CAP_A_0603V-47UF,4V,20%,X5R,60A':
 GROUP='PWR_MLCC_CAP';

SECTION_NUMBER 1
 '@BASEBOARD_FAB2_LIB.BASEBOARD_FAB2(SCH_1):PAGE217_I294@DEV_DISCRETE.CAP_A(CHIPS)':
 C_PATH='@baseboard_fab2_lib.baseboard_fab2(sch_1):page217_i294@dev_discrete.cap~
_a(chips)',
 P_PATH='@baseboard_fab2_lib.baseboard_fab2(sch_1):page217_i294@dev_discrete.cap~
_a(chips)',
 PATH='I294',
 DRAWING='@BASEBOARD_FAB2_LIB.BASEBOARD_FAB2(SCH_1):PAGE217',
 BOM_SS='E15431-004',
 TOLERANCE='20%',
 SEC_TYPE='0603V',
 MATERIAL='X5R',
 PHYS_PAGE='217',
 XY='(1400,50)',
 ROT='0',
 VER='1',
 VALUE='47UF',
 PACK_TYPE='0603V',
 PART_NUMBER='602433-106',
 LOCATION='C5T9',
 GROUP='PWR_MLCC_CAP',
 SEC='1',
 CDS_LIB='dev_discrete',
 CDS_PART_NAME='CAP_A_0603V-47UF,4V,20%,X5R,60A',
 VOLTAGE='4V',
 PRIM_FILE='./archive_libs/discrete/cap_a/chips/chips.prt';

PART_NAME
 C5T10 'CAP_A_0603V-47UF,4V,20%,X5R,60A':
 GROUP='PWR_MLCC_CAP';

SECTION_NUMBER 1
 '@BASEBOARD_FAB2_LIB.BASEBOARD_FAB2(SCH_1):PAGE217_I293@DEV_DISCRETE.CAP_A(CHIPS)':
 C_PATH='@baseboard_fab2_lib.baseboard_fab2(sch_1):page217_i293@dev_discrete.cap~
_a(chips)',
 P_PATH='@baseboard_fab2_lib.baseboard_fab2(sch_1):page217_i293@dev_discrete.cap~
_a(chips)',
 PATH='I293',
 DRAWING='@BASEBOARD_FAB2_LIB.BASEBOARD_FAB2(SCH_1):PAGE217',
 BOM_SS='E15431-004',
 TOLERANCE='20%',
 SEC_TYPE='0603V',
 MATERIAL='X5R',
 PHYS_PAGE='217',
 XY='(1125,50)',
 ROT='0',
 VER='1',
 VALUE='47UF',
 PACK_TYPE='0603V',
 PART_NUMBER='602433-106',
 LOCATION='C5T10',
 GROUP='PWR_MLCC_CAP',
 SEC='1',
 CDS_LIB='dev_discrete',
 CDS_PART_NAME='CAP_A_0603V-47UF,4V,20%,X5R,60A',
 VOLTAGE='4V',
 PRIM_FILE='./archive_libs/discrete/cap_a/chips/chips.prt';

PART_NAME
 C5T11 'CAP_A_0603V-47UF,4V,20%,X5R,60A':
 GROUP='PWR_MLCC_CAP';

SECTION_NUMBER 1
 '@BASEBOARD_FAB2_LIB.BASEBOARD_FAB2(SCH_1):PAGE217_I292@DEV_DISCRETE.CAP_A(CHIPS)':
 C_PATH='@baseboard_fab2_lib.baseboard_fab2(sch_1):page217_i292@dev_discrete.cap~
_a(chips)',
 P_PATH='@baseboard_fab2_lib.baseboard_fab2(sch_1):page217_i292@dev_discrete.cap~
_a(chips)',
 PATH='I292',
 DRAWING='@BASEBOARD_FAB2_LIB.BASEBOARD_FAB2(SCH_1):PAGE217',
 BOM_SS='E15431-004',
 TOLERANCE='20%',
 SEC_TYPE='0603V',
 MATERIAL='X5R',
 PHYS_PAGE='217',
 XY='(825,50)',
 ROT='0',
 VER='1',
 VALUE='47UF',
 PACK_TYPE='0603V',
 PART_NUMBER='602433-106',
 LOCATION='C5T11',
 GROUP='PWR_MLCC_CAP',
 SEC='1',
 CDS_LIB='dev_discrete',
 CDS_PART_NAME='CAP_A_0603V-47UF,4V,20%,X5R,60A',
 VOLTAGE='4V',
 PRIM_FILE='./archive_libs/discrete/cap_a/chips/chips.prt';

PART_NAME
 C5T12 'CAP_A_0603V-47UF,4V,20%,X5R,60A':
 GROUP='PWR_MLCC_CAP';

SECTION_NUMBER 1
 '@BASEBOARD_FAB2_LIB.BASEBOARD_FAB2(SCH_1):PAGE217_I291@DEV_DISCRETE.CAP_A(CHIPS)':
 C_PATH='@baseboard_fab2_lib.baseboard_fab2(sch_1):page217_i291@dev_discrete.cap~
_a(chips)',
 P_PATH='@baseboard_fab2_lib.baseboard_fab2(sch_1):page217_i291@dev_discrete.cap~
_a(chips)',
 PATH='I291',
 DRAWING='@BASEBOARD_FAB2_LIB.BASEBOARD_FAB2(SCH_1):PAGE217',
 BOM_SS='E15431-004',
 TOLERANCE='20%',
 SEC_TYPE='0603V',
 MATERIAL='X5R',
 PHYS_PAGE='217',
 XY='(525,50)',
 ROT='0',
 VER='1',
 VALUE='47UF',
 PACK_TYPE='0603V',
 PART_NUMBER='602433-106',
 LOCATION='C5T12',
 GROUP='PWR_MLCC_CAP',
 SEC='1',
 CDS_LIB='dev_discrete',
 CDS_PART_NAME='CAP_A_0603V-47UF,4V,20%,X5R,60A',
 VOLTAGE='4V',
 PRIM_FILE='./archive_libs/discrete/cap_a/chips/chips.prt';

PART_NAME
 C5T13 'CAP_A_0603V-47UF,4V,20%,X5R,60A':
 GROUP='PWR_MLCC_CAP';

SECTION_NUMBER 1
 '@BASEBOARD_FAB2_LIB.BASEBOARD_FAB2(SCH_1):PAGE217_I210@DEV_DISCRETE.CAP_A(CHIPS)':
 C_PATH='@baseboard_fab2_lib.baseboard_fab2(sch_1):page217_i210@dev_discrete.cap~
_a(chips)',
 P_PATH='@baseboard_fab2_lib.baseboard_fab2(sch_1):page217_i210@dev_discrete.cap~
_a(chips)',
 PATH='I210',
 DRAWING='@BASEBOARD_FAB2_LIB.BASEBOARD_FAB2(SCH_1):PAGE217',
 BOM_SS='NOPOP',
 TOLERANCE='20%',
 SEC_TYPE='0603V',
 MATERIAL='X5R',
 PHYS_PAGE='217',
 XY='(4750,1725)',
 ROT='0',
 VER='1',
 VALUE='47UF',
 PACK_TYPE='0603V',
 PART_NUMBER='602433-106',
 LOCATION='C5T13',
 GROUP='PWR_MLCC_CAP',
 SEC='1',
 CDS_LIB='dev_discrete',
 CDS_PART_NAME='CAP_A_0603V-47UF,4V,20%,X5R,60A',
 VOLTAGE='4V',
 PRIM_FILE='./archive_libs/discrete/cap_a/chips/chips.prt';

PART_NAME
 C5U1 'CAP_0805-100UF,4V,20%,X5R,6024A':
 GROUP='PWR_MLCC_CAP',
 ROOM='VDDQ_ABC_PWR_VR';

SECTION_NUMBER 1
 '@BASEBOARD_FAB2_LIB.BASEBOARD_FAB2(SCH_1):PAGE217_I316@MSTR_DISCRETE.CAP(CHIPS)':
 C_PATH='@baseboard_fab2_lib.baseboard_fab2(sch_1):page217_i316@mstr_discrete.ca~
p(chips)',
 P_PATH='@baseboard_fab2_lib.baseboard_fab2(sch_1):page217_i316@mstr_discrete.ca~
p(chips)',
 PATH='I316',
 DRAWING='@BASEBOARD_FAB2_LIB.BASEBOARD_FAB2(SCH_1):PAGE217',
 NEW_PN='078.1071T.M002',
 NEW_MATERIAL='X6S',
 BOM_SS='NOPOP',
 TOLERANCE='20%',
 SEC_TYPE='0805',
 MATERIAL='X5R',
 BOM_COST='MEM_VRD_PVDDQ_CD',
 PHYS_PAGE='217',
 XY='(4725,2850)',
 ROT='0',
 VER='1',
 VALUE='100UF',
 PACK_TYPE='0805',
 PART_NUMBER='602433-112',
 LOCATION='C5U1',
 ROOM='VDDQ_ABC_PWR_VR',
 GROUP='PWR_MLCC_CAP',
 SEC='1',
 CDS_LIB='mstr_discrete',
 CDS_PART_NAME='CAP_0805-100UF,4V,20%,X5R,6024A',
 VOLTAGE='4V',
 PRIM_FILE='./archive_libs/mstr_discrete/cap/chips/chips.prt';

PART_NAME
 C5U2 'CAP_A_0603V-47UF,4V,20%,X5R,60A':
 GROUP='PWR_MLCC_CAP';

SECTION_NUMBER 1
 '@BASEBOARD_FAB2_LIB.BASEBOARD_FAB2(SCH_1):PAGE217_I283@DEV_DISCRETE.CAP_A(CHIPS)':
 C_PATH='@baseboard_fab2_lib.baseboard_fab2(sch_1):page217_i283@dev_discrete.cap~
_a(chips)',
 P_PATH='@baseboard_fab2_lib.baseboard_fab2(sch_1):page217_i283@dev_discrete.cap~
_a(chips)',
 PATH='I283',
 DRAWING='@BASEBOARD_FAB2_LIB.BASEBOARD_FAB2(SCH_1):PAGE217',
 BOM_SS='E15431-004',
 TOLERANCE='20%',
 SEC_TYPE='0603V',
 MATERIAL='X5R',
 PHYS_PAGE='217',
 XY='(-1825,50)',
 ROT='0',
 VER='1',
 VALUE='47UF',
 PACK_TYPE='0603V',
 PART_NUMBER='602433-106',
 LOCATION='C5U2',
 GROUP='PWR_MLCC_CAP',
 SEC='1',
 CDS_LIB='dev_discrete',
 CDS_PART_NAME='CAP_A_0603V-47UF,4V,20%,X5R,60A',
 VOLTAGE='4V',
 PRIM_FILE='./archive_libs/discrete/cap_a/chips/chips.prt';

PART_NAME
 C5U3 'CAP_A_0603V-47UF,4V,20%,X5R,60A':
 GROUP='PWR_MLCC_CAP';

SECTION_NUMBER 1
 '@BASEBOARD_FAB2_LIB.BASEBOARD_FAB2(SCH_1):PAGE217_I284@DEV_DISCRETE.CAP_A(CHIPS)':
 C_PATH='@baseboard_fab2_lib.baseboard_fab2(sch_1):page217_i284@dev_discrete.cap~
_a(chips)',
 P_PATH='@baseboard_fab2_lib.baseboard_fab2(sch_1):page217_i284@dev_discrete.cap~
_a(chips)',
 PATH='I284',
 DRAWING='@BASEBOARD_FAB2_LIB.BASEBOARD_FAB2(SCH_1):PAGE217',
 BOM_SS='E15431-004',
 TOLERANCE='20%',
 SEC_TYPE='0603V',
 MATERIAL='X5R',
 PHYS_PAGE='217',
 XY='(-1525,50)',
 ROT='0',
 VER='1',
 VALUE='47UF',
 PACK_TYPE='0603V',
 PART_NUMBER='602433-106',
 LOCATION='C5U3',
 GROUP='PWR_MLCC_CAP',
 SEC='1',
 CDS_LIB='dev_discrete',
 CDS_PART_NAME='CAP_A_0603V-47UF,4V,20%,X5R,60A',
 VOLTAGE='4V',
 PRIM_FILE='./archive_libs/discrete/cap_a/chips/chips.prt';

PART_NAME
 C5U4 'CAP_A_0603V-47UF,4V,20%,X5R,60A':
 GROUP='PWR_MLCC_CAP';

SECTION_NUMBER 1
 '@BASEBOARD_FAB2_LIB.BASEBOARD_FAB2(SCH_1):PAGE217_I285@DEV_DISCRETE.CAP_A(CHIPS)':
 C_PATH='@baseboard_fab2_lib.baseboard_fab2(sch_1):page217_i285@dev_discrete.cap~
_a(chips)',
 P_PATH='@baseboard_fab2_lib.baseboard_fab2(sch_1):page217_i285@dev_discrete.cap~
_a(chips)',
 PATH='I285',
 DRAWING='@BASEBOARD_FAB2_LIB.BASEBOARD_FAB2(SCH_1):PAGE217',
 BOM_SS='E15431-004',
 TOLERANCE='20%',
 SEC_TYPE='0603V',
 MATERIAL='X5R',
 PHYS_PAGE='217',
 XY='(-1225,50)',
 ROT='0',
 VER='1',
 VALUE='47UF',
 PACK_TYPE='0603V',
 PART_NUMBER='602433-106',
 LOCATION='C5U4',
 GROUP='PWR_MLCC_CAP',
 SEC='1',
 CDS_LIB='dev_discrete',
 CDS_PART_NAME='CAP_A_0603V-47UF,4V,20%,X5R,60A',
 VOLTAGE='4V',
 PRIM_FILE='./archive_libs/discrete/cap_a/chips/chips.prt';

PART_NAME
 C5U5 'CAP_A_0603V-47UF,4V,20%,X5R,60A':
 GROUP='PWR_MLCC_CAP';

SECTION_NUMBER 1
 '@BASEBOARD_FAB2_LIB.BASEBOARD_FAB2(SCH_1):PAGE217_I286@DEV_DISCRETE.CAP_A(CHIPS)':
 C_PATH='@baseboard_fab2_lib.baseboard_fab2(sch_1):page217_i286@dev_discrete.cap~
_a(chips)',
 P_PATH='@baseboard_fab2_lib.baseboard_fab2(sch_1):page217_i286@dev_discrete.cap~
_a(chips)',
 PATH='I286',
 DRAWING='@BASEBOARD_FAB2_LIB.BASEBOARD_FAB2(SCH_1):PAGE217',
 BOM_SS='E15431-004',
 TOLERANCE='20%',
 SEC_TYPE='0603V',
 MATERIAL='X5R',
 PHYS_PAGE='217',
 XY='(-950,50)',
 ROT='0',
 VER='1',
 VALUE='47UF',
 PACK_TYPE='0603V',
 PART_NUMBER='602433-106',
 LOCATION='C5U5',
 GROUP='PWR_MLCC_CAP',
 SEC='1',
 CDS_LIB='dev_discrete',
 CDS_PART_NAME='CAP_A_0603V-47UF,4V,20%,X5R,60A',
 VOLTAGE='4V',
 PRIM_FILE='./archive_libs/discrete/cap_a/chips/chips.prt';

PART_NAME
 C5U6 'CAP_A_0603V-47UF,4V,20%,X5R,60A':
 GROUP='PWR_MLCC_CAP';

SECTION_NUMBER 1
 '@BASEBOARD_FAB2_LIB.BASEBOARD_FAB2(SCH_1):PAGE217_I287@DEV_DISCRETE.CAP_A(CHIPS)':
 C_PATH='@baseboard_fab2_lib.baseboard_fab2(sch_1):page217_i287@dev_discrete.cap~
_a(chips)',
 P_PATH='@baseboard_fab2_lib.baseboard_fab2(sch_1):page217_i287@dev_discrete.cap~
_a(chips)',
 PATH='I287',
 DRAWING='@BASEBOARD_FAB2_LIB.BASEBOARD_FAB2(SCH_1):PAGE217',
 BOM_SS='E15431-004',
 TOLERANCE='20%',
 SEC_TYPE='0603V',
 MATERIAL='X5R',
 PHYS_PAGE='217',
 XY='(-675,50)',
 ROT='0',
 VER='1',
 VALUE='47UF',
 PACK_TYPE='0603V',
 PART_NUMBER='602433-106',
 LOCATION='C5U6',
 GROUP='PWR_MLCC_CAP',
 SEC='1',
 CDS_LIB='dev_discrete',
 CDS_PART_NAME='CAP_A_0603V-47UF,4V,20%,X5R,60A',
 VOLTAGE='4V',
 PRIM_FILE='./archive_libs/discrete/cap_a/chips/chips.prt';

PART_NAME
 C5U7 'CAP_A_0603V-47UF,4V,20%,X5R,60A':
 GROUP='PWR_MLCC_CAP';

SECTION_NUMBER 1
 '@BASEBOARD_FAB2_LIB.BASEBOARD_FAB2(SCH_1):PAGE217_I288@DEV_DISCRETE.CAP_A(CHIPS)':
 C_PATH='@baseboard_fab2_lib.baseboard_fab2(sch_1):page217_i288@dev_discrete.cap~
_a(chips)',
 P_PATH='@baseboard_fab2_lib.baseboard_fab2(sch_1):page217_i288@dev_discrete.cap~
_a(chips)',
 PATH='I288',
 DRAWING='@BASEBOARD_FAB2_LIB.BASEBOARD_FAB2(SCH_1):PAGE217',
 BOM_SS='E15431-004',
 TOLERANCE='20%',
 SEC_TYPE='0603V',
 MATERIAL='X5R',
 PHYS_PAGE='217',
 XY='(-375,50)',
 ROT='0',
 VER='1',
 VALUE='47UF',
 PACK_TYPE='0603V',
 PART_NUMBER='602433-106',
 LOCATION='C5U7',
 GROUP='PWR_MLCC_CAP',
 SEC='1',
 CDS_LIB='dev_discrete',
 CDS_PART_NAME='CAP_A_0603V-47UF,4V,20%,X5R,60A',
 VOLTAGE='4V',
 PRIM_FILE='./archive_libs/discrete/cap_a/chips/chips.prt';

PART_NAME
 C5U8 'CAP_A_0603V-47UF,4V,20%,X5R,60A':
 GROUP='PWR_MLCC_CAP';

SECTION_NUMBER 1
 '@BASEBOARD_FAB2_LIB.BASEBOARD_FAB2(SCH_1):PAGE217_I289@DEV_DISCRETE.CAP_A(CHIPS)':
 C_PATH='@baseboard_fab2_lib.baseboard_fab2(sch_1):page217_i289@dev_discrete.cap~
_a(chips)',
 P_PATH='@baseboard_fab2_lib.baseboard_fab2(sch_1):page217_i289@dev_discrete.cap~
_a(chips)',
 PATH='I289',
 DRAWING='@BASEBOARD_FAB2_LIB.BASEBOARD_FAB2(SCH_1):PAGE217',
 BOM_SS='E15431-004',
 TOLERANCE='20%',
 SEC_TYPE='0603V',
 MATERIAL='X5R',
 PHYS_PAGE='217',
 XY='(-75,50)',
 ROT='0',
 VER='1',
 VALUE='47UF',
 PACK_TYPE='0603V',
 PART_NUMBER='602433-106',
 LOCATION='C5U8',
 GROUP='PWR_MLCC_CAP',
 SEC='1',
 CDS_LIB='dev_discrete',
 CDS_PART_NAME='CAP_A_0603V-47UF,4V,20%,X5R,60A',
 VOLTAGE='4V',
 PRIM_FILE='./archive_libs/discrete/cap_a/chips/chips.prt';

PART_NAME
 C5U9 'CAP_A_0603V-47UF,4V,20%,X5R,60A':
 GROUP='PWR_MLCC_CAP';

SECTION_NUMBER 1
 '@BASEBOARD_FAB2_LIB.BASEBOARD_FAB2(SCH_1):PAGE217_I290@DEV_DISCRETE.CAP_A(CHIPS)':
 C_PATH='@baseboard_fab2_lib.baseboard_fab2(sch_1):page217_i290@dev_discrete.cap~
_a(chips)',
 P_PATH='@baseboard_fab2_lib.baseboard_fab2(sch_1):page217_i290@dev_discrete.cap~
_a(chips)',
 PATH='I290',
 DRAWING='@BASEBOARD_FAB2_LIB.BASEBOARD_FAB2(SCH_1):PAGE217',
 BOM_SS='E15431-004',
 TOLERANCE='20%',
 SEC_TYPE='0603V',
 MATERIAL='X5R',
 PHYS_PAGE='217',
 XY='(200,50)',
 ROT='0',
 VER='1',
 VALUE='47UF',
 PACK_TYPE='0603V',
 PART_NUMBER='602433-106',
 LOCATION='C5U9',
 GROUP='PWR_MLCC_CAP',
 SEC='1',
 CDS_LIB='dev_discrete',
 CDS_PART_NAME='CAP_A_0603V-47UF,4V,20%,X5R,60A',
 VOLTAGE='4V',
 PRIM_FILE='./archive_libs/discrete/cap_a/chips/chips.prt';

PART_NAME
 C5U10 'CAP_0805-100UF,4V,20%,X5R,6024A':
 GROUP='PWR_MLCC_CAP',
 ROOM='VDDQ_ABC_PWR_VR';

SECTION_NUMBER 1
 '@BASEBOARD_FAB2_LIB.BASEBOARD_FAB2(SCH_1):PAGE217_I317@MSTR_DISCRETE.CAP(CHIPS)':
 C_PATH='@baseboard_fab2_lib.baseboard_fab2(sch_1):page217_i317@mstr_discrete.ca~
p(chips)',
 P_PATH='@baseboard_fab2_lib.baseboard_fab2(sch_1):page217_i317@mstr_discrete.ca~
p(chips)',
 PATH='I317',
 DRAWING='@BASEBOARD_FAB2_LIB.BASEBOARD_FAB2(SCH_1):PAGE217',
 NEW_PN='078.1071T.M002',
 NEW_MATERIAL='X6S',
 BOM_SS='NOPOP',
 TOLERANCE='20%',
 SEC_TYPE='0805',
 MATERIAL='X5R',
 BOM_COST='MEM_VRD_PVDDQ_CD',
 PHYS_PAGE='217',
 XY='(5075,2850)',
 ROT='0',
 VER='1',
 VALUE='100UF',
 PACK_TYPE='0805',
 PART_NUMBER='602433-112',
 LOCATION='C5U10',
 ROOM='VDDQ_ABC_PWR_VR',
 GROUP='PWR_MLCC_CAP',
 SEC='1',
 CDS_LIB='mstr_discrete',
 CDS_PART_NAME='CAP_0805-100UF,4V,20%,X5R,6024A',
 VOLTAGE='4V',
 PRIM_FILE='./archive_libs/mstr_discrete/cap/chips/chips.prt';

PART_NAME
 C5U11 'CAP_A_0603V-47UF,4V,20%,X5R,60A':
 GROUP='PWR_MLCC_CAP';

SECTION_NUMBER 1
 '@BASEBOARD_FAB2_LIB.BASEBOARD_FAB2(SCH_1):PAGE217_I209@DEV_DISCRETE.CAP_A(CHIPS)':
 C_PATH='@baseboard_fab2_lib.baseboard_fab2(sch_1):page217_i209@dev_discrete.cap~
_a(chips)',
 P_PATH='@baseboard_fab2_lib.baseboard_fab2(sch_1):page217_i209@dev_discrete.cap~
_a(chips)',
 PATH='I209',
 DRAWING='@BASEBOARD_FAB2_LIB.BASEBOARD_FAB2(SCH_1):PAGE217',
 BOM_SS='NOPOP',
 TOLERANCE='20%',
 SEC_TYPE='0603V',
 MATERIAL='X5R',
 PHYS_PAGE='217',
 XY='(4350,1725)',
 ROT='0',
 VER='1',
 VALUE='47UF',
 PACK_TYPE='0603V',
 PART_NUMBER='602433-106',
 LOCATION='C5U11',
 GROUP='PWR_MLCC_CAP',
 SEC='1',
 CDS_LIB='dev_discrete',
 CDS_PART_NAME='CAP_A_0603V-47UF,4V,20%,X5R,60A',
 VOLTAGE='4V',
 PRIM_FILE='./archive_libs/discrete/cap_a/chips/chips.prt';

PART_NAME
 C5U12 'CAP_0805-100UF,4V,20%,X5R,6024A':
 GROUP='PWR_MLCC_CAP',
 ROOM='VDDQ_ABC_PWR_VR';

SECTION_NUMBER 1
 '@BASEBOARD_FAB2_LIB.BASEBOARD_FAB2(SCH_1):PAGE221_I45@MSTR_DISCRETE.CAP(CHIPS)':
 C_PATH='@baseboard_fab2_lib.baseboard_fab2(sch_1):page221_i45@mstr_discrete.cap~
(chips)',
 P_PATH='@baseboard_fab2_lib.baseboard_fab2(sch_1):page221_i45@mstr_discrete.cap~
(chips)',
 PATH='I45',
 DRAWING='@BASEBOARD_FAB2_LIB.BASEBOARD_FAB2(SCH_1):PAGE221',
 NEW_PN='078.1071T.M002',
 NEW_MATERIAL='X6S',
 TOLERANCE='20%',
 SEC_TYPE='0805',
 MATERIAL='X5R',
 BOM_COST='MEM_VRD_PVDDQ_CD',
 PHYS_PAGE='221',
 XY='(3325,3300)',
 ROT='0',
 VER='1',
 VALUE='100UF',
 PACK_TYPE='0805',
 PART_NUMBER='602433-112',
 LOCATION='C5U12',
 ROOM='VDDQ_ABC_PWR_VR',
 GROUP='PWR_MLCC_CAP',
 SEC='1',
 CDS_LIB='mstr_discrete',
 CDS_PART_NAME='CAP_0805-100UF,4V,20%,X5R,6024A',
 VOLTAGE='4V',
 PRIM_FILE='./archive_libs/mstr_discrete/cap/chips/chips.prt';

PART_NAME
 C5U13 'CAP_0805-100UF,4V,20%,X5R,6024A':
 GROUP='PWR_MLCC_CAP',
 ROOM='VDDQ_ABC_PWR_VR';

SECTION_NUMBER 1
 '@BASEBOARD_FAB2_LIB.BASEBOARD_FAB2(SCH_1):PAGE217_I321@MSTR_DISCRETE.CAP(CHIPS)':
 C_PATH='@baseboard_fab2_lib.baseboard_fab2(sch_1):page217_i321@mstr_discrete.ca~
p(chips)',
 P_PATH='@baseboard_fab2_lib.baseboard_fab2(sch_1):page217_i321@mstr_discrete.ca~
p(chips)',
 PATH='I321',
 DRAWING='@BASEBOARD_FAB2_LIB.BASEBOARD_FAB2(SCH_1):PAGE217',
 NEW_PN='078.1071T.M002',
 NEW_MATERIAL='X6S',
 BOM_SS='NOPOP',
 TOLERANCE='20%',
 SEC_TYPE='0805',
 MATERIAL='X5R',
 BOM_COST='MEM_VRD_PVDDQ_CD',
 PHYS_PAGE='217',
 XY='(5475,2850)',
 ROT='0',
 VER='1',
 VALUE='100UF',
 PACK_TYPE='0805',
 PART_NUMBER='602433-112',
 LOCATION='C5U13',
 ROOM='VDDQ_ABC_PWR_VR',
 GROUP='PWR_MLCC_CAP',
 SEC='1',
 CDS_LIB='mstr_discrete',
 CDS_PART_NAME='CAP_0805-100UF,4V,20%,X5R,6024A',
 VOLTAGE='4V',
 PRIM_FILE='./archive_libs/mstr_discrete/cap/chips/chips.prt';

PART_NAME
 C5U14 'CAP_0805-100UF,4V,20%,X5R,6024A':
 GROUP='PWR_MLCC_CAP',
 ROOM='VDDQ_ABC_PWR_VR';

SECTION_NUMBER 1
 '@BASEBOARD_FAB2_LIB.BASEBOARD_FAB2(SCH_1):PAGE217_I322@MSTR_DISCRETE.CAP(CHIPS)':
 C_PATH='@baseboard_fab2_lib.baseboard_fab2(sch_1):page217_i322@mstr_discrete.ca~
p(chips)',
 P_PATH='@baseboard_fab2_lib.baseboard_fab2(sch_1):page217_i322@mstr_discrete.ca~
p(chips)',
 PATH='I322',
 DRAWING='@BASEBOARD_FAB2_LIB.BASEBOARD_FAB2(SCH_1):PAGE217',
 NEW_PN='078.1071T.M002',
 NEW_MATERIAL='X6S',
 BOM_SS='NOPOP',
 TOLERANCE='20%',
 SEC_TYPE='0805',
 MATERIAL='X5R',
 BOM_COST='MEM_VRD_PVDDQ_CD',
 PHYS_PAGE='217',
 XY='(4325,2850)',
 ROT='0',
 VER='1',
 VALUE='100UF',
 PACK_TYPE='0805',
 PART_NUMBER='602433-112',
 LOCATION='C5U14',
 ROOM='VDDQ_ABC_PWR_VR',
 GROUP='PWR_MLCC_CAP',
 SEC='1',
 CDS_LIB='mstr_discrete',
 CDS_PART_NAME='CAP_0805-100UF,4V,20%,X5R,6024A',
 VOLTAGE='4V',
 PRIM_FILE='./archive_libs/mstr_discrete/cap/chips/chips.prt';

PART_NAME
 C5U15 'CAP_0805-100UF,4V,20%,X5R,6024A':
 GROUP='PWR_MLCC_CAP',
 ROOM='VDDQ_ABC_PWR_VR';

SECTION_NUMBER 1
 '@BASEBOARD_FAB2_LIB.BASEBOARD_FAB2(SCH_1):PAGE217_I320@MSTR_DISCRETE.CAP(CHIPS)':
 C_PATH='@baseboard_fab2_lib.baseboard_fab2(sch_1):page217_i320@mstr_discrete.ca~
p(chips)',
 P_PATH='@baseboard_fab2_lib.baseboard_fab2(sch_1):page217_i320@mstr_discrete.ca~
p(chips)',
 PATH='I320',
 DRAWING='@BASEBOARD_FAB2_LIB.BASEBOARD_FAB2(SCH_1):PAGE217',
 NEW_PN='078.1071T.M002',
 NEW_MATERIAL='X6S',
 BOM_SS='NOPOP',
 TOLERANCE='20%',
 SEC_TYPE='0805',
 MATERIAL='X5R',
 BOM_COST='MEM_VRD_PVDDQ_CD',
 PHYS_PAGE='217',
 XY='(3975,2850)',
 ROT='0',
 VER='1',
 VALUE='100UF',
 PACK_TYPE='0805',
 PART_NUMBER='602433-112',
 LOCATION='C5U15',
 ROOM='VDDQ_ABC_PWR_VR',
 GROUP='PWR_MLCC_CAP',
 SEC='1',
 CDS_LIB='mstr_discrete',
 CDS_PART_NAME='CAP_0805-100UF,4V,20%,X5R,6024A',
 VOLTAGE='4V',
 PRIM_FILE='./archive_libs/mstr_discrete/cap/chips/chips.prt';

PART_NAME
 C5U16 'CAP_0805-100UF,4V,20%,X5R,6024A':
 GROUP='PWR_MLCC_CAP',
 ROOM='VDDQ_ABC_PWR_VR';

SECTION_NUMBER 1
 '@BASEBOARD_FAB2_LIB.BASEBOARD_FAB2(SCH_1):PAGE221_I46@MSTR_DISCRETE.CAP(CHIPS)':
 C_PATH='@baseboard_fab2_lib.baseboard_fab2(sch_1):page221_i46@mstr_discrete.cap~
(chips)',
 P_PATH='@baseboard_fab2_lib.baseboard_fab2(sch_1):page221_i46@mstr_discrete.cap~
(chips)',
 PATH='I46',
 DRAWING='@BASEBOARD_FAB2_LIB.BASEBOARD_FAB2(SCH_1):PAGE221',
 NEW_PN='078.1071T.M002',
 NEW_MATERIAL='X6S',
 TOLERANCE='20%',
 SEC_TYPE='0805',
 MATERIAL='X5R',
 BOM_COST='MEM_VRD_PVDDQ_CD',
 PHYS_PAGE='221',
 XY='(3675,3300)',
 ROT='0',
 VER='1',
 VALUE='100UF',
 PACK_TYPE='0805',
 PART_NUMBER='602433-112',
 LOCATION='C5U16',
 ROOM='VDDQ_ABC_PWR_VR',
 GROUP='PWR_MLCC_CAP',
 SEC='1',
 CDS_LIB='mstr_discrete',
 CDS_PART_NAME='CAP_0805-100UF,4V,20%,X5R,6024A',
 VOLTAGE='4V',
 PRIM_FILE='./archive_libs/mstr_discrete/cap/chips/chips.prt';

PART_NAME
 C5W1 'CAP_A_0603V-22.0UF,4V,20%,X6S,A':
 GROUP='PWR_MCP_CAP',
 ROOM='PVCCIN_CPU0_DECAP_VR';

SECTION_NUMBER 1
 '@BASEBOARD_FAB2_LIB.BASEBOARD_FAB2(SCH_1):PAGE42_I217@DEV_DISCRETE.CAP_A(CHIPS)':
 C_PATH='@baseboard_fab2_lib.baseboard_fab2(sch_1):page42_i217@dev_discrete.cap_~
a(chips)',
 P_PATH='@baseboard_fab2_lib.baseboard_fab2(sch_1):page42_i217@dev_discrete.cap_~
a(chips)',
 PATH='I217',
 DRAWING='@BASEBOARD_FAB2_LIB.BASEBOARD_FAB2(SCH_1):PAGE42',
 TOLERANCE='20%',
 SEC_TYPE='0603V',
 MATERIAL='X6S',
 BOM_COST='PROC_SOCKET',
 PHYS_PAGE='42',
 XY='(-800,3150)',
 ROT='0',
 VER='1',
 VALUE='22.0UF',
 PACK_TYPE='0603V',
 PART_NUMBER='E15431-004',
 LOCATION='C5W1',
 ROOM='PVCCIN_CPU0_DECAP_VR',
 GROUP='PWR_MCP_CAP',
 SEC='1',
 CDS_LIB='dev_discrete',
 CDS_PART_NAME='CAP_A_0603V-22.0UF,4V,20%,X6S,A',
 VOLTAGE='4V',
 PRIM_FILE='./archive_libs/discrete/cap_a/chips/chips.prt';

PART_NAME
 C5W2 'CAP_A_0603V-22.0UF,4V,20%,X6S,A':
 GROUP='PWR_MCP_CAP',
 ROOM='PVCCIN_CPU0_DECAP_VR';

SECTION_NUMBER 1
 '@BASEBOARD_FAB2_LIB.BASEBOARD_FAB2(SCH_1):PAGE42_I218@DEV_DISCRETE.CAP_A(CHIPS)':
 C_PATH='@baseboard_fab2_lib.baseboard_fab2(sch_1):page42_i218@dev_discrete.cap_~
a(chips)',
 P_PATH='@baseboard_fab2_lib.baseboard_fab2(sch_1):page42_i218@dev_discrete.cap_~
a(chips)',
 PATH='I218',
 DRAWING='@BASEBOARD_FAB2_LIB.BASEBOARD_FAB2(SCH_1):PAGE42',
 TOLERANCE='20%',
 SEC_TYPE='0603V',
 MATERIAL='X6S',
 BOM_COST='PROC_SOCKET',
 PHYS_PAGE='42',
 XY='(-550,3150)',
 ROT='0',
 VER='1',
 VALUE='22.0UF',
 PACK_TYPE='0603V',
 PART_NUMBER='E15431-004',
 LOCATION='C5W2',
 ROOM='PVCCIN_CPU0_DECAP_VR',
 GROUP='PWR_MCP_CAP',
 SEC='1',
 CDS_LIB='dev_discrete',
 CDS_PART_NAME='CAP_A_0603V-22.0UF,4V,20%,X6S,A',
 VOLTAGE='4V',
 PRIM_FILE='./archive_libs/discrete/cap_a/chips/chips.prt';

PART_NAME
 C6A1 'CAP_0805LF-22UF,4V,20%,X6S,C95A':
 GROUP='PWR_MLCC_CAP',
 ROOM='VDDQ_DEF_PWR_VR';

SECTION_NUMBER 1
 '@BASEBOARD_FAB2_LIB.BASEBOARD_FAB2(SCH_1):PAGE219_I87@MSTR_DISCRETE.CAP(CHIPS)':
 C_PATH='@baseboard_fab2_lib.baseboard_fab2(sch_1):page219_i87@mstr_discrete.cap~
(chips)',
 P_PATH='@baseboard_fab2_lib.baseboard_fab2(sch_1):page219_i87@mstr_discrete.cap~
(chips)',
 PATH='I87',
 DRAWING='@BASEBOARD_FAB2_LIB.BASEBOARD_FAB2(SCH_1):PAGE219',
 TOLERANCE='20%',
 SEC_TYPE='0805LF',
 MATERIAL='X6S',
 BOM_COST='PROC_VRD_VCCIN_CPU0',
 PHYS_PAGE='219',
 XY='(4450,1675)',
 ROT='0',
 VER='1',
 VALUE='22UF',
 PACK_TYPE='0805LF',
 PART_NUMBER='C95333-002',
 LOCATION='C6A1',
 ROOM='VDDQ_DEF_PWR_VR',
 GROUP='PWR_MLCC_CAP',
 SEC='1',
 CDS_LIB='mstr_discrete',
 CDS_PART_NAME='CAP_0805LF-22UF,4V,20%,X6S,C95A',
 VOLTAGE='4V',
 PRIM_FILE='./archive_libs/mstr_discrete/cap/chips/chips.prt';

PART_NAME
 C6A2 'CAP_0603LF-10UF,4V,20%,X6S,E15A':
 GROUP='PWR_MLCC_CAP',
 ROOM='PVPP_KLM_VR';

SECTION_NUMBER 1
 '@BASEBOARD_FAB2_LIB.BASEBOARD_FAB2(SCH_1):PAGE232_I105@MSTR_DISCRETE.CAP(CHIPS)':
 C_PATH='@baseboard_fab2_lib.baseboard_fab2(sch_1):page232_i105@mstr_discrete.ca~
p(chips)',
 P_PATH='@baseboard_fab2_lib.baseboard_fab2(sch_1):page232_i105@mstr_discrete.ca~
p(chips)',
 PATH='I105',
 DRAWING='@BASEBOARD_FAB2_LIB.BASEBOARD_FAB2(SCH_1):PAGE232',
 TOLERANCE='20%',
 MATERIAL='X6S',
 BOM_COST='MEM_VRD_PVPP_AB',
 PHYS_PAGE='232',
 XY='(-8050,875)',
 ROT='0',
 VER='1',
 VALUE='10UF',
 PACK_TYPE='0603LF',
 PART_NUMBER='E15431-001',
 LOCATION='C6A2',
 ROOM='PVPP_KLM_VR',
 GROUP='PWR_MLCC_CAP',
 CDS_LIB='mstr_discrete',
 CDS_PART_NAME='CAP_0603LF-10UF,4V,20%,X6S,E15A',
 VOLTAGE='4V',
 PRIM_FILE='./archive_libs/mstr_discrete/cap/chips/chips.prt';

PART_NAME
 C6A3 'CAP_0603LF-10UF,4V,20%,X6S,E15A':
 GROUP='PWR_MLCC_CAP',
 ROOM='PVPP_KLM_VR';

SECTION_NUMBER 1
 '@BASEBOARD_FAB2_LIB.BASEBOARD_FAB2(SCH_1):PAGE232_I104@MSTR_DISCRETE.CAP(CHIPS)':
 C_PATH='@baseboard_fab2_lib.baseboard_fab2(sch_1):page232_i104@mstr_discrete.ca~
p(chips)',
 P_PATH='@baseboard_fab2_lib.baseboard_fab2(sch_1):page232_i104@mstr_discrete.ca~
p(chips)',
 PATH='I104',
 DRAWING='@BASEBOARD_FAB2_LIB.BASEBOARD_FAB2(SCH_1):PAGE232',
 TOLERANCE='20%',
 MATERIAL='X6S',
 BOM_COST='MEM_VRD_PVPP_AB',
 PHYS_PAGE='232',
 XY='(-8325,875)',
 ROT='0',
 VER='1',
 VALUE='10UF',
 PACK_TYPE='0603LF',
 PART_NUMBER='E15431-001',
 LOCATION='C6A3',
 ROOM='PVPP_KLM_VR',
 GROUP='PWR_MLCC_CAP',
 CDS_LIB='mstr_discrete',
 CDS_PART_NAME='CAP_0603LF-10UF,4V,20%,X6S,E15A',
 VOLTAGE='4V',
 PRIM_FILE='./archive_libs/mstr_discrete/cap/chips/chips.prt';

PART_NAME
 C6A4 'CAP_0805LF-22UF,4V,20%,X6S,C95A':
 GROUP='PWR_MLCC_CAP',
 ROOM='VDDQ_DEF_PWR_VR';

SECTION_NUMBER 1
 '@BASEBOARD_FAB2_LIB.BASEBOARD_FAB2(SCH_1):PAGE219_I68@MSTR_DISCRETE.CAP(CHIPS)':
 C_PATH='@baseboard_fab2_lib.baseboard_fab2(sch_1):page219_i68@mstr_discrete.cap~
(chips)',
 P_PATH='@baseboard_fab2_lib.baseboard_fab2(sch_1):page219_i68@mstr_discrete.cap~
(chips)',
 PATH='I68',
 DRAWING='@BASEBOARD_FAB2_LIB.BASEBOARD_FAB2(SCH_1):PAGE219',
 BOM_SS='NOPOP',
 TOLERANCE='20%',
 SEC_TYPE='0805LF',
 MATERIAL='X6S',
 BOM_COST='PROC_VRD_VCCIN_CPU0',
 PHYS_PAGE='219',
 XY='(4500,-575)',
 ROT='0',
 VER='1',
 VALUE='22UF',
 PACK_TYPE='0805LF',
 PART_NUMBER='C95333-002',
 LOCATION='C6A4',
 ROOM='VDDQ_DEF_PWR_VR',
 GROUP='PWR_MLCC_CAP',
 SEC='1',
 CDS_LIB='mstr_discrete',
 CDS_PART_NAME='CAP_0805LF-22UF,4V,20%,X6S,C95A',
 VOLTAGE='4V',
 PRIM_FILE='./archive_libs/mstr_discrete/cap/chips/chips.prt';

PART_NAME
 C6A5 'CAPP_3018-470UF,2.5V,20%,ALUM,A':
 GROUP='PWR_BULK_CAP',
 ROOM='VDDQ_DEF_PWR_VR';

SECTION_NUMBER 1
 '@BASEBOARD_FAB2_LIB.BASEBOARD_FAB2(SCH_1):PAGE220_I77@MSTR_DISCRETE.CAPP(CHIPS)':
 C_PATH='@baseboard_fab2_lib.baseboard_fab2(sch_1):page220_i77@mstr_discrete.cap~
p(chips)',
 P_PATH='@baseboard_fab2_lib.baseboard_fab2(sch_1):page220_i77@mstr_discrete.cap~
p(chips)',
 PATH='I77',
 DRAWING='@BASEBOARD_FAB2_LIB.BASEBOARD_FAB2(SCH_1):PAGE220',
 TOLERANCE='20%',
 SEC_TYPE='3018',
 MATERIAL='ALUM',
 PHYS_PAGE='220',
 XY='(3500,-100)',
 ROT='0',
 VER='1',
 VALUE='470UF',
 PACK_TYPE='3018',
 PART_NUMBER='699013-049',
 LOCATION='C6A5',
 ROOM='VDDQ_DEF_PWR_VR',
 GROUP='PWR_BULK_CAP',
 SEC='1',
 CDS_LIB='mstr_discrete',
 CDS_PART_NAME='CAPP_3018-470UF,2.5V,20%,ALUM,A',
 VOLTAGE='2.5V',
 PRIM_FILE='./archive_libs/mstr_discrete/capp/chips/chips.prt';

PART_NAME
 C6A6 'CAP_0603LF-10UF,4V,20%,X6S,E15A':
 GROUP='PWR_MLCC_CAP',
 ROOM='PVPP_KLM_VR';

SECTION_NUMBER 1
 '@BASEBOARD_FAB2_LIB.BASEBOARD_FAB2(SCH_1):PAGE232_I110@MSTR_DISCRETE.CAP(CHIPS)':
 C_PATH='@baseboard_fab2_lib.baseboard_fab2(sch_1):page232_i110@mstr_discrete.ca~
p(chips)',
 P_PATH='@baseboard_fab2_lib.baseboard_fab2(sch_1):page232_i110@mstr_discrete.ca~
p(chips)',
 PATH='I110',
 DRAWING='@BASEBOARD_FAB2_LIB.BASEBOARD_FAB2(SCH_1):PAGE232',
 TOLERANCE='20%',
 MATERIAL='X6S',
 BOM_COST='MEM_VRD_PVPP_AB',
 PHYS_PAGE='232',
 XY='(-6925,875)',
 ROT='0',
 VER='1',
 VALUE='10UF',
 PACK_TYPE='0603LF',
 PART_NUMBER='E15431-001',
 LOCATION='C6A6',
 ROOM='PVPP_KLM_VR',
 GROUP='PWR_MLCC_CAP',
 CDS_LIB='mstr_discrete',
 CDS_PART_NAME='CAP_0603LF-10UF,4V,20%,X6S,E15A',
 VOLTAGE='4V',
 PRIM_FILE='./archive_libs/mstr_discrete/cap/chips/chips.prt';

PART_NAME
 C6A7 'CAP_0603LF-10UF,4V,20%,X6S,E15A':
 GROUP='PWR_MLCC_CAP',
 ROOM='PVPP_KLM_VR';

SECTION_NUMBER 1
 '@BASEBOARD_FAB2_LIB.BASEBOARD_FAB2(SCH_1):PAGE232_I109@MSTR_DISCRETE.CAP(CHIPS)':
 C_PATH='@baseboard_fab2_lib.baseboard_fab2(sch_1):page232_i109@mstr_discrete.ca~
p(chips)',
 P_PATH='@baseboard_fab2_lib.baseboard_fab2(sch_1):page232_i109@mstr_discrete.ca~
p(chips)',
 PATH='I109',
 DRAWING='@BASEBOARD_FAB2_LIB.BASEBOARD_FAB2(SCH_1):PAGE232',
 TOLERANCE='20%',
 MATERIAL='X6S',
 BOM_COST='MEM_VRD_PVPP_AB',
 PHYS_PAGE='232',
 XY='(-7200,875)',
 ROT='0',
 VER='1',
 VALUE='10UF',
 PACK_TYPE='0603LF',
 PART_NUMBER='E15431-001',
 LOCATION='C6A7',
 ROOM='PVPP_KLM_VR',
 GROUP='PWR_MLCC_CAP',
 CDS_LIB='mstr_discrete',
 CDS_PART_NAME='CAP_0603LF-10UF,4V,20%,X6S,E15A',
 VOLTAGE='4V',
 PRIM_FILE='./archive_libs/mstr_discrete/cap/chips/chips.prt';

PART_NAME
 C6B1 'CAP_0603LF-10UF,4V,20%,X6S,E15A':
 GROUP='PWR_MLCC_CAP',
 ROOM='PVPP_KLM_VR';

SECTION_NUMBER 1
 '@BASEBOARD_FAB2_LIB.BASEBOARD_FAB2(SCH_1):PAGE232_I128@MSTR_DISCRETE.CAP(CHIPS)':
 C_PATH='@baseboard_fab2_lib.baseboard_fab2(sch_1):page232_i128@mstr_discrete.ca~
p(chips)',
 P_PATH='@baseboard_fab2_lib.baseboard_fab2(sch_1):page232_i128@mstr_discrete.ca~
p(chips)',
 PATH='I128',
 DRAWING='@BASEBOARD_FAB2_LIB.BASEBOARD_FAB2(SCH_1):PAGE232',
 TOLERANCE='20%',
 MATERIAL='X6S',
 BOM_COST='MEM_VRD_PVPP_AB',
 PHYS_PAGE='232',
 XY='(-5775,875)',
 ROT='0',
 VER='1',
 VALUE='10UF',
 PACK_TYPE='0603LF',
 PART_NUMBER='E15431-001',
 LOCATION='C6B1',
 ROOM='PVPP_KLM_VR',
 GROUP='PWR_MLCC_CAP',
 CDS_LIB='mstr_discrete',
 CDS_PART_NAME='CAP_0603LF-10UF,4V,20%,X6S,E15A',
 VOLTAGE='4V',
 PRIM_FILE='./archive_libs/mstr_discrete/cap/chips/chips.prt';

PART_NAME
 C6B2 'CAP_0603LF-10UF,4V,20%,X6S,E15A':
 GROUP='PWR_MLCC_CAP',
 ROOM='PVPP_KLM_VR';

SECTION_NUMBER 1
 '@BASEBOARD_FAB2_LIB.BASEBOARD_FAB2(SCH_1):PAGE232_I126@MSTR_DISCRETE.CAP(CHIPS)':
 C_PATH='@baseboard_fab2_lib.baseboard_fab2(sch_1):page232_i126@mstr_discrete.ca~
p(chips)',
 P_PATH='@baseboard_fab2_lib.baseboard_fab2(sch_1):page232_i126@mstr_discrete.ca~
p(chips)',
 PATH='I126',
 DRAWING='@BASEBOARD_FAB2_LIB.BASEBOARD_FAB2(SCH_1):PAGE232',
 TOLERANCE='20%',
 MATERIAL='X6S',
 BOM_COST='MEM_VRD_PVPP_AB',
 PHYS_PAGE='232',
 XY='(-6050,875)',
 ROT='0',
 VER='1',
 VALUE='10UF',
 PACK_TYPE='0603LF',
 PART_NUMBER='E15431-001',
 LOCATION='C6B2',
 ROOM='PVPP_KLM_VR',
 GROUP='PWR_MLCC_CAP',
 CDS_LIB='mstr_discrete',
 CDS_PART_NAME='CAP_0603LF-10UF,4V,20%,X6S,E15A',
 VOLTAGE='4V',
 PRIM_FILE='./archive_libs/mstr_discrete/cap/chips/chips.prt';

PART_NAME
 C6B3 'CAP_0805-47UF,4V,20%,X6S,C9533A':
 GROUP='PWR_MLCC_CAP',
 ROOM='PVPP_KLM_VR',
 REUSE_ID='33';

SECTION_NUMBER 1
 '@BASEBOARD_FAB2_LIB.BASEBOARD_FAB2(SCH_1):PAGE232_I236@MSTR_DISCRETE.CAP(CHIPS)':
 C_PATH='@baseboard_fab2_lib.baseboard_fab2(sch_1):page232_i236@mstr_discrete.ca~
p(chips)',
 P_PATH='@baseboard_fab2_lib.baseboard_fab2(sch_1):page232_i236@mstr_discrete.ca~
p(chips)',
 PATH='I236',
 DRAWING='@BASEBOARD_FAB2_LIB.BASEBOARD_FAB2(SCH_1):PAGE232',
 TOLERANCE='20%',
 MATERIAL='X6S',
 BOM_COST='PVPP_KLM_VR',
 PHYS_PAGE='232',
 REUSE_ID='33',
 XY='(-1475,3675)',
 ROT='0',
 VER='1',
 VALUE='47UF',
 PACK_TYPE='0805',
 PART_NUMBER='C95333-006',
 LOCATION='C6B3',
 ROOM='PVPP_KLM_VR',
 GROUP='PWR_MLCC_CAP',
 CDS_LIB='mstr_discrete',
 CDS_PART_NAME='CAP_0805-47UF,4V,20%,X6S,C9533A',
 VOLTAGE='4V',
 PRIM_FILE='./archive_libs/mstr_discrete/cap/chips/chips.prt';

PART_NAME
 C6B4 'CAP_0402-0.22UF,16V,10%,X7R,A3A':
 GROUP='PCIE_UPLINK',
 ROOM='OCP_STEERING';

SECTION_NUMBER 1
 '@BASEBOARD_FAB2_LIB.BASEBOARD_FAB2(SCH_1):PAGE105_I196@MSTR_DISCRETE.CAP(CHIPS)':
 C_PATH='@baseboard_fab2_lib.baseboard_fab2(sch_1):page105_i196@mstr_discrete.ca~
p(chips)',
 P_PATH='@baseboard_fab2_lib.baseboard_fab2(sch_1):page105_i196@mstr_discrete.ca~
p(chips)',
 PATH='I196',
 DRAWING='@BASEBOARD_FAB2_LIB.BASEBOARD_FAB2(SCH_1):PAGE105',
 TOLERANCE='10%',
 SEC_TYPE='0402',
 MATERIAL='X7R',
 PHYS_PAGE='105',
 XY='(-2750,1975)',
 ROT='2',
 VER='1',
 VALUE='0.22UF',
 PACK_TYPE='0402',
 PART_NUMBER='A36096-155',
 LOCATION='C6B4',
 ROOM='OCP_STEERING',
 GROUP='PCIE_UPLINK',
 SEC='1',
 CDS_LIB='mstr_discrete',
 CDS_PART_NAME='CAP_0402-0.22UF,16V,10%,X7R,A3A',
 VOLTAGE='16V',
 PRIM_FILE='./archive_libs/mstr_discrete/cap/chips/chips.prt';

PART_NAME
 C6B5 'CAP_0402-0.22UF,16V,10%,X7R,A3A':
 GROUP='PCIE_UPLINK',
 ROOM='OCP_STEERING';

SECTION_NUMBER 1
 '@BASEBOARD_FAB2_LIB.BASEBOARD_FAB2(SCH_1):PAGE105_I201@MSTR_DISCRETE.CAP(CHIPS)':
 C_PATH='@baseboard_fab2_lib.baseboard_fab2(sch_1):page105_i201@mstr_discrete.ca~
p(chips)',
 P_PATH='@baseboard_fab2_lib.baseboard_fab2(sch_1):page105_i201@mstr_discrete.ca~
p(chips)',
 PATH='I201',
 DRAWING='@BASEBOARD_FAB2_LIB.BASEBOARD_FAB2(SCH_1):PAGE105',
 TOLERANCE='10%',
 SEC_TYPE='0402',
 MATERIAL='X7R',
 PHYS_PAGE='105',
 XY='(-2700,975)',
 ROT='2',
 VER='1',
 VALUE='0.22UF',
 PACK_TYPE='0402',
 PART_NUMBER='A36096-155',
 LOCATION='C6B5',
 ROOM='OCP_STEERING',
 GROUP='PCIE_UPLINK',
 SEC='1',
 CDS_LIB='mstr_discrete',
 CDS_PART_NAME='CAP_0402-0.22UF,16V,10%,X7R,A3A',
 VOLTAGE='16V',
 PRIM_FILE='./archive_libs/mstr_discrete/cap/chips/chips.prt';

PART_NAME
 C6B6 'CAP_0402-0.22UF,16V,10%,X7R,A3A':
 GROUP='PCIE_UPLINK',
 ROOM='OCP_STEERING';

SECTION_NUMBER 1
 '@BASEBOARD_FAB2_LIB.BASEBOARD_FAB2(SCH_1):PAGE105_I169@MSTR_DISCRETE.CAP(CHIPS)':
 C_PATH='@baseboard_fab2_lib.baseboard_fab2(sch_1):page105_i169@mstr_discrete.ca~
p(chips)',
 P_PATH='@baseboard_fab2_lib.baseboard_fab2(sch_1):page105_i169@mstr_discrete.ca~
p(chips)',
 PATH='I169',
 DRAWING='@BASEBOARD_FAB2_LIB.BASEBOARD_FAB2(SCH_1):PAGE105',
 TOLERANCE='10%',
 SEC_TYPE='0402',
 MATERIAL='X7R',
 PHYS_PAGE='105',
 XY='(-2550,2275)',
 ROT='2',
 VER='1',
 VALUE='0.22UF',
 PACK_TYPE='0402',
 PART_NUMBER='A36096-155',
 LOCATION='C6B6',
 ROOM='OCP_STEERING',
 GROUP='PCIE_UPLINK',
 SEC='1',
 CDS_LIB='mstr_discrete',
 CDS_PART_NAME='CAP_0402-0.22UF,16V,10%,X7R,A3A',
 VOLTAGE='16V',
 PRIM_FILE='./archive_libs/mstr_discrete/cap/chips/chips.prt';

PART_NAME
 C6B7 'CAPP_7343LF-330UF,6.3V,20%,POSA':
 GROUP='PWR_BULK_CAP',
 ROOM='PVPP_KLM_VR',
 REUSE_ID='28';

SECTION_NUMBER 1
 '@BASEBOARD_FAB2_LIB.BASEBOARD_FAB2(SCH_1):PAGE232_I229@MSTR_DISCRETE.CAPP(CHIPS)':
 C_PATH='@baseboard_fab2_lib.baseboard_fab2(sch_1):page232_i229@mstr_discrete.ca~
pp(chips)',
 P_PATH='@baseboard_fab2_lib.baseboard_fab2(sch_1):page232_i229@mstr_discrete.ca~
pp(chips)',
 PATH='I229',
 DRAWING='@BASEBOARD_FAB2_LIB.BASEBOARD_FAB2(SCH_1):PAGE232',
 TOLERANCE='20%',
 MATERIAL='POSCAP',
 BOM_COST='PVPP_KLM_VR',
 PHYS_PAGE='232',
 REUSE_ID='28',
 XY='(-2100,3650)',
 ROT='0',
 VER='1',
 VALUE='330UF',
 PACK_TYPE='7343LF',
 PART_NUMBER='724613-042',
 LOCATION='C6B7',
 ROOM='PVPP_KLM_VR',
 GROUP='PWR_BULK_CAP',
 CDS_LIB='mstr_discrete',
 CDS_PART_NAME='CAPP_7343LF-330UF,6.3V,20%,POSA',
 VOLTAGE='6.3V',
 PRIM_FILE='./archive_libs/mstr_discrete/capp/chips/chips.prt';

PART_NAME
 C6B8 'CAP_0402-0.22UF,16V,10%,X7R,A3A':
 GROUP='PCIE_UPLINK',
 ROOM='OCP_STEERING';

SECTION_NUMBER 1
 '@BASEBOARD_FAB2_LIB.BASEBOARD_FAB2(SCH_1):PAGE105_I198@MSTR_DISCRETE.CAP(CHIPS)':
 C_PATH='@baseboard_fab2_lib.baseboard_fab2(sch_1):page105_i198@mstr_discrete.ca~
p(chips)',
 P_PATH='@baseboard_fab2_lib.baseboard_fab2(sch_1):page105_i198@mstr_discrete.ca~
p(chips)',
 PATH='I198',
 DRAWING='@BASEBOARD_FAB2_LIB.BASEBOARD_FAB2(SCH_1):PAGE105',
 TOLERANCE='10%',
 SEC_TYPE='0402',
 MATERIAL='X7R',
 PHYS_PAGE='105',
 XY='(-2500,1275)',
 ROT='2',
 VER='1',
 VALUE='0.22UF',
 PACK_TYPE='0402',
 PART_NUMBER='A36096-155',
 LOCATION='C6B8',
 ROOM='OCP_STEERING',
 GROUP='PCIE_UPLINK',
 SEC='1',
 CDS_LIB='mstr_discrete',
 CDS_PART_NAME='CAP_0402-0.22UF,16V,10%,X7R,A3A',
 VOLTAGE='16V',
 PRIM_FILE='./archive_libs/mstr_discrete/cap/chips/chips.prt';

PART_NAME
 C6B9 'CAP_0402-0.22UF,16V,10%,X7R,A3A':
 GROUP='PCIE_UPLINK',
 ROOM='OCP_STEERING';

SECTION_NUMBER 1
 '@BASEBOARD_FAB2_LIB.BASEBOARD_FAB2(SCH_1):PAGE105_I185@MSTR_DISCRETE.CAP(CHIPS)':
 C_PATH='@baseboard_fab2_lib.baseboard_fab2(sch_1):page105_i185@mstr_discrete.ca~
p(chips)',
 P_PATH='@baseboard_fab2_lib.baseboard_fab2(sch_1):page105_i185@mstr_discrete.ca~
p(chips)',
 PATH='I185',
 DRAWING='@BASEBOARD_FAB2_LIB.BASEBOARD_FAB2(SCH_1):PAGE105',
 TOLERANCE='10%',
 SEC_TYPE='0402',
 MATERIAL='X7R',
 PHYS_PAGE='105',
 XY='(-2350,1975)',
 ROT='2',
 VER='1',
 VALUE='0.22UF',
 PACK_TYPE='0402',
 PART_NUMBER='A36096-155',
 LOCATION='C6B9',
 ROOM='OCP_STEERING',
 GROUP='PCIE_UPLINK',
 SEC='1',
 CDS_LIB='mstr_discrete',
 CDS_PART_NAME='CAP_0402-0.22UF,16V,10%,X7R,A3A',
 VOLTAGE='16V',
 PRIM_FILE='./archive_libs/mstr_discrete/cap/chips/chips.prt';

PART_NAME
 C6B10 'CAP_0402-0.22UF,16V,10%,X7R,A3A':
 GROUP='PCIE_UPLINK',
 ROOM='OCP_STEERING';

SECTION_NUMBER 1
 '@BASEBOARD_FAB2_LIB.BASEBOARD_FAB2(SCH_1):PAGE105_I193@MSTR_DISCRETE.CAP(CHIPS)':
 C_PATH='@baseboard_fab2_lib.baseboard_fab2(sch_1):page105_i193@mstr_discrete.ca~
p(chips)',
 P_PATH='@baseboard_fab2_lib.baseboard_fab2(sch_1):page105_i193@mstr_discrete.ca~
p(chips)',
 PATH='I193',
 DRAWING='@BASEBOARD_FAB2_LIB.BASEBOARD_FAB2(SCH_1):PAGE105',
 TOLERANCE='10%',
 SEC_TYPE='0402',
 MATERIAL='X7R',
 PHYS_PAGE='105',
 XY='(-2300,975)',
 ROT='2',
 VER='1',
 VALUE='0.22UF',
 PACK_TYPE='0402',
 PART_NUMBER='A36096-155',
 LOCATION='C6B10',
 ROOM='OCP_STEERING',
 GROUP='PCIE_UPLINK',
 SEC='1',
 CDS_LIB='mstr_discrete',
 CDS_PART_NAME='CAP_0402-0.22UF,16V,10%,X7R,A3A',
 VOLTAGE='16V',
 PRIM_FILE='./archive_libs/mstr_discrete/cap/chips/chips.prt';

PART_NAME
 C6B11 'CAP_0402-0.22UF,16V,10%,X7R,A3A':
 GROUP='PCIE_UPLINK',
 ROOM='OCP_STEERING';

SECTION_NUMBER 1
 '@BASEBOARD_FAB2_LIB.BASEBOARD_FAB2(SCH_1):PAGE105_I166@MSTR_DISCRETE.CAP(CHIPS)':
 C_PATH='@baseboard_fab2_lib.baseboard_fab2(sch_1):page105_i166@mstr_discrete.ca~
p(chips)',
 P_PATH='@baseboard_fab2_lib.baseboard_fab2(sch_1):page105_i166@mstr_discrete.ca~
p(chips)',
 PATH='I166',
 DRAWING='@BASEBOARD_FAB2_LIB.BASEBOARD_FAB2(SCH_1):PAGE105',
 TOLERANCE='10%',
 SEC_TYPE='0402',
 MATERIAL='X7R',
 PHYS_PAGE='105',
 XY='(-2150,2275)',
 ROT='2',
 VER='1',
 VALUE='0.22UF',
 PACK_TYPE='0402',
 PART_NUMBER='A36096-155',
 LOCATION='C6B11',
 ROOM='OCP_STEERING',
 GROUP='PCIE_UPLINK',
 SEC='1',
 CDS_LIB='mstr_discrete',
 CDS_PART_NAME='CAP_0402-0.22UF,16V,10%,X7R,A3A',
 VOLTAGE='16V',
 PRIM_FILE='./archive_libs/mstr_discrete/cap/chips/chips.prt';

PART_NAME
 C6B12 'CAP_0402-0.22UF,16V,10%,X7R,A3A':
 GROUP='PCIE_UPLINK',
 ROOM='OCP_STEERING';

SECTION_NUMBER 1
 '@BASEBOARD_FAB2_LIB.BASEBOARD_FAB2(SCH_1):PAGE105_I187@MSTR_DISCRETE.CAP(CHIPS)':
 C_PATH='@baseboard_fab2_lib.baseboard_fab2(sch_1):page105_i187@mstr_discrete.ca~
p(chips)',
 P_PATH='@baseboard_fab2_lib.baseboard_fab2(sch_1):page105_i187@mstr_discrete.ca~
p(chips)',
 PATH='I187',
 DRAWING='@BASEBOARD_FAB2_LIB.BASEBOARD_FAB2(SCH_1):PAGE105',
 TOLERANCE='10%',
 SEC_TYPE='0402',
 MATERIAL='X7R',
 PHYS_PAGE='105',
 XY='(-2100,1275)',
 ROT='2',
 VER='1',
 VALUE='0.22UF',
 PACK_TYPE='0402',
 PART_NUMBER='A36096-155',
 LOCATION='C6B12',
 ROOM='OCP_STEERING',
 GROUP='PCIE_UPLINK',
 SEC='1',
 CDS_LIB='mstr_discrete',
 CDS_PART_NAME='CAP_0402-0.22UF,16V,10%,X7R,A3A',
 VOLTAGE='16V',
 PRIM_FILE='./archive_libs/mstr_discrete/cap/chips/chips.prt';

PART_NAME
 C6B13 'CAP_0402-0.22UF,16V,10%,X7R,A3A':
 GROUP='PCIE_UPLINK',
 ROOM='OCP_STEERING';

SECTION_NUMBER 1
 '@BASEBOARD_FAB2_LIB.BASEBOARD_FAB2(SCH_1):PAGE105_I189@MSTR_DISCRETE.CAP(CHIPS)':
 C_PATH='@baseboard_fab2_lib.baseboard_fab2(sch_1):page105_i189@mstr_discrete.ca~
p(chips)',
 P_PATH='@baseboard_fab2_lib.baseboard_fab2(sch_1):page105_i189@mstr_discrete.ca~
p(chips)',
 PATH='I189',
 DRAWING='@BASEBOARD_FAB2_LIB.BASEBOARD_FAB2(SCH_1):PAGE105',
 TOLERANCE='10%',
 SEC_TYPE='0402',
 MATERIAL='X7R',
 PHYS_PAGE='105',
 XY='(-1900,975)',
 ROT='2',
 VER='1',
 VALUE='0.22UF',
 PACK_TYPE='0402',
 PART_NUMBER='A36096-155',
 LOCATION='C6B13',
 ROOM='OCP_STEERING',
 GROUP='PCIE_UPLINK',
 SEC='1',
 CDS_LIB='mstr_discrete',
 CDS_PART_NAME='CAP_0402-0.22UF,16V,10%,X7R,A3A',
 VOLTAGE='16V',
 PRIM_FILE='./archive_libs/mstr_discrete/cap/chips/chips.prt';

PART_NAME
 C6B14 'CAP_0402-0.22UF,16V,10%,X7R,A3A':
 GROUP='PCIE_UPLINK',
 ROOM='OCP_STEERING';

SECTION_NUMBER 1
 '@BASEBOARD_FAB2_LIB.BASEBOARD_FAB2(SCH_1):PAGE105_I181@MSTR_DISCRETE.CAP(CHIPS)':
 C_PATH='@baseboard_fab2_lib.baseboard_fab2(sch_1):page105_i181@mstr_discrete.ca~
p(chips)',
 P_PATH='@baseboard_fab2_lib.baseboard_fab2(sch_1):page105_i181@mstr_discrete.ca~
p(chips)',
 PATH='I181',
 DRAWING='@BASEBOARD_FAB2_LIB.BASEBOARD_FAB2(SCH_1):PAGE105',
 TOLERANCE='10%',
 SEC_TYPE='0402',
 MATERIAL='X7R',
 PHYS_PAGE='105',
 XY='(-1950,1975)',
 ROT='2',
 VER='1',
 VALUE='0.22UF',
 PACK_TYPE='0402',
 PART_NUMBER='A36096-155',
 LOCATION='C6B14',
 ROOM='OCP_STEERING',
 GROUP='PCIE_UPLINK',
 SEC='1',
 CDS_LIB='mstr_discrete',
 CDS_PART_NAME='CAP_0402-0.22UF,16V,10%,X7R,A3A',
 VOLTAGE='16V',
 PRIM_FILE='./archive_libs/mstr_discrete/cap/chips/chips.prt';

PART_NAME
 C6B15 'CAP_0402-0.22UF,16V,10%,X7R,A3A':
 GROUP='PCIE_UPLINK',
 ROOM='OCP_STEERING';

SECTION_NUMBER 1
 '@BASEBOARD_FAB2_LIB.BASEBOARD_FAB2(SCH_1):PAGE105_I163@MSTR_DISCRETE.CAP(CHIPS)':
 C_PATH='@baseboard_fab2_lib.baseboard_fab2(sch_1):page105_i163@mstr_discrete.ca~
p(chips)',
 P_PATH='@baseboard_fab2_lib.baseboard_fab2(sch_1):page105_i163@mstr_discrete.ca~
p(chips)',
 PATH='I163',
 DRAWING='@BASEBOARD_FAB2_LIB.BASEBOARD_FAB2(SCH_1):PAGE105',
 TOLERANCE='10%',
 SEC_TYPE='0402',
 MATERIAL='X7R',
 PHYS_PAGE='105',
 XY='(-1750,2275)',
 ROT='2',
 VER='1',
 VALUE='0.22UF',
 PACK_TYPE='0402',
 PART_NUMBER='A36096-155',
 LOCATION='C6B15',
 ROOM='OCP_STEERING',
 GROUP='PCIE_UPLINK',
 SEC='1',
 CDS_LIB='mstr_discrete',
 CDS_PART_NAME='CAP_0402-0.22UF,16V,10%,X7R,A3A',
 VOLTAGE='16V',
 PRIM_FILE='./archive_libs/mstr_discrete/cap/chips/chips.prt';

PART_NAME
 C6B16 'CAP_0402-0.22UF,16V,10%,X7R,A3A':
 GROUP='PCIE_UPLINK',
 ROOM='OCP_STEERING';

SECTION_NUMBER 1
 '@BASEBOARD_FAB2_LIB.BASEBOARD_FAB2(SCH_1):PAGE105_I180@MSTR_DISCRETE.CAP(CHIPS)':
 C_PATH='@baseboard_fab2_lib.baseboard_fab2(sch_1):page105_i180@mstr_discrete.ca~
p(chips)',
 P_PATH='@baseboard_fab2_lib.baseboard_fab2(sch_1):page105_i180@mstr_discrete.ca~
p(chips)',
 PATH='I180',
 DRAWING='@BASEBOARD_FAB2_LIB.BASEBOARD_FAB2(SCH_1):PAGE105',
 TOLERANCE='10%',
 SEC_TYPE='0402',
 MATERIAL='X7R',
 PHYS_PAGE='105',
 XY='(-1700,1275)',
 ROT='2',
 VER='1',
 VALUE='0.22UF',
 PACK_TYPE='0402',
 PART_NUMBER='A36096-155',
 LOCATION='C6B16',
 ROOM='OCP_STEERING',
 GROUP='PCIE_UPLINK',
 SEC='1',
 CDS_LIB='mstr_discrete',
 CDS_PART_NAME='CAP_0402-0.22UF,16V,10%,X7R,A3A',
 VOLTAGE='16V',
 PRIM_FILE='./archive_libs/mstr_discrete/cap/chips/chips.prt';

PART_NAME
 C6B17 'CAP_0402-0.22UF,16V,10%,X7R,A3A':
 GROUP='PCIE_UPLINK',
 ROOM='OCP_STEERING';

SECTION_NUMBER 1
 '@BASEBOARD_FAB2_LIB.BASEBOARD_FAB2(SCH_1):PAGE105_I175@MSTR_DISCRETE.CAP(CHIPS)':
 C_PATH='@baseboard_fab2_lib.baseboard_fab2(sch_1):page105_i175@mstr_discrete.ca~
p(chips)',
 P_PATH='@baseboard_fab2_lib.baseboard_fab2(sch_1):page105_i175@mstr_discrete.ca~
p(chips)',
 PATH='I175',
 DRAWING='@BASEBOARD_FAB2_LIB.BASEBOARD_FAB2(SCH_1):PAGE105',
 TOLERANCE='10%',
 SEC_TYPE='0402',
 MATERIAL='X7R',
 PHYS_PAGE='105',
 XY='(-1550,1975)',
 ROT='2',
 VER='1',
 VALUE='0.22UF',
 PACK_TYPE='0402',
 PART_NUMBER='A36096-155',
 LOCATION='C6B17',
 ROOM='OCP_STEERING',
 GROUP='PCIE_UPLINK',
 SEC='1',
 CDS_LIB='mstr_discrete',
 CDS_PART_NAME='CAP_0402-0.22UF,16V,10%,X7R,A3A',
 VOLTAGE='16V',
 PRIM_FILE='./archive_libs/mstr_discrete/cap/chips/chips.prt';

PART_NAME
 C6B18 'CAP_0402-0.22UF,16V,10%,X7R,A3A':
 GROUP='PCIE_UPLINK',
 ROOM='OCP_STEERING';

SECTION_NUMBER 1
 '@BASEBOARD_FAB2_LIB.BASEBOARD_FAB2(SCH_1):PAGE105_I153@MSTR_DISCRETE.CAP(CHIPS)':
 C_PATH='@baseboard_fab2_lib.baseboard_fab2(sch_1):page105_i153@mstr_discrete.ca~
p(chips)',
 P_PATH='@baseboard_fab2_lib.baseboard_fab2(sch_1):page105_i153@mstr_discrete.ca~
p(chips)',
 PATH='I153',
 DRAWING='@BASEBOARD_FAB2_LIB.BASEBOARD_FAB2(SCH_1):PAGE105',
 TOLERANCE='10%',
 SEC_TYPE='0402',
 MATERIAL='X7R',
 PHYS_PAGE='105',
 XY='(-1500,975)',
 ROT='2',
 VER='1',
 VALUE='0.22UF',
 PACK_TYPE='0402',
 PART_NUMBER='A36096-155',
 LOCATION='C6B18',
 ROOM='OCP_STEERING',
 GROUP='PCIE_UPLINK',
 SEC='1',
 CDS_LIB='mstr_discrete',
 CDS_PART_NAME='CAP_0402-0.22UF,16V,10%,X7R,A3A',
 VOLTAGE='16V',
 PRIM_FILE='./archive_libs/mstr_discrete/cap/chips/chips.prt';

PART_NAME
 C6B19 'CAP_0402-0.22UF,16V,10%,X7R,A3A':
 GROUP='PCIE_UPLINK',
 ROOM='OCP_STEERING';

SECTION_NUMBER 1
 '@BASEBOARD_FAB2_LIB.BASEBOARD_FAB2(SCH_1):PAGE105_I160@MSTR_DISCRETE.CAP(CHIPS)':
 C_PATH='@baseboard_fab2_lib.baseboard_fab2(sch_1):page105_i160@mstr_discrete.ca~
p(chips)',
 P_PATH='@baseboard_fab2_lib.baseboard_fab2(sch_1):page105_i160@mstr_discrete.ca~
p(chips)',
 PATH='I160',
 DRAWING='@BASEBOARD_FAB2_LIB.BASEBOARD_FAB2(SCH_1):PAGE105',
 TOLERANCE='10%',
 SEC_TYPE='0402',
 MATERIAL='X7R',
 PHYS_PAGE='105',
 XY='(-1350,2275)',
 ROT='2',
 VER='1',
 VALUE='0.22UF',
 PACK_TYPE='0402',
 PART_NUMBER='A36096-155',
 LOCATION='C6B19',
 ROOM='OCP_STEERING',
 GROUP='PCIE_UPLINK',
 SEC='1',
 CDS_LIB='mstr_discrete',
 CDS_PART_NAME='CAP_0402-0.22UF,16V,10%,X7R,A3A',
 VOLTAGE='16V',
 PRIM_FILE='./archive_libs/mstr_discrete/cap/chips/chips.prt';

PART_NAME
 C6B20 'CAP_0402-0.22UF,16V,10%,X7R,A3A':
 GROUP='PCIE_UPLINK',
 ROOM='OCP_STEERING';

SECTION_NUMBER 1
 '@BASEBOARD_FAB2_LIB.BASEBOARD_FAB2(SCH_1):PAGE105_I173@MSTR_DISCRETE.CAP(CHIPS)':
 C_PATH='@baseboard_fab2_lib.baseboard_fab2(sch_1):page105_i173@mstr_discrete.ca~
p(chips)',
 P_PATH='@baseboard_fab2_lib.baseboard_fab2(sch_1):page105_i173@mstr_discrete.ca~
p(chips)',
 PATH='I173',
 DRAWING='@BASEBOARD_FAB2_LIB.BASEBOARD_FAB2(SCH_1):PAGE105',
 TOLERANCE='10%',
 SEC_TYPE='0402',
 MATERIAL='X7R',
 PHYS_PAGE='105',
 XY='(-1300,1275)',
 ROT='2',
 VER='1',
 VALUE='0.22UF',
 PACK_TYPE='0402',
 PART_NUMBER='A36096-155',
 LOCATION='C6B20',
 ROOM='OCP_STEERING',
 GROUP='PCIE_UPLINK',
 SEC='1',
 CDS_LIB='mstr_discrete',
 CDS_PART_NAME='CAP_0402-0.22UF,16V,10%,X7R,A3A',
 VOLTAGE='16V',
 PRIM_FILE='./archive_libs/mstr_discrete/cap/chips/chips.prt';

PART_NAME
 C6D1 'CAP_0603LF-10UF,4V,20%,X6S,E15A':
 GROUP='PWR_MCP_CAP',
 ROOM='CPU0';

SECTION_NUMBER 1
 '@BASEBOARD_FAB2_LIB.BASEBOARD_FAB2(SCH_1):PAGE38_I19@MSTR_DISCRETE.CAP(CHIPS)':
 C_PATH='@baseboard_fab2_lib.baseboard_fab2(sch_1):page38_i19@mstr_discrete.cap(~
chips)',
 P_PATH='@baseboard_fab2_lib.baseboard_fab2(sch_1):page38_i19@mstr_discrete.cap(~
chips)',
 PATH='I19',
 DRAWING='@BASEBOARD_FAB2_LIB.BASEBOARD_FAB2(SCH_1):PAGE38',
 TOLERANCE='20%',
 SEC_TYPE='0603LF',
 MATERIAL='X6S',
 BOM_COST='PROC_SOCKET',
 PHYS_PAGE='38',
 XY='(3000,1350)',
 ROT='0',
 VER='1',
 VALUE='10UF',
 PACK_TYPE='0603LF',
 PART_NUMBER='E15431-001',
 LOCATION='C6D1',
 ROOM='CPU0',
 GROUP='PWR_MCP_CAP',
 SEC='1',
 CDS_LIB='mstr_discrete',
 CDS_PART_NAME='CAP_0603LF-10UF,4V,20%,X6S,E15A',
 VOLTAGE='4V',
 PRIM_FILE='./archive_libs/mstr_discrete/cap/chips/chips.prt';

PART_NAME
 C6D2 'CAP_A_0603V-22.0UF,4V,20%,X6S,A':
 GROUP='PWR_MCP_CAP',
 ROOM='PVCCIN_CPU0_DECAP_VR';

SECTION_NUMBER 1
 '@BASEBOARD_FAB2_LIB.BASEBOARD_FAB2(SCH_1):PAGE42_I77@DEV_DISCRETE.CAP_A(CHIPS)':
 C_PATH='@baseboard_fab2_lib.baseboard_fab2(sch_1):page42_i77@dev_discrete.cap_a~
(chips)',
 P_PATH='@baseboard_fab2_lib.baseboard_fab2(sch_1):page42_i77@dev_discrete.cap_a~
(chips)',
 PATH='I77',
 DRAWING='@BASEBOARD_FAB2_LIB.BASEBOARD_FAB2(SCH_1):PAGE42',
 TOLERANCE='20%',
 MATERIAL='X6S',
 BOM_COST='PROC_SOCKET',
 PHYS_PAGE='42',
 XY='(-1800,4500)',
 ROT='0',
 VER='1',
 VALUE='22.0UF',
 PACK_TYPE='0603V',
 PART_NUMBER='E15431-004',
 LOCATION='C6D2',
 ROOM='PVCCIN_CPU0_DECAP_VR',
 GROUP='PWR_MCP_CAP',
 CDS_LIB='dev_discrete',
 CDS_PART_NAME='CAP_A_0603V-22.0UF,4V,20%,X6S,A',
 VOLTAGE='4V',
 PRIM_FILE='./archive_libs/discrete/cap_a/chips/chips.prt';

PART_NAME
 C6D3 'CAP_A_0603V-22.0UF,4V,20%,X6S,A':
 GROUP='PWR_MLCC_CAP',
 ROOM='PVCCIN_CPU0_DECAP_VR';

SECTION_NUMBER 1
 '@BASEBOARD_FAB2_LIB.BASEBOARD_FAB2(SCH_1):PAGE42_I80@DEV_DISCRETE.CAP_A(CHIPS)':
 C_PATH='@baseboard_fab2_lib.baseboard_fab2(sch_1):page42_i80@dev_discrete.cap_a~
(chips)',
 P_PATH='@baseboard_fab2_lib.baseboard_fab2(sch_1):page42_i80@dev_discrete.cap_a~
(chips)',
 PATH='I80',
 DRAWING='@BASEBOARD_FAB2_LIB.BASEBOARD_FAB2(SCH_1):PAGE42',
 TOLERANCE='20%',
 MATERIAL='X6S',
 BOM_COST='PROC_SOCKET',
 PHYS_PAGE='42',
 XY='(-3850,3800)',
 ROT='0',
 VER='1',
 VALUE='22.0UF',
 PACK_TYPE='0603V',
 PART_NUMBER='E15431-004',
 LOCATION='C6D3',
 ROOM='PVCCIN_CPU0_DECAP_VR',
 GROUP='PWR_MLCC_CAP',
 CDS_LIB='dev_discrete',
 CDS_PART_NAME='CAP_A_0603V-22.0UF,4V,20%,X6S,A',
 VOLTAGE='4V',
 PRIM_FILE='./archive_libs/discrete/cap_a/chips/chips.prt';

PART_NAME
 C6D4 'CAP_A_0603V-22.0UF,4V,20%,X6S,A':
 GROUP='PWR_MLCC_CAP',
 ROOM='PVCCIN_CPU0_DECAP_VR';

SECTION_NUMBER 1
 '@BASEBOARD_FAB2_LIB.BASEBOARD_FAB2(SCH_1):PAGE42_I74@DEV_DISCRETE.CAP_A(CHIPS)':
 C_PATH='@baseboard_fab2_lib.baseboard_fab2(sch_1):page42_i74@dev_discrete.cap_a~
(chips)',
 P_PATH='@baseboard_fab2_lib.baseboard_fab2(sch_1):page42_i74@dev_discrete.cap_a~
(chips)',
 PATH='I74',
 DRAWING='@BASEBOARD_FAB2_LIB.BASEBOARD_FAB2(SCH_1):PAGE42',
 TOLERANCE='20%',
 MATERIAL='X6S',
 BOM_COST='PROC_SOCKET',
 PHYS_PAGE='42',
 XY='(-3600,3800)',
 ROT='0',
 VER='1',
 VALUE='22.0UF',
 PACK_TYPE='0603V',
 PART_NUMBER='E15431-004',
 LOCATION='C6D4',
 ROOM='PVCCIN_CPU0_DECAP_VR',
 GROUP='PWR_MLCC_CAP',
 CDS_LIB='dev_discrete',
 CDS_PART_NAME='CAP_A_0603V-22.0UF,4V,20%,X6S,A',
 VOLTAGE='4V',
 PRIM_FILE='./archive_libs/discrete/cap_a/chips/chips.prt';

PART_NAME
 C6D5 'CAP_A_0603V-22.0UF,4V,20%,X6S,A':
 GROUP='PWR_MCP_CAP',
 ROOM='PVCCIN_CPU0_DECAP_VR';

SECTION_NUMBER 1
 '@BASEBOARD_FAB2_LIB.BASEBOARD_FAB2(SCH_1):PAGE42_I75@DEV_DISCRETE.CAP_A(CHIPS)':
 C_PATH='@baseboard_fab2_lib.baseboard_fab2(sch_1):page42_i75@dev_discrete.cap_a~
(chips)',
 P_PATH='@baseboard_fab2_lib.baseboard_fab2(sch_1):page42_i75@dev_discrete.cap_a~
(chips)',
 PATH='I75',
 DRAWING='@BASEBOARD_FAB2_LIB.BASEBOARD_FAB2(SCH_1):PAGE42',
 TOLERANCE='20%',
 MATERIAL='X6S',
 BOM_COST='PROC_SOCKET',
 PHYS_PAGE='42',
 XY='(-1550,4500)',
 ROT='0',
 VER='1',
 VALUE='22.0UF',
 PACK_TYPE='0603V',
 PART_NUMBER='E15431-004',
 LOCATION='C6D5',
 ROOM='PVCCIN_CPU0_DECAP_VR',
 GROUP='PWR_MCP_CAP',
 CDS_LIB='dev_discrete',
 CDS_PART_NAME='CAP_A_0603V-22.0UF,4V,20%,X6S,A',
 VOLTAGE='4V',
 PRIM_FILE='./archive_libs/discrete/cap_a/chips/chips.prt';

PART_NAME
 C6D6 'CAP_A_0603V-22.0UF,4V,20%,X6S,A':
 GROUP='PWR_MLCC_CAP',
 ROOM='PVCCIN_CPU0_DECAP_VR';

SECTION_NUMBER 1
 '@BASEBOARD_FAB2_LIB.BASEBOARD_FAB2(SCH_1):PAGE42_I81@DEV_DISCRETE.CAP_A(CHIPS)':
 C_PATH='@baseboard_fab2_lib.baseboard_fab2(sch_1):page42_i81@dev_discrete.cap_a~
(chips)',
 P_PATH='@baseboard_fab2_lib.baseboard_fab2(sch_1):page42_i81@dev_discrete.cap_a~
(chips)',
 PATH='I81',
 DRAWING='@BASEBOARD_FAB2_LIB.BASEBOARD_FAB2(SCH_1):PAGE42',
 TOLERANCE='20%',
 MATERIAL='X6S',
 BOM_COST='PROC_SOCKET',
 PHYS_PAGE='42',
 XY='(-4100,3800)',
 ROT='0',
 VER='1',
 VALUE='22.0UF',
 PACK_TYPE='0603V',
 PART_NUMBER='E15431-004',
 LOCATION='C6D6',
 ROOM='PVCCIN_CPU0_DECAP_VR',
 GROUP='PWR_MLCC_CAP',
 CDS_LIB='dev_discrete',
 CDS_PART_NAME='CAP_A_0603V-22.0UF,4V,20%,X6S,A',
 VOLTAGE='4V',
 PRIM_FILE='./archive_libs/discrete/cap_a/chips/chips.prt';

PART_NAME
 C6D7 'CAP_A_0603V-22.0UF,4V,20%,X6S,A':
 GROUP='PWR_MLCC_CAP',
 ROOM='PVCCIN_CPU0_DECAP_VR';

SECTION_NUMBER 1
 '@BASEBOARD_FAB2_LIB.BASEBOARD_FAB2(SCH_1):PAGE42_I72@DEV_DISCRETE.CAP_A(CHIPS)':
 C_PATH='@baseboard_fab2_lib.baseboard_fab2(sch_1):page42_i72@dev_discrete.cap_a~
(chips)',
 P_PATH='@baseboard_fab2_lib.baseboard_fab2(sch_1):page42_i72@dev_discrete.cap_a~
(chips)',
 PATH='I72',
 DRAWING='@BASEBOARD_FAB2_LIB.BASEBOARD_FAB2(SCH_1):PAGE42',
 TOLERANCE='20%',
 MATERIAL='X6S',
 BOM_COST='PROC_SOCKET',
 PHYS_PAGE='42',
 XY='(-3350,3800)',
 ROT='0',
 VER='1',
 VALUE='22.0UF',
 PACK_TYPE='0603V',
 PART_NUMBER='E15431-004',
 LOCATION='C6D7',
 ROOM='PVCCIN_CPU0_DECAP_VR',
 GROUP='PWR_MLCC_CAP',
 CDS_LIB='dev_discrete',
 CDS_PART_NAME='CAP_A_0603V-22.0UF,4V,20%,X6S,A',
 VOLTAGE='4V',
 PRIM_FILE='./archive_libs/discrete/cap_a/chips/chips.prt';

PART_NAME
 C6D8 'CAP_A_0603V-22.0UF,4V,20%,X6S,A':
 GROUP='PWR_MCP_CAP',
 ROOM='PVCCIN_CPU0_DECAP_VR';

SECTION_NUMBER 1
 '@BASEBOARD_FAB2_LIB.BASEBOARD_FAB2(SCH_1):PAGE42_I68@DEV_DISCRETE.CAP_A(CHIPS)':
 C_PATH='@baseboard_fab2_lib.baseboard_fab2(sch_1):page42_i68@dev_discrete.cap_a~
(chips)',
 P_PATH='@baseboard_fab2_lib.baseboard_fab2(sch_1):page42_i68@dev_discrete.cap_a~
(chips)',
 PATH='I68',
 DRAWING='@BASEBOARD_FAB2_LIB.BASEBOARD_FAB2(SCH_1):PAGE42',
 TOLERANCE='20%',
 MATERIAL='X6S',
 BOM_COST='PROC_SOCKET',
 PHYS_PAGE='42',
 XY='(-800,4500)',
 ROT='0',
 VER='1',
 VALUE='22.0UF',
 PACK_TYPE='0603V',
 PART_NUMBER='E15431-004',
 LOCATION='C6D8',
 ROOM='PVCCIN_CPU0_DECAP_VR',
 GROUP='PWR_MCP_CAP',
 CDS_LIB='dev_discrete',
 CDS_PART_NAME='CAP_A_0603V-22.0UF,4V,20%,X6S,A',
 VOLTAGE='4V',
 PRIM_FILE='./archive_libs/discrete/cap_a/chips/chips.prt';

PART_NAME
 C6D9 'CAP_A_0603V-22.0UF,4V,20%,X6S,A':
 GROUP='PWR_MLCC_CAP',
 ROOM='PVCCIN_CPU0_DECAP_VR';

SECTION_NUMBER 1
 '@BASEBOARD_FAB2_LIB.BASEBOARD_FAB2(SCH_1):PAGE42_I145@DEV_DISCRETE.CAP_A(CHIPS)':
 C_PATH='@baseboard_fab2_lib.baseboard_fab2(sch_1):page42_i145@dev_discrete.cap_~
a(chips)',
 P_PATH='@baseboard_fab2_lib.baseboard_fab2(sch_1):page42_i145@dev_discrete.cap_~
a(chips)',
 PATH='I145',
 DRAWING='@BASEBOARD_FAB2_LIB.BASEBOARD_FAB2(SCH_1):PAGE42',
 TOLERANCE='20%',
 MATERIAL='X6S',
 PHYS_PAGE='42',
 XY='(-2850,3800)',
 ROT='0',
 VER='1',
 VALUE='22.0UF',
 PACK_TYPE='0603V',
 PART_NUMBER='E15431-004',
 LOCATION='C6D9',
 ROOM='PVCCIN_CPU0_DECAP_VR',
 GROUP='PWR_MLCC_CAP',
 CDS_LIB='dev_discrete',
 CDS_PART_NAME='CAP_A_0603V-22.0UF,4V,20%,X6S,A',
 VOLTAGE='4V',
 PRIM_FILE='./archive_libs/discrete/cap_a/chips/chips.prt';

PART_NAME
 C6D10 'CAP_A_0603V-22.0UF,4V,20%,X6S,A':
 GROUP='PWR_MLCC_CAP',
 ROOM='PVCCIN_CPU0_DECAP_VR';

SECTION_NUMBER 1
 '@BASEBOARD_FAB2_LIB.BASEBOARD_FAB2(SCH_1):PAGE42_I147@DEV_DISCRETE.CAP_A(CHIPS)':
 C_PATH='@baseboard_fab2_lib.baseboard_fab2(sch_1):page42_i147@dev_discrete.cap_~
a(chips)',
 P_PATH='@baseboard_fab2_lib.baseboard_fab2(sch_1):page42_i147@dev_discrete.cap_~
a(chips)',
 PATH='I147',
 DRAWING='@BASEBOARD_FAB2_LIB.BASEBOARD_FAB2(SCH_1):PAGE42',
 TOLERANCE='20%',
 MATERIAL='X6S',
 PHYS_PAGE='42',
 XY='(-3100,3800)',
 ROT='0',
 VER='1',
 VALUE='22.0UF',
 PACK_TYPE='0603V',
 PART_NUMBER='E15431-004',
 LOCATION='C6D10',
 ROOM='PVCCIN_CPU0_DECAP_VR',
 GROUP='PWR_MLCC_CAP',
 CDS_LIB='dev_discrete',
 CDS_PART_NAME='CAP_A_0603V-22.0UF,4V,20%,X6S,A',
 VOLTAGE='4V',
 PRIM_FILE='./archive_libs/discrete/cap_a/chips/chips.prt';

PART_NAME
 C6F1 'CAP_A_0402V-0.1UF,16V,10%,X7R,A':
 ROOM='CLOCK_CPU0_OSC';

SECTION_NUMBER 1
 '@BASEBOARD_FAB2_LIB.BASEBOARD_FAB2(SCH_1):PAGE104_I25@DEV_DISCRETE.CAP_A(CHIPS)':
 C_PATH='@baseboard_fab2_lib.baseboard_fab2(sch_1):page104_i25@dev_discrete.cap_~
a(chips)',
 P_PATH='@baseboard_fab2_lib.baseboard_fab2(sch_1):page104_i25@dev_discrete.cap_~
a(chips)',
 PATH='I25',
 DRAWING='@BASEBOARD_FAB2_LIB.BASEBOARD_FAB2(SCH_1):PAGE104',
 TOLERANCE='10%',
 SEC_TYPE='0402V',
 MATERIAL='X7R',
 PHYS_PAGE='104',
 XY='(-4250,5100)',
 ROT='0',
 VER='1',
 VALUE='0.1UF',
 PACK_TYPE='0402V',
 PART_NUMBER='A36096-030',
 LOCATION='C6F1',
 ROOM='CLOCK_CPU0_OSC',
 SEC='1',
 CDS_LIB='dev_discrete',
 CDS_PART_NAME='CAP_A_0402V-0.1UF,16V,10%,X7R,A',
 VOLTAGE='16V',
 PRIM_FILE='./archive_libs/discrete/cap_a/chips/chips.prt';

PART_NAME
 C6F2 'CAP_A_0402V-0.1UF,16V,10%,X7R,A':
 ROOM='MEM',
 SIGNAL_MODEL='DEFAULT_CAPACITOR_100000pF_2_1';

SECTION_NUMBER 1
 '@BASEBOARD_FAB2_LIB.BASEBOARD_FAB2(SCH_1):PAGE99_I2@DEV_DISCRETE.CAP_A(CHIPS)':
 C_PATH='@baseboard_fab2_lib.baseboard_fab2(sch_1):page99_i2@dev_discrete.cap_a(~
chips)',
 P_PATH='@baseboard_fab2_lib.baseboard_fab2(sch_1):page99_i2@dev_discrete.cap_a(~
chips)',
 PATH='I2',
 DRAWING='@BASEBOARD_FAB2_LIB.BASEBOARD_FAB2(SCH_1):PAGE99',
 CD_SEC='1',
 TOLERANCE='10%',
 MATERIAL='X7R',
 BOM_COST='SM_CONTROLLER',
 PHYS_PAGE='99',
 XY='(1900,4925)',
 ROT='0',
 VER='1',
 VALUE='0.1UF',
 PACK_TYPE='0402V',
 PART_NUMBER='A36096-030',
 LOCATION='C6F2',
 SIGNAL_MODEL='DEFAULT_CAPACITOR_100000pF_2_1',
 ROOM='MEM',
 CDS_LIB='dev_discrete',
 CDS_PART_NAME='CAP_A_0402V-0.1UF,16V,10%,X7R,A',
 VOLTAGE='16V',
 PRIM_FILE='./archive_libs/discrete/cap_a/chips/chips.prt';

PART_NAME
 C6F3 'CAP_A_0402V-0.1UF,16V,10%,X7R,A':
 ROOM='MEM',
 SIGNAL_MODEL='DEFAULT_CAPACITOR_100000pF_2_1';

SECTION_NUMBER 1
 '@BASEBOARD_FAB2_LIB.BASEBOARD_FAB2(SCH_1):PAGE99_I7@DEV_DISCRETE.CAP_A(CHIPS)':
 C_PATH='@baseboard_fab2_lib.baseboard_fab2(sch_1):page99_i7@dev_discrete.cap_a(~
chips)',
 P_PATH='@baseboard_fab2_lib.baseboard_fab2(sch_1):page99_i7@dev_discrete.cap_a(~
chips)',
 PATH='I7',
 DRAWING='@BASEBOARD_FAB2_LIB.BASEBOARD_FAB2(SCH_1):PAGE99',
 CD_SEC='1',
 TOLERANCE='10%',
 MATERIAL='X7R',
 BOM_COST='SM_CONTROLLER',
 PHYS_PAGE='99',
 XY='(1475,4900)',
 ROT='0',
 VER='1',
 VALUE='0.1UF',
 PACK_TYPE='0402V',
 PART_NUMBER='A36096-030',
 LOCATION='C6F3',
 SIGNAL_MODEL='DEFAULT_CAPACITOR_100000pF_2_1',
 ROOM='MEM',
 CDS_LIB='dev_discrete',
 CDS_PART_NAME='CAP_A_0402V-0.1UF,16V,10%,X7R,A',
 VOLTAGE='16V',
 PRIM_FILE='./archive_libs/discrete/cap_a/chips/chips.prt';

PART_NAME
 C6F4 'CAPP_7343LF-330UF,6.3V,20%,POSA':
 GROUP='PWR_BULK_CAP',
 ROOM='PVPP_KLM_VR',
 REUSE_ID='28';

SECTION_NUMBER 1
 '@BASEBOARD_FAB2_LIB.BASEBOARD_FAB2(SCH_1):PAGE231_I180@MSTR_DISCRETE.CAPP(CHIPS)':
 C_PATH='@baseboard_fab2_lib.baseboard_fab2(sch_1):page231_i180@mstr_discrete.ca~
pp(chips)',
 P_PATH='@baseboard_fab2_lib.baseboard_fab2(sch_1):page231_i180@mstr_discrete.ca~
pp(chips)',
 PATH='I180',
 DRAWING='@BASEBOARD_FAB2_LIB.BASEBOARD_FAB2(SCH_1):PAGE231',
 TOLERANCE='20%',
 MATERIAL='POSCAP',
 BOM_COST='PVPP_KLM_VR',
 PHYS_PAGE='231',
 REUSE_ID='28',
 XY='(-1400,3900)',
 ROT='0',
 VER='1',
 VALUE='330UF',
 PACK_TYPE='7343LF',
 PART_NUMBER='724613-042',
 LOCATION='C6F4',
 ROOM='PVPP_KLM_VR',
 GROUP='PWR_BULK_CAP',
 CDS_LIB='mstr_discrete',
 CDS_PART_NAME='CAPP_7343LF-330UF,6.3V,20%,POSA',
 VOLTAGE='6.3V',
 PRIM_FILE='./archive_libs/mstr_discrete/capp/chips/chips.prt';

PART_NAME
 C6F5 'CAP_0603LF-10UF,4V,20%,X6S,E15A':
 GROUP='PWR_MLCC_CAP',
 ROOM='PVPP_KLM_VR';

SECTION_NUMBER 1
 '@BASEBOARD_FAB2_LIB.BASEBOARD_FAB2(SCH_1):PAGE231_I149@MSTR_DISCRETE.CAP(CHIPS)':
 C_PATH='@baseboard_fab2_lib.baseboard_fab2(sch_1):page231_i149@mstr_discrete.ca~
p(chips)',
 P_PATH='@baseboard_fab2_lib.baseboard_fab2(sch_1):page231_i149@mstr_discrete.ca~
p(chips)',
 PATH='I149',
 DRAWING='@BASEBOARD_FAB2_LIB.BASEBOARD_FAB2(SCH_1):PAGE231',
 TOLERANCE='20%',
 SEC_TYPE='0603LF',
 MATERIAL='X6S',
 BOM_COST='MEM_VRD_PVPP_AB',
 PHYS_PAGE='231',
 XY='(-4800,975)',
 ROT='0',
 VER='1',
 VALUE='10UF',
 PACK_TYPE='0603LF',
 PART_NUMBER='E15431-001',
 LOCATION='C6F5',
 ROOM='PVPP_KLM_VR',
 GROUP='PWR_MLCC_CAP',
 SEC='1',
 CDS_LIB='mstr_discrete',
 CDS_PART_NAME='CAP_0603LF-10UF,4V,20%,X6S,E15A',
 VOLTAGE='4V',
 PRIM_FILE='./archive_libs/mstr_discrete/cap/chips/chips.prt';

PART_NAME
 C6F6 'CAP_0603LF-10UF,4V,20%,X6S,E15A':
 GROUP='PWR_MLCC_CAP',
 ROOM='PVPP_KLM_VR';

SECTION_NUMBER 1
 '@BASEBOARD_FAB2_LIB.BASEBOARD_FAB2(SCH_1):PAGE231_I122@MSTR_DISCRETE.CAP(CHIPS)':
 C_PATH='@baseboard_fab2_lib.baseboard_fab2(sch_1):page231_i122@mstr_discrete.ca~
p(chips)',
 P_PATH='@baseboard_fab2_lib.baseboard_fab2(sch_1):page231_i122@mstr_discrete.ca~
p(chips)',
 PATH='I122',
 DRAWING='@BASEBOARD_FAB2_LIB.BASEBOARD_FAB2(SCH_1):PAGE231',
 TOLERANCE='20%',
 MATERIAL='X6S',
 BOM_COST='MEM_VRD_PVPP_AB',
 PHYS_PAGE='231',
 XY='(-7925,1000)',
 ROT='0',
 VER='1',
 VALUE='10UF',
 PACK_TYPE='0603LF',
 PART_NUMBER='E15431-001',
 LOCATION='C6F6',
 ROOM='PVPP_KLM_VR',
 GROUP='PWR_MLCC_CAP',
 CDS_LIB='mstr_discrete',
 CDS_PART_NAME='CAP_0603LF-10UF,4V,20%,X6S,E15A',
 VOLTAGE='4V',
 PRIM_FILE='./archive_libs/mstr_discrete/cap/chips/chips.prt';

PART_NAME
 C6G1 'CAP_0603LF-10UF,4V,20%,X6S,E15A':
 GROUP='PWR_MLCC_CAP',
 ROOM='PVPP_KLM_VR';

SECTION_NUMBER 1
 '@BASEBOARD_FAB2_LIB.BASEBOARD_FAB2(SCH_1):PAGE231_I126@MSTR_DISCRETE.CAP(CHIPS)':
 C_PATH='@baseboard_fab2_lib.baseboard_fab2(sch_1):page231_i126@mstr_discrete.ca~
p(chips)',
 P_PATH='@baseboard_fab2_lib.baseboard_fab2(sch_1):page231_i126@mstr_discrete.ca~
p(chips)',
 PATH='I126',
 DRAWING='@BASEBOARD_FAB2_LIB.BASEBOARD_FAB2(SCH_1):PAGE231',
 TOLERANCE='20%',
 MATERIAL='X6S',
 BOM_COST='MEM_VRD_PVPP_AB',
 PHYS_PAGE='231',
 XY='(-7075,975)',
 ROT='0',
 VER='1',
 VALUE='10UF',
 PACK_TYPE='0603LF',
 PART_NUMBER='E15431-001',
 LOCATION='C6G1',
 ROOM='PVPP_KLM_VR',
 GROUP='PWR_MLCC_CAP',
 CDS_LIB='mstr_discrete',
 CDS_PART_NAME='CAP_0603LF-10UF,4V,20%,X6S,E15A',
 VOLTAGE='4V',
 PRIM_FILE='./archive_libs/mstr_discrete/cap/chips/chips.prt';

PART_NAME
 C6G2 'CAP_0603LF-10UF,4V,20%,X6S,E15A':
 GROUP='PWR_MLCC_CAP',
 ROOM='PVPP_KLM_VR';

SECTION_NUMBER 1
 '@BASEBOARD_FAB2_LIB.BASEBOARD_FAB2(SCH_1):PAGE231_I128@MSTR_DISCRETE.CAP(CHIPS)':
 C_PATH='@baseboard_fab2_lib.baseboard_fab2(sch_1):page231_i128@mstr_discrete.ca~
p(chips)',
 P_PATH='@baseboard_fab2_lib.baseboard_fab2(sch_1):page231_i128@mstr_discrete.ca~
p(chips)',
 PATH='I128',
 DRAWING='@BASEBOARD_FAB2_LIB.BASEBOARD_FAB2(SCH_1):PAGE231',
 TOLERANCE='20%',
 MATERIAL='X6S',
 BOM_COST='MEM_VRD_PVPP_AB',
 PHYS_PAGE='231',
 XY='(-6800,1000)',
 ROT='0',
 VER='1',
 VALUE='10UF',
 PACK_TYPE='0603LF',
 PART_NUMBER='E15431-001',
 LOCATION='C6G2',
 ROOM='PVPP_KLM_VR',
 GROUP='PWR_MLCC_CAP',
 CDS_LIB='mstr_discrete',
 CDS_PART_NAME='CAP_0603LF-10UF,4V,20%,X6S,E15A',
 VOLTAGE='4V',
 PRIM_FILE='./archive_libs/mstr_discrete/cap/chips/chips.prt';

PART_NAME
 C6G3 'CAP_0805LF-22UF,4V,20%,X6S,C95A':
 GROUP='PWR_MLCC_CAP',
 ROOM='VDDQ_ABC_PWR_VR';

SECTION_NUMBER 1
 '@BASEBOARD_FAB2_LIB.BASEBOARD_FAB2(SCH_1):PAGE216_I6@MSTR_DISCRETE.CAP(CHIPS)':
 C_PATH='@baseboard_fab2_lib.baseboard_fab2(sch_1):page216_i6@mstr_discrete.cap(~
chips)',
 P_PATH='@baseboard_fab2_lib.baseboard_fab2(sch_1):page216_i6@mstr_discrete.cap(~
chips)',
 PATH='I6',
 DRAWING='@BASEBOARD_FAB2_LIB.BASEBOARD_FAB2(SCH_1):PAGE216',
 TOLERANCE='20%',
 SEC_TYPE='0805LF',
 MATERIAL='X6S',
 BOM_COST='PROC_VRD_VCCIN_CPU0',
 PHYS_PAGE='216',
 XY='(4350,1850)',
 ROT='0',
 VER='1',
 VALUE='22UF',
 PACK_TYPE='0805LF',
 PART_NUMBER='C95333-002',
 LOCATION='C6G3',
 ROOM='VDDQ_ABC_PWR_VR',
 GROUP='PWR_MLCC_CAP',
 SEC='1',
 CDS_LIB='mstr_discrete',
 CDS_PART_NAME='CAP_0805LF-22UF,4V,20%,X6S,C95A',
 VOLTAGE='4V',
 PRIM_FILE='./archive_libs/mstr_discrete/cap/chips/chips.prt';

PART_NAME
 C6G4 'CAP_0603LF-10UF,4V,20%,X6S,E15A':
 GROUP='PWR_MLCC_CAP',
 ROOM='PVPP_KLM_VR';

SECTION_NUMBER 1
 '@BASEBOARD_FAB2_LIB.BASEBOARD_FAB2(SCH_1):PAGE231_I131@MSTR_DISCRETE.CAP(CHIPS)':
 C_PATH='@baseboard_fab2_lib.baseboard_fab2(sch_1):page231_i131@mstr_discrete.ca~
p(chips)',
 P_PATH='@baseboard_fab2_lib.baseboard_fab2(sch_1):page231_i131@mstr_discrete.ca~
p(chips)',
 PATH='I131',
 DRAWING='@BASEBOARD_FAB2_LIB.BASEBOARD_FAB2(SCH_1):PAGE231',
 TOLERANCE='20%',
 MATERIAL='X6S',
 BOM_COST='MEM_VRD_PVPP_AB',
 PHYS_PAGE='231',
 XY='(-5925,1000)',
 ROT='0',
 VER='1',
 VALUE='10UF',
 PACK_TYPE='0603LF',
 PART_NUMBER='E15431-001',
 LOCATION='C6G4',
 ROOM='PVPP_KLM_VR',
 GROUP='PWR_MLCC_CAP',
 CDS_LIB='mstr_discrete',
 CDS_PART_NAME='CAP_0603LF-10UF,4V,20%,X6S,E15A',
 VOLTAGE='4V',
 PRIM_FILE='./archive_libs/mstr_discrete/cap/chips/chips.prt';

PART_NAME
 C6G5 'CAP_0603LF-10UF,4V,20%,X6S,E15A':
 GROUP='PWR_MLCC_CAP',
 ROOM='PVPP_KLM_VR';

SECTION_NUMBER 1
 '@BASEBOARD_FAB2_LIB.BASEBOARD_FAB2(SCH_1):PAGE231_I145@MSTR_DISCRETE.CAP(CHIPS)':
 C_PATH='@baseboard_fab2_lib.baseboard_fab2(sch_1):page231_i145@mstr_discrete.ca~
p(chips)',
 P_PATH='@baseboard_fab2_lib.baseboard_fab2(sch_1):page231_i145@mstr_discrete.ca~
p(chips)',
 PATH='I145',
 DRAWING='@BASEBOARD_FAB2_LIB.BASEBOARD_FAB2(SCH_1):PAGE231',
 TOLERANCE='20%',
 MATERIAL='X6S',
 BOM_COST='MEM_VRD_PVPP_AB',
 PHYS_PAGE='231',
 XY='(-5625,1000)',
 ROT='0',
 VER='1',
 VALUE='10UF',
 PACK_TYPE='0603LF',
 PART_NUMBER='E15431-001',
 LOCATION='C6G5',
 ROOM='PVPP_KLM_VR',
 GROUP='PWR_MLCC_CAP',
 CDS_LIB='mstr_discrete',
 CDS_PART_NAME='CAP_0603LF-10UF,4V,20%,X6S,E15A',
 VOLTAGE='4V',
 PRIM_FILE='./archive_libs/mstr_discrete/cap/chips/chips.prt';

PART_NAME
 C6L1 'CAP_A_0402V-0.01UF,25V,10%,X7RA':
 ROOM='DDR4_CH_F';

SECTION_NUMBER 1
 '@BASEBOARD_FAB2_LIB.BASEBOARD_FAB2(SCH_1):PAGE53_I178@DEV_DISCRETE.CAP_A(CHIPS)':
 C_PATH='@baseboard_fab2_lib.baseboard_fab2(sch_1):page53_i178@dev_discrete.cap_~
a(chips)',
 P_PATH='@baseboard_fab2_lib.baseboard_fab2(sch_1):page53_i178@dev_discrete.cap_~
a(chips)',
 PATH='I178',
 DRAWING='@BASEBOARD_FAB2_LIB.BASEBOARD_FAB2(SCH_1):PAGE53',
 TOLERANCE='10%',
 SEC_TYPE='0402V',
 MATERIAL='X7R',
 BOM_COST='MEM',
 PHYS_PAGE='53',
 XY='(-4500,1125)',
 ROT='2',
 VER='1',
 VALUE='0.01UF',
 PACK_TYPE='0402V',
 PART_NUMBER='A36096-045',
 LOCATION='C6L1',
 ROOM='DDR4_CH_F',
 SEC='1',
 CDS_LIB='dev_discrete',
 CDS_PART_NAME='CAP_A_0402V-0.01UF,25V,10%,X7RA',
 VOLTAGE='25V',
 PRIM_FILE='./archive_libs/discrete/cap_a/chips/chips.prt';

PART_NAME
 C6L2 'CAP_A_0402V-0.01UF,25V,10%,X7RA':
 ROOM='MEM';

SECTION_NUMBER 1
 '@BASEBOARD_FAB2_LIB.BASEBOARD_FAB2(SCH_1):PAGE98_I67@DEV_DISCRETE.CAP_A(CHIPS)':
 C_PATH='@baseboard_fab2_lib.baseboard_fab2(sch_1):page98_i67@dev_discrete.cap_a~
(chips)',
 P_PATH='@baseboard_fab2_lib.baseboard_fab2(sch_1):page98_i67@dev_discrete.cap_a~
(chips)',
 PATH='I67',
 DRAWING='@BASEBOARD_FAB2_LIB.BASEBOARD_FAB2(SCH_1):PAGE98',
 TOLERANCE='10%',
 SEC_TYPE='0402V',
 MATERIAL='X7R',
 BOM_COST='SM_CONTROLLER',
 PHYS_PAGE='98',
 XY='(1950,2025)',
 ROT='0',
 VER='1',
 VALUE='0.01UF',
 PACK_TYPE='0402V',
 PART_NUMBER='A36096-045',
 LOCATION='C6L2',
 ROOM='MEM',
 SEC='1',
 CDS_LIB='dev_discrete',
 CDS_PART_NAME='CAP_A_0402V-0.01UF,25V,10%,X7RA',
 VOLTAGE='25V',
 PRIM_FILE='./archive_libs/discrete/cap_a/chips/chips.prt';

PART_NAME
 C6L3 'CAP_0603LF-10UF,4V,20%,X6S,E15A':
 ROOM='VTT_DEF_PWR_VR';

SECTION_NUMBER 1
 '@BASEBOARD_FAB2_LIB.BASEBOARD_FAB2(SCH_1):PAGE222_I17@MSTR_DISCRETE.CAP(CHIPS)':
 C_PATH='@baseboard_fab2_lib.baseboard_fab2(sch_1):page222_i17@mstr_discrete.cap~
(chips)',
 P_PATH='@baseboard_fab2_lib.baseboard_fab2(sch_1):page222_i17@mstr_discrete.cap~
(chips)',
 PATH='I17',
 DRAWING='@BASEBOARD_FAB2_LIB.BASEBOARD_FAB2(SCH_1):PAGE222',
 TOLERANCE='20%',
 SEC_TYPE='0603LF',
 MATERIAL='X6S',
 BOM_COST='MEM_VRD_VTT_DEF',
 PHYS_PAGE='222',
 XY='(-325,1925)',
 ROT='0',
 VER='1',
 VALUE='10UF',
 PACK_TYPE='0603LF',
 PART_NUMBER='E15431-001',
 LOCATION='C6L3',
 ROOM='VTT_DEF_PWR_VR',
 SEC='1',
 CDS_LIB='mstr_discrete',
 CDS_PART_NAME='CAP_0603LF-10UF,4V,20%,X6S,E15A',
 VOLTAGE='4V',
 PRIM_FILE='./archive_libs/mstr_discrete/cap/chips/chips.prt';

PART_NAME
 C6L4 'CAP_0603LF-10UF,4V,20%,X6S,E15A':
 ROOM='VTT_DEF_PWR_VR';

SECTION_NUMBER 1
 '@BASEBOARD_FAB2_LIB.BASEBOARD_FAB2(SCH_1):PAGE222_I15@MSTR_DISCRETE.CAP(CHIPS)':
 C_PATH='@baseboard_fab2_lib.baseboard_fab2(sch_1):page222_i15@mstr_discrete.cap~
(chips)',
 P_PATH='@baseboard_fab2_lib.baseboard_fab2(sch_1):page222_i15@mstr_discrete.cap~
(chips)',
 PATH='I15',
 DRAWING='@BASEBOARD_FAB2_LIB.BASEBOARD_FAB2(SCH_1):PAGE222',
 TOLERANCE='20%',
 SEC_TYPE='0603LF',
 MATERIAL='X6S',
 BOM_COST='MEM_VRD_VTT_DEF',
 PHYS_PAGE='222',
 XY='(-750,1900)',
 ROT='0',
 VER='1',
 VALUE='10UF',
 PACK_TYPE='0603LF',
 PART_NUMBER='E15431-001',
 LOCATION='C6L4',
 ROOM='VTT_DEF_PWR_VR',
 SEC='1',
 CDS_LIB='mstr_discrete',
 CDS_PART_NAME='CAP_0603LF-10UF,4V,20%,X6S,E15A',
 VOLTAGE='4V',
 PRIM_FILE='./archive_libs/mstr_discrete/cap/chips/chips.prt';

PART_NAME
 C6L5 'CAP_0603LF-10UF,4V,20%,X6S,E15A':
 ROOM='VTT_KLM_PWR_VR';

SECTION_NUMBER 1
 '@BASEBOARD_FAB2_LIB.BASEBOARD_FAB2(SCH_1):PAGE230_I35@MSTR_DISCRETE.CAP(CHIPS)':
 C_PATH='@baseboard_fab2_lib.baseboard_fab2(sch_1):page230_i35@mstr_discrete.cap~
(chips)',
 P_PATH='@baseboard_fab2_lib.baseboard_fab2(sch_1):page230_i35@mstr_discrete.cap~
(chips)',
 PATH='I35',
 DRAWING='@BASEBOARD_FAB2_LIB.BASEBOARD_FAB2(SCH_1):PAGE230',
 TOLERANCE='20%',
 SEC_TYPE='0603LF',
 MATERIAL='X6S',
 BOM_COST='MEM_VRD_VTT_KLM',
 PHYS_PAGE='230',
 XY='(-1625,1625)',
 ROT='0',
 VER='1',
 VALUE='10UF',
 PACK_TYPE='0603LF',
 PART_NUMBER='E15431-001',
 LOCATION='C6L5',
 ROOM='VTT_KLM_PWR_VR',
 SEC='1',
 CDS_LIB='mstr_discrete',
 CDS_PART_NAME='CAP_0603LF-10UF,4V,20%,X6S,E15A',
 VOLTAGE='4V',
 PRIM_FILE='./archive_libs/mstr_discrete/cap/chips/chips.prt';

PART_NAME
 C6L6 'CAP_A_0402V-0.01UF,25V,10%,X7RA':
 ROOM='DDR4_CH_E';

SECTION_NUMBER 1
 '@BASEBOARD_FAB2_LIB.BASEBOARD_FAB2(SCH_1):PAGE51_I175@DEV_DISCRETE.CAP_A(CHIPS)':
 C_PATH='@baseboard_fab2_lib.baseboard_fab2(sch_1):page51_i175@dev_discrete.cap_~
a(chips)',
 P_PATH='@baseboard_fab2_lib.baseboard_fab2(sch_1):page51_i175@dev_discrete.cap_~
a(chips)',
 PATH='I175',
 DRAWING='@BASEBOARD_FAB2_LIB.BASEBOARD_FAB2(SCH_1):PAGE51',
 TOLERANCE='10%',
 SEC_TYPE='0402V',
 MATERIAL='X7R',
 BOM_COST='MEM',
 PHYS_PAGE='51',
 XY='(-4650,1550)',
 ROT='2',
 VER='1',
 VALUE='0.01UF',
 PACK_TYPE='0402V',
 PART_NUMBER='A36096-045',
 LOCATION='C6L6',
 ROOM='DDR4_CH_E',
 SEC='1',
 CDS_LIB='dev_discrete',
 CDS_PART_NAME='CAP_A_0402V-0.01UF,25V,10%,X7RA',
 VOLTAGE='25V',
 PRIM_FILE='./archive_libs/discrete/cap_a/chips/chips.prt';

PART_NAME
 C6L7 'CAP_A_0402V-0.01UF,25V,10%,X7RA':
 ROOM='MEM';

SECTION_NUMBER 1
 '@BASEBOARD_FAB2_LIB.BASEBOARD_FAB2(SCH_1):PAGE98_I59@DEV_DISCRETE.CAP_A(CHIPS)':
 C_PATH='@baseboard_fab2_lib.baseboard_fab2(sch_1):page98_i59@dev_discrete.cap_a~
(chips)',
 P_PATH='@baseboard_fab2_lib.baseboard_fab2(sch_1):page98_i59@dev_discrete.cap_a~
(chips)',
 PATH='I59',
 DRAWING='@BASEBOARD_FAB2_LIB.BASEBOARD_FAB2(SCH_1):PAGE98',
 TOLERANCE='10%',
 SEC_TYPE='0402V',
 MATERIAL='X7R',
 BOM_COST='SM_CONTROLLER',
 PHYS_PAGE='98',
 XY='(-225,2050)',
 ROT='0',
 VER='1',
 VALUE='0.01UF',
 PACK_TYPE='0402V',
 PART_NUMBER='A36096-045',
 LOCATION='C6L7',
 ROOM='MEM',
 SEC='1',
 CDS_LIB='dev_discrete',
 CDS_PART_NAME='CAP_A_0402V-0.01UF,25V,10%,X7RA',
 VOLTAGE='25V',
 PRIM_FILE='./archive_libs/discrete/cap_a/chips/chips.prt';

PART_NAME
 C6L8 'CAPP_7343-220UF,4V,20%,POSCAP,A':
 GROUP='PWR_BULK_CAP';

SECTION_NUMBER 1
 '@BASEBOARD_FAB2_LIB.BASEBOARD_FAB2(SCH_1):PAGE234_I210@MSTR_DISCRETE.CAPP(CHIPS)':
 C_PATH='@baseboard_fab2_lib.baseboard_fab2(sch_1):page234_i210@mstr_discrete.ca~
pp(chips)',
 P_PATH='@baseboard_fab2_lib.baseboard_fab2(sch_1):page234_i210@mstr_discrete.ca~
pp(chips)',
 PATH='I210',
 DRAWING='@BASEBOARD_FAB2_LIB.BASEBOARD_FAB2(SCH_1):PAGE234',
 TOLERANCE='20%',
 SEC_TYPE='7343',
 MATERIAL='POSCAP',
 PHYS_PAGE='234',
 XY='(-1450,3650)',
 ROT='0',
 VER='1',
 VALUE='220UF',
 PACK_TYPE='7343',
 PART_NUMBER='724613-067',
 LOCATION='C6L8',
 GROUP='PWR_BULK_CAP',
 SEC='1',
 CDS_LIB='mstr_discrete',
 CDS_PART_NAME='CAPP_7343-220UF,4V,20%,POSCAP,A',
 VOLTAGE='4V',
 PRIM_FILE='./archive_libs/mstr_discrete/capp/chips/chips.prt';

PART_NAME
 C6L10 'CAP_0805-10UF,16V,10%,X6S,C953A':;

SECTION_NUMBER 1
 '@BASEBOARD_FAB2_LIB.BASEBOARD_FAB2(SCH_1):PAGE234_I202@MSTR_DISCRETE.CAP(CHIPS)':
 C_PATH='@baseboard_fab2_lib.baseboard_fab2(sch_1):page234_i202@mstr_discrete.ca~
p(chips)',
 P_PATH='@baseboard_fab2_lib.baseboard_fab2(sch_1):page234_i202@mstr_discrete.ca~
p(chips)',
 PATH='I202',
 DRAWING='@BASEBOARD_FAB2_LIB.BASEBOARD_FAB2(SCH_1):PAGE234',
 TOLERANCE='10%',
 SEC_TYPE='0805',
 MATERIAL='X6S',
 PHYS_PAGE='234',
 XY='(-6750,4150)',
 ROT='0',
 VER='1',
 VALUE='10UF',
 PACK_TYPE='0805',
 PART_NUMBER='C95333-007',
 LOCATION='C6L10',
 SEC='1',
 CDS_LIB='mstr_discrete',
 CDS_PART_NAME='CAP_0805-10UF,16V,10%,X6S,C953A',
 VOLTAGE='16V',
 PRIM_FILE='./archive_libs/mstr_discrete/cap/chips/chips.prt';

PART_NAME
 C6L11 'CAP_0402-1.0UF,16V,10%,X6S,D97A':
 ROOM='PVPP_KLM_VR',
 REUSE_ID='1';

SECTION_NUMBER 1
 '@BASEBOARD_FAB2_LIB.BASEBOARD_FAB2(SCH_1):PAGE234_I152@MSTR_DISCRETE.CAP(CHIPS)':
 C_PATH='@baseboard_fab2_lib.baseboard_fab2(sch_1):page234_i152@mstr_discrete.ca~
p(chips)',
 P_PATH='@baseboard_fab2_lib.baseboard_fab2(sch_1):page234_i152@mstr_discrete.ca~
p(chips)',
 PATH='I152',
 DRAWING='@BASEBOARD_FAB2_LIB.BASEBOARD_FAB2(SCH_1):PAGE234',
 FIN='VR_1P2',
 TOLERANCE='10%',
 MATERIAL='X6S',
 BOM_COST='PVPP_KLM_VR',
 PHYS_PAGE='234',
 REUSE_ID='1',
 XY='(-5100,4150)',
 ROT='0',
 VER='1',
 VALUE='1.0UF',
 PACK_TYPE='0402',
 PART_NUMBER='D97712-011',
 LOCATION='C6L11',
 ROOM='PVPP_KLM_VR',
 CDS_LIB='mstr_discrete',
 CDS_PART_NAME='CAP_0402-1.0UF,16V,10%,X6S,D97A',
 VOLTAGE='16V',
 PRIM_FILE='./archive_libs/mstr_discrete/cap/chips/chips.prt';

PART_NAME
 C6L12 'CAP_0603-4.7UF,6.3V,10%,X6S,E1A':
 ROOM='PVPP_KLM_VR',
 REUSE_ID='26';

SECTION_NUMBER 1
 '@BASEBOARD_FAB2_LIB.BASEBOARD_FAB2(SCH_1):PAGE234_I144@MSTR_DISCRETE.CAP(CHIPS)':
 C_PATH='@baseboard_fab2_lib.baseboard_fab2(sch_1):page234_i144@mstr_discrete.ca~
p(chips)',
 P_PATH='@baseboard_fab2_lib.baseboard_fab2(sch_1):page234_i144@mstr_discrete.ca~
p(chips)',
 PATH='I144',
 DRAWING='@BASEBOARD_FAB2_LIB.BASEBOARD_FAB2(SCH_1):PAGE234',
 CONFIG='078.47521.08BD',
 TOLERANCE='10%',
 SEC_TYPE='0603',
 MATERIAL='X6S',
 BOM_COST='PVPP_KLM_VR',
 PHYS_PAGE='234',
 REUSE_ID='26',
 XY='(-5650,2400)',
 ROT='0',
 VER='1',
 VALUE='4.7UF',
 PACK_TYPE='0603',
 PART_NUMBER='E15431-003',
 LOCATION='C6L12',
 ROOM='PVPP_KLM_VR',
 SEC='1',
 CDS_LIB='mstr_discrete',
 CDS_PART_NAME='CAP_0603-4.7UF,6.3V,10%,X6S,E1A',
 VOLTAGE='6.3V',
 PRIM_FILE='./archive_libs/mstr_discrete/cap/chips/chips.prt';

PART_NAME
 C6M1 'CAP_A_0402V-0.01UF,25V,10%,X7RA':
 ROOM='DDR4_CH_B';

SECTION_NUMBER 1
 '@BASEBOARD_FAB2_LIB.BASEBOARD_FAB2(SCH_1):PAGE50_I177@DEV_DISCRETE.CAP_A(CHIPS)':
 C_PATH='@baseboard_fab2_lib.baseboard_fab2(sch_1):page50_i177@dev_discrete.cap_~
a(chips)',
 P_PATH='@baseboard_fab2_lib.baseboard_fab2(sch_1):page50_i177@dev_discrete.cap_~
a(chips)',
 PATH='I177',
 DRAWING='@BASEBOARD_FAB2_LIB.BASEBOARD_FAB2(SCH_1):PAGE50',
 TOLERANCE='10%',
 SEC_TYPE='0402V',
 MATERIAL='X7R',
 BOM_COST='MEM',
 PHYS_PAGE='50',
 XY='(-1200,1400)',
 ROT='2',
 VER='1',
 VALUE='0.01UF',
 PACK_TYPE='0402V',
 PART_NUMBER='A36096-045',
 LOCATION='C6M1',
 ROOM='DDR4_CH_B',
 SEC='1',
 CDS_LIB='dev_discrete',
 CDS_PART_NAME='CAP_A_0402V-0.01UF,25V,10%,X7RA',
 VOLTAGE='25V',
 PRIM_FILE='./archive_libs/discrete/cap_a/chips/chips.prt';

PART_NAME
 C6M2 'CAP_A_0402V-0.01UF,25V,10%,X7RA':
 ROOM='MEM';

SECTION_NUMBER 1
 '@BASEBOARD_FAB2_LIB.BASEBOARD_FAB2(SCH_1):PAGE98_I33@DEV_DISCRETE.CAP_A(CHIPS)':
 C_PATH='@baseboard_fab2_lib.baseboard_fab2(sch_1):page98_i33@dev_discrete.cap_a~
(chips)',
 P_PATH='@baseboard_fab2_lib.baseboard_fab2(sch_1):page98_i33@dev_discrete.cap_a~
(chips)',
 PATH='I33',
 DRAWING='@BASEBOARD_FAB2_LIB.BASEBOARD_FAB2(SCH_1):PAGE98',
 TOLERANCE='10%',
 SEC_TYPE='0402V',
 MATERIAL='X7R',
 BOM_COST='SM_CONTROLLER',
 PHYS_PAGE='98',
 XY='(-2250,2050)',
 ROT='0',
 VER='1',
 VALUE='0.01UF',
 PACK_TYPE='0402V',
 PART_NUMBER='A36096-045',
 LOCATION='C6M2',
 ROOM='MEM',
 SEC='1',
 CDS_LIB='dev_discrete',
 CDS_PART_NAME='CAP_A_0402V-0.01UF,25V,10%,X7RA',
 VOLTAGE='25V',
 PRIM_FILE='./archive_libs/discrete/cap_a/chips/chips.prt';

PART_NAME
 C6M3 'CAP_0805-10UF,16V,10%,X6S,C953A':;

SECTION_NUMBER 1
 '@BASEBOARD_FAB2_LIB.BASEBOARD_FAB2(SCH_1):PAGE234_I203@MSTR_DISCRETE.CAP(CHIPS)':
 C_PATH='@baseboard_fab2_lib.baseboard_fab2(sch_1):page234_i203@mstr_discrete.ca~
p(chips)',
 P_PATH='@baseboard_fab2_lib.baseboard_fab2(sch_1):page234_i203@mstr_discrete.ca~
p(chips)',
 PATH='I203',
 DRAWING='@BASEBOARD_FAB2_LIB.BASEBOARD_FAB2(SCH_1):PAGE234',
 TOLERANCE='10%',
 SEC_TYPE='0805',
 MATERIAL='X6S',
 PHYS_PAGE='234',
 XY='(-6375,4150)',
 ROT='0',
 VER='1',
 VALUE='10UF',
 PACK_TYPE='0805',
 PART_NUMBER='C95333-007',
 LOCATION='C6M3',
 SEC='1',
 CDS_LIB='mstr_discrete',
 CDS_PART_NAME='CAP_0805-10UF,16V,10%,X6S,C953A',
 VOLTAGE='16V',
 PRIM_FILE='./archive_libs/mstr_discrete/cap/chips/chips.prt';

PART_NAME
 C6M5 'CAP_0805-10UF,16V,10%,X6S,C953A':;

SECTION_NUMBER 1
 '@BASEBOARD_FAB2_LIB.BASEBOARD_FAB2(SCH_1):PAGE234_I204@MSTR_DISCRETE.CAP(CHIPS)':
 C_PATH='@baseboard_fab2_lib.baseboard_fab2(sch_1):page234_i204@mstr_discrete.ca~
p(chips)',
 P_PATH='@baseboard_fab2_lib.baseboard_fab2(sch_1):page234_i204@mstr_discrete.ca~
p(chips)',
 PATH='I204',
 DRAWING='@BASEBOARD_FAB2_LIB.BASEBOARD_FAB2(SCH_1):PAGE234',
 TOLERANCE='10%',
 SEC_TYPE='0805',
 MATERIAL='X6S',
 PHYS_PAGE='234',
 XY='(-5925,4150)',
 ROT='0',
 VER='1',
 VALUE='10UF',
 PACK_TYPE='0805',
 PART_NUMBER='C95333-007',
 LOCATION='C6M5',
 SEC='1',
 CDS_LIB='mstr_discrete',
 CDS_PART_NAME='CAP_0805-10UF,16V,10%,X6S,C953A',
 VOLTAGE='16V',
 PRIM_FILE='./archive_libs/mstr_discrete/cap/chips/chips.prt';

PART_NAME
 C6M6 'CAP_A_0402V-0.1UF,16V,10%,X7R,A':
 ROOM='DEBUG';

SECTION_NUMBER 1
 '@BASEBOARD_FAB2_LIB.BASEBOARD_FAB2(SCH_1):PAGE113_I250@DEV_DISCRETE.CAP_A(CHIPS)':
 C_PATH='@baseboard_fab2_lib.baseboard_fab2(sch_1):page113_i250@dev_discrete.cap~
_a(chips)',
 P_PATH='@baseboard_fab2_lib.baseboard_fab2(sch_1):page113_i250@dev_discrete.cap~
_a(chips)',
 PATH='I250',
 DRAWING='@BASEBOARD_FAB2_LIB.BASEBOARD_FAB2(SCH_1):PAGE113',
 POP='NOPOP',
 TOLERANCE='10%',
 SEC_TYPE='0402V',
 MATERIAL='X7R',
 BOM_COST='DEBUG',
 PHYS_PAGE='113',
 XY='(2150,1825)',
 ROT='2',
 VER='1',
 VALUE='0.1UF',
 PACK_TYPE='0402V',
 PART_NUMBER='A36096-030',
 LOCATION='C6M6',
 ROOM='DEBUG',
 SEC='1',
 CDS_LIB='dev_discrete',
 CDS_PART_NAME='CAP_A_0402V-0.1UF,16V,10%,X7R,A',
 VOLTAGE='16V',
 PRIM_FILE='./archive_libs/discrete/cap_a/chips/chips.prt';

PART_NAME
 C6N1 'CAPP_3018-470UF,2.5V,20%,ALUM,A':
 GROUP='PWR_BULK_CAP',
 ROOM='PVSA_CPU0_DECAP_VR';

SECTION_NUMBER 1
 '@BASEBOARD_FAB2_LIB.BASEBOARD_FAB2(SCH_1):PAGE205_I12@MSTR_DISCRETE.CAPP(CHIPS)':
 C_PATH='@baseboard_fab2_lib.baseboard_fab2(sch_1):page205_i12@mstr_discrete.cap~
p(chips)',
 P_PATH='@baseboard_fab2_lib.baseboard_fab2(sch_1):page205_i12@mstr_discrete.cap~
p(chips)',
 PATH='I12',
 DRAWING='@BASEBOARD_FAB2_LIB.BASEBOARD_FAB2(SCH_1):PAGE205',
 TOLERANCE='20%',
 SEC_TYPE='3018',
 MATERIAL='ALUM',
 BOM_COST='PROC_VRD_VCCIN_CPU0',
 PHYS_PAGE='205',
 XY='(-2000,1350)',
 ROT='0',
 VER='1',
 VALUE='470UF',
 PACK_TYPE='3018',
 PART_NUMBER='699013-049',
 LOCATION='C6N1',
 ROOM='PVSA_CPU0_DECAP_VR',
 GROUP='PWR_BULK_CAP',
 SEC='1',
 CDS_LIB='mstr_discrete',
 CDS_PART_NAME='CAPP_3018-470UF,2.5V,20%,ALUM,A',
 VOLTAGE='2.5V',
 PRIM_FILE='./archive_libs/mstr_discrete/capp/chips/chips.prt';

PART_NAME
 C6N2 'CAP_0805-10UF,16V,10%,X6S,C953A':
 ROOM='PVSA_CPU0_PWR_VR';

SECTION_NUMBER 1
 '@BASEBOARD_FAB2_LIB.BASEBOARD_FAB2(SCH_1):PAGE205_I33@MSTR_DISCRETE.CAP(CHIPS)':
 C_PATH='@baseboard_fab2_lib.baseboard_fab2(sch_1):page205_i33@mstr_discrete.cap~
(chips)',
 P_PATH='@baseboard_fab2_lib.baseboard_fab2(sch_1):page205_i33@mstr_discrete.cap~
(chips)',
 PATH='I33',
 DRAWING='@BASEBOARD_FAB2_LIB.BASEBOARD_FAB2(SCH_1):PAGE205',
 TOLERANCE='10%',
 SEC_TYPE='0805',
 MATERIAL='X6S',
 PHYS_PAGE='205',
 XY='(-6700,4200)',
 ROT='0',
 VER='1',
 VALUE='10UF',
 PACK_TYPE='0805',
 PART_NUMBER='C95333-007',
 LOCATION='C6N2',
 ROOM='PVSA_CPU0_PWR_VR',
 SEC='1',
 CDS_LIB='mstr_discrete',
 CDS_PART_NAME='CAP_0805-10UF,16V,10%,X6S,C953A',
 VOLTAGE='16V',
 PRIM_FILE='./archive_libs/mstr_discrete/cap/chips/chips.prt';

PART_NAME
 C6N3 'CAP_0805-10UF,16V,10%,X6S,C953A':
 ROOM='PVSA_CPU0_PWR_VR';

SECTION_NUMBER 1
 '@BASEBOARD_FAB2_LIB.BASEBOARD_FAB2(SCH_1):PAGE205_I34@MSTR_DISCRETE.CAP(CHIPS)':
 C_PATH='@baseboard_fab2_lib.baseboard_fab2(sch_1):page205_i34@mstr_discrete.cap~
(chips)',
 P_PATH='@baseboard_fab2_lib.baseboard_fab2(sch_1):page205_i34@mstr_discrete.cap~
(chips)',
 PATH='I34',
 DRAWING='@BASEBOARD_FAB2_LIB.BASEBOARD_FAB2(SCH_1):PAGE205',
 TOLERANCE='10%',
 SEC_TYPE='0805',
 MATERIAL='X6S',
 PHYS_PAGE='205',
 XY='(-6925,4200)',
 ROT='0',
 VER='1',
 VALUE='10UF',
 PACK_TYPE='0805',
 PART_NUMBER='C95333-007',
 LOCATION='C6N3',
 ROOM='PVSA_CPU0_PWR_VR',
 SEC='1',
 CDS_LIB='mstr_discrete',
 CDS_PART_NAME='CAP_0805-10UF,16V,10%,X6S,C953A',
 VOLTAGE='16V',
 PRIM_FILE='./archive_libs/mstr_discrete/cap/chips/chips.prt';

PART_NAME
 C6N4 'CAPP_3018-470UF,2.5V,20%,ALUM,A':
 GROUP='PWR_BULK_CAP',
 ROOM='PVSA_CPU0_DECAP_VR';

SECTION_NUMBER 1
 '@BASEBOARD_FAB2_LIB.BASEBOARD_FAB2(SCH_1):PAGE205_I14@MSTR_DISCRETE.CAPP(CHIPS)':
 C_PATH='@baseboard_fab2_lib.baseboard_fab2(sch_1):page205_i14@mstr_discrete.cap~
p(chips)',
 P_PATH='@baseboard_fab2_lib.baseboard_fab2(sch_1):page205_i14@mstr_discrete.cap~
p(chips)',
 PATH='I14',
 DRAWING='@BASEBOARD_FAB2_LIB.BASEBOARD_FAB2(SCH_1):PAGE205',
 TOLERANCE='20%',
 SEC_TYPE='3018',
 MATERIAL='ALUM',
 BOM_COST='PROC_VRD_VCCIN_CPU0',
 PHYS_PAGE='205',
 XY='(-2650,1350)',
 ROT='2',
 VER='1',
 VALUE='470UF',
 PACK_TYPE='3018',
 PART_NUMBER='699013-049',
 LOCATION='C6N4',
 ROOM='PVSA_CPU0_DECAP_VR',
 GROUP='PWR_BULK_CAP',
 SEC='1',
 CDS_LIB='mstr_discrete',
 CDS_PART_NAME='CAPP_3018-470UF,2.5V,20%,ALUM,A',
 VOLTAGE='2.5V',
 PRIM_FILE='./archive_libs/mstr_discrete/capp/chips/chips.prt';

PART_NAME
 C6N5 'CAPP_3018-68UF,16V,20%,TANT,72A':;

SECTION_NUMBER 1
 '@BASEBOARD_FAB2_LIB.BASEBOARD_FAB2(SCH_1):PAGE195_I109@MSTR_DISCRETE.CAPP(CHIPS)':
 C_PATH='@baseboard_fab2_lib.baseboard_fab2(sch_1):page195_i109@mstr_discrete.ca~
pp(chips)',
 P_PATH='@baseboard_fab2_lib.baseboard_fab2(sch_1):page195_i109@mstr_discrete.ca~
pp(chips)',
 PATH='I109',
 DRAWING='@BASEBOARD_FAB2_LIB.BASEBOARD_FAB2(SCH_1):PAGE195',
 TOLERANCE='20%',
 SEC_TYPE='3018',
 MATERIAL='TANT',
 PHYS_PAGE='195',
 XY='(-6525,1950)',
 ROT='0',
 VER='1',
 VALUE='68UF',
 PACK_TYPE='3018',
 PART_NUMBER='724613-112',
 LOCATION='C6N5',
 SEC='1',
 CDS_LIB='mstr_discrete',
 CDS_PART_NAME='CAPP_3018-68UF,16V,20%,TANT,72A',
 VOLTAGE='16V',
 PRIM_FILE='./archive_libs/mstr_discrete/capp/chips/chips.prt';

PART_NAME
 C6N6 'CAP_0805-10UF,16V,10%,X6S,C953A':
 ROOM='PVSA_CPU0_PWR_VR';

SECTION_NUMBER 1
 '@BASEBOARD_FAB2_LIB.BASEBOARD_FAB2(SCH_1):PAGE205_I35@MSTR_DISCRETE.CAP(CHIPS)':
 C_PATH='@baseboard_fab2_lib.baseboard_fab2(sch_1):page205_i35@mstr_discrete.cap~
(chips)',
 P_PATH='@baseboard_fab2_lib.baseboard_fab2(sch_1):page205_i35@mstr_discrete.cap~
(chips)',
 PATH='I35',
 DRAWING='@BASEBOARD_FAB2_LIB.BASEBOARD_FAB2(SCH_1):PAGE205',
 TOLERANCE='10%',
 SEC_TYPE='0805',
 MATERIAL='X6S',
 PHYS_PAGE='205',
 XY='(-7175,4200)',
 ROT='0',
 VER='1',
 VALUE='10UF',
 PACK_TYPE='0805',
 PART_NUMBER='C95333-007',
 LOCATION='C6N6',
 ROOM='PVSA_CPU0_PWR_VR',
 SEC='1',
 CDS_LIB='mstr_discrete',
 CDS_PART_NAME='CAP_0805-10UF,16V,10%,X6S,C953A',
 VOLTAGE='16V',
 PRIM_FILE='./archive_libs/mstr_discrete/cap/chips/chips.prt';

PART_NAME
 C6N7 'CAP_A_0603V-22.0UF,4V,20%,X6S,A':
 ROOM='PVSA_CPU0_PWR_VR';

SECTION_NUMBER 1
 '@BASEBOARD_FAB2_LIB.BASEBOARD_FAB2(SCH_1):PAGE205_I5@DEV_DISCRETE.CAP_A(CHIPS)':
 C_PATH='@baseboard_fab2_lib.baseboard_fab2(sch_1):page205_i5@dev_discrete.cap_a~
(chips)',
 P_PATH='@baseboard_fab2_lib.baseboard_fab2(sch_1):page205_i5@dev_discrete.cap_a~
(chips)',
 PATH='I5',
 DRAWING='@BASEBOARD_FAB2_LIB.BASEBOARD_FAB2(SCH_1):PAGE205',
 TOLERANCE='20%',
 SEC_TYPE='0603V',
 MATERIAL='X6S',
 BOM_COST='PROC_VRD_VCCIN_CPU0',
 PHYS_PAGE='205',
 XY='(-950,3075)',
 ROT='0',
 VER='1',
 VALUE='22.0UF',
 PACK_TYPE='0603V',
 PART_NUMBER='E15431-004',
 LOCATION='C6N7',
 ROOM='PVSA_CPU0_PWR_VR',
 SEC='1',
 CDS_LIB='dev_discrete',
 CDS_PART_NAME='CAP_A_0603V-22.0UF,4V,20%,X6S,A',
 VOLTAGE='4V',
 PRIM_FILE='./archive_libs/discrete/cap_a/chips/chips.prt';

PART_NAME
 C6N8 'CAP_0805-10UF,16V,10%,X6S,C953A':
 ROOM='PVCCIN_CPU0_PWR_VR';

SECTION_NUMBER 1
 '@BASEBOARD_FAB2_LIB.BASEBOARD_FAB2(SCH_1):PAGE202_I51@MSTR_DISCRETE.CAP(CHIPS)':
 C_PATH='@baseboard_fab2_lib.baseboard_fab2(sch_1):page202_i51@mstr_discrete.cap~
(chips)',
 P_PATH='@baseboard_fab2_lib.baseboard_fab2(sch_1):page202_i51@mstr_discrete.cap~
(chips)',
 PATH='I51',
 DRAWING='@BASEBOARD_FAB2_LIB.BASEBOARD_FAB2(SCH_1):PAGE202',
 TOLERANCE='10%',
 SEC_TYPE='0805',
 MATERIAL='X6S',
 PHYS_PAGE='202',
 XY='(-7175,1475)',
 ROT='0',
 VER='1',
 VALUE='10UF',
 PACK_TYPE='0805',
 PART_NUMBER='C95333-007',
 LOCATION='C6N8',
 ROOM='PVCCIN_CPU0_PWR_VR',
 SEC='1',
 CDS_LIB='mstr_discrete',
 CDS_PART_NAME='CAP_0805-10UF,16V,10%,X6S,C953A',
 VOLTAGE='16V',
 PRIM_FILE='./archive_libs/mstr_discrete/cap/chips/chips.prt';

PART_NAME
 C6N9 'CAPP_3018-470UF,2.5V,20%,ALUM,A':
 GROUP='PWR_BULK_CAP',
 ROOM='PVCCIN_CPU0_DECAP_VR';

SECTION_NUMBER 1
 '@BASEBOARD_FAB2_LIB.BASEBOARD_FAB2(SCH_1):PAGE203_I34@MSTR_DISCRETE.CAPP(CHIPS)':
 C_PATH='@baseboard_fab2_lib.baseboard_fab2(sch_1):page203_i34@mstr_discrete.cap~
p(chips)',
 P_PATH='@baseboard_fab2_lib.baseboard_fab2(sch_1):page203_i34@mstr_discrete.cap~
p(chips)',
 PATH='I34',
 DRAWING='@BASEBOARD_FAB2_LIB.BASEBOARD_FAB2(SCH_1):PAGE203',
 TOLERANCE='20%',
 SEC_TYPE='3018',
 MATERIAL='ALUM',
 BOM_COST='PROC_VRD_VCCIN_CPU0',
 PHYS_PAGE='203',
 XY='(-3625,2600)',
 ROT='0',
 VER='1',
 VALUE='470UF',
 PACK_TYPE='3018',
 PART_NUMBER='699013-049',
 LOCATION='C6N9',
 ROOM='PVCCIN_CPU0_DECAP_VR',
 GROUP='PWR_BULK_CAP',
 SEC='1',
 CDS_LIB='mstr_discrete',
 CDS_PART_NAME='CAPP_3018-470UF,2.5V,20%,ALUM,A',
 VOLTAGE='2.5V',
 PRIM_FILE='./archive_libs/mstr_discrete/capp/chips/chips.prt';

PART_NAME
 C6N10 'CAP_0805-10UF,16V,10%,X6S,C953A':
 ROOM='PVCCIN_CPU0_PWR_VR';

SECTION_NUMBER 1
 '@BASEBOARD_FAB2_LIB.BASEBOARD_FAB2(SCH_1):PAGE204_I37@MSTR_DISCRETE.CAP(CHIPS)':
 C_PATH='@baseboard_fab2_lib.baseboard_fab2(sch_1):page204_i37@mstr_discrete.cap~
(chips)',
 P_PATH='@baseboard_fab2_lib.baseboard_fab2(sch_1):page204_i37@mstr_discrete.cap~
(chips)',
 PATH='I37',
 DRAWING='@BASEBOARD_FAB2_LIB.BASEBOARD_FAB2(SCH_1):PAGE204',
 TOLERANCE='10%',
 SEC_TYPE='0805',
 MATERIAL='X6S',
 PHYS_PAGE='204',
 XY='(-6600,4175)',
 ROT='0',
 VER='1',
 VALUE='10UF',
 PACK_TYPE='0805',
 PART_NUMBER='C95333-007',
 LOCATION='C6N10',
 ROOM='PVCCIN_CPU0_PWR_VR',
 SEC='1',
 CDS_LIB='mstr_discrete',
 CDS_PART_NAME='CAP_0805-10UF,16V,10%,X6S,C953A',
 VOLTAGE='16V',
 PRIM_FILE='./archive_libs/mstr_discrete/cap/chips/chips.prt';

PART_NAME
 C6N11 'CAP_0805-10UF,16V,10%,X6S,C953A':
 ROOM='PVCCIN_CPU0_PWR_VR';

SECTION_NUMBER 1
 '@BASEBOARD_FAB2_LIB.BASEBOARD_FAB2(SCH_1):PAGE204_I42@MSTR_DISCRETE.CAP(CHIPS)':
 C_PATH='@baseboard_fab2_lib.baseboard_fab2(sch_1):page204_i42@mstr_discrete.cap~
(chips)',
 P_PATH='@baseboard_fab2_lib.baseboard_fab2(sch_1):page204_i42@mstr_discrete.cap~
(chips)',
 PATH='I42',
 DRAWING='@BASEBOARD_FAB2_LIB.BASEBOARD_FAB2(SCH_1):PAGE204',
 TOLERANCE='10%',
 SEC_TYPE='0805',
 MATERIAL='X6S',
 PHYS_PAGE='204',
 XY='(-7200,4175)',
 ROT='0',
 VER='1',
 VALUE='10UF',
 PACK_TYPE='0805',
 PART_NUMBER='C95333-007',
 LOCATION='C6N11',
 ROOM='PVCCIN_CPU0_PWR_VR',
 SEC='1',
 CDS_LIB='mstr_discrete',
 CDS_PART_NAME='CAP_0805-10UF,16V,10%,X6S,C953A',
 VOLTAGE='16V',
 PRIM_FILE='./archive_libs/mstr_discrete/cap/chips/chips.prt';

PART_NAME
 C6P3 'CAP_A_0603V-22.0UF,4V,20%,X6S,A':
 GROUP='PWR_MLCC_CAP',
 ROOM='PVCCIN_CPU0_PWR_VR';

SECTION_NUMBER 1
 '@BASEBOARD_FAB2_LIB.BASEBOARD_FAB2(SCH_1):PAGE203_I25@DEV_DISCRETE.CAP_A(CHIPS)':
 C_PATH='@baseboard_fab2_lib.baseboard_fab2(sch_1):page203_i25@dev_discrete.cap_~
a(chips)',
 P_PATH='@baseboard_fab2_lib.baseboard_fab2(sch_1):page203_i25@dev_discrete.cap_~
a(chips)',
 PATH='I25',
 DRAWING='@BASEBOARD_FAB2_LIB.BASEBOARD_FAB2(SCH_1):PAGE203',
 TOLERANCE='20%',
 SEC_TYPE='0603V',
 MATERIAL='X6S',
 BOM_COST='PROC_VRD_VCCIN_CPU0',
 PHYS_PAGE='203',
 XY='(-700,725)',
 ROT='0',
 VER='1',
 VALUE='22.0UF',
 PACK_TYPE='0603V',
 PART_NUMBER='E15431-004',
 LOCATION='C6P3',
 ROOM='PVCCIN_CPU0_PWR_VR',
 GROUP='PWR_MLCC_CAP',
 SEC='1',
 CDS_LIB='dev_discrete',
 CDS_PART_NAME='CAP_A_0603V-22.0UF,4V,20%,X6S,A',
 VOLTAGE='4V',
 PRIM_FILE='./archive_libs/discrete/cap_a/chips/chips.prt';

PART_NAME
 C6P4 'CAP_A_0402V-0.1UF,16V,10%,X7R,A':
 ROOM='DB1200ZL';

SECTION_NUMBER 1
 '@BASEBOARD_FAB2_LIB.BASEBOARD_FAB2(SCH_1):PAGE102_I11@DEV_DISCRETE.CAP_A(CHIPS)':
 C_PATH='@baseboard_fab2_lib.baseboard_fab2(sch_1):page102_i11@dev_discrete.cap_~
a(chips)',
 P_PATH='@baseboard_fab2_lib.baseboard_fab2(sch_1):page102_i11@dev_discrete.cap_~
a(chips)',
 PATH='I11',
 DRAWING='@BASEBOARD_FAB2_LIB.BASEBOARD_FAB2(SCH_1):PAGE102',
 TOLERANCE='10%',
 SEC_TYPE='0402V',
 MATERIAL='X7R',
 BOM_COST='SYS_CLOCK',
 PHYS_PAGE='102',
 XY='(2575,900)',
 ROT='0',
 VER='1',
 VALUE='0.1UF',
 PACK_TYPE='0402V',
 PART_NUMBER='A36096-030',
 LOCATION='C6P4',
 ROOM='DB1200ZL',
 SEC='1',
 CDS_LIB='dev_discrete',
 CDS_PART_NAME='CAP_A_0402V-0.1UF,16V,10%,X7R,A',
 VOLTAGE='16V',
 PRIM_FILE='./archive_libs/discrete/cap_a/chips/chips.prt';

PART_NAME
 C6P5 'CAP_A_0402V-0.1UF,16V,10%,X7R,A':
 ROOM='DB1200ZL';

SECTION_NUMBER 1
 '@BASEBOARD_FAB2_LIB.BASEBOARD_FAB2(SCH_1):PAGE102_I14@DEV_DISCRETE.CAP_A(CHIPS)':
 C_PATH='@baseboard_fab2_lib.baseboard_fab2(sch_1):page102_i14@dev_discrete.cap_~
a(chips)',
 P_PATH='@baseboard_fab2_lib.baseboard_fab2(sch_1):page102_i14@dev_discrete.cap_~
a(chips)',
 PATH='I14',
 DRAWING='@BASEBOARD_FAB2_LIB.BASEBOARD_FAB2(SCH_1):PAGE102',
 TOLERANCE='10%',
 SEC_TYPE='0402V',
 MATERIAL='X7R',
 BOM_COST='SYS_CLOCK',
 PHYS_PAGE='102',
 XY='(3275,900)',
 ROT='0',
 VER='1',
 VALUE='0.1UF',
 PACK_TYPE='0402V',
 PART_NUMBER='A36096-030',
 LOCATION='C6P5',
 ROOM='DB1200ZL',
 SEC='1',
 CDS_LIB='dev_discrete',
 CDS_PART_NAME='CAP_A_0402V-0.1UF,16V,10%,X7R,A',
 VOLTAGE='16V',
 PRIM_FILE='./archive_libs/discrete/cap_a/chips/chips.prt';

PART_NAME
 C6P6 'CAP_A_0402V-0.1UF,16V,10%,X7R,A':
 ROOM='DB1200ZL';

SECTION_NUMBER 1
 '@BASEBOARD_FAB2_LIB.BASEBOARD_FAB2(SCH_1):PAGE102_I12@DEV_DISCRETE.CAP_A(CHIPS)':
 C_PATH='@baseboard_fab2_lib.baseboard_fab2(sch_1):page102_i12@dev_discrete.cap_~
a(chips)',
 P_PATH='@baseboard_fab2_lib.baseboard_fab2(sch_1):page102_i12@dev_discrete.cap_~
a(chips)',
 PATH='I12',
 DRAWING='@BASEBOARD_FAB2_LIB.BASEBOARD_FAB2(SCH_1):PAGE102',
 TOLERANCE='10%',
 SEC_TYPE='0402V',
 MATERIAL='X7R',
 BOM_COST='SYS_CLOCK',
 PHYS_PAGE='102',
 XY='(2825,900)',
 ROT='0',
 VER='1',
 VALUE='0.1UF',
 PACK_TYPE='0402V',
 PART_NUMBER='A36096-030',
 LOCATION='C6P6',
 ROOM='DB1200ZL',
 SEC='1',
 CDS_LIB='dev_discrete',
 CDS_PART_NAME='CAP_A_0402V-0.1UF,16V,10%,X7R,A',
 VOLTAGE='16V',
 PRIM_FILE='./archive_libs/discrete/cap_a/chips/chips.prt';

PART_NAME
 C6P7 'CAP_0805-10UF,16V,10%,X6S,C953A':
 ROOM='PVCCIN_CPU0_PWR_VR';

SECTION_NUMBER 1
 '@BASEBOARD_FAB2_LIB.BASEBOARD_FAB2(SCH_1):PAGE203_I59@MSTR_DISCRETE.CAP(CHIPS)':
 C_PATH='@baseboard_fab2_lib.baseboard_fab2(sch_1):page203_i59@mstr_discrete.cap~
(chips)',
 P_PATH='@baseboard_fab2_lib.baseboard_fab2(sch_1):page203_i59@mstr_discrete.cap~
(chips)',
 PATH='I59',
 DRAWING='@BASEBOARD_FAB2_LIB.BASEBOARD_FAB2(SCH_1):PAGE203',
 TOLERANCE='10%',
 SEC_TYPE='0805',
 MATERIAL='X6S',
 PHYS_PAGE='203',
 XY='(-7100,1475)',
 ROT='0',
 VER='1',
 VALUE='10UF',
 PACK_TYPE='0805',
 PART_NUMBER='C95333-007',
 LOCATION='C6P7',
 ROOM='PVCCIN_CPU0_PWR_VR',
 SEC='1',
 CDS_LIB='mstr_discrete',
 CDS_PART_NAME='CAP_0805-10UF,16V,10%,X6S,C953A',
 VOLTAGE='16V',
 PRIM_FILE='./archive_libs/mstr_discrete/cap/chips/chips.prt';

PART_NAME
 C6P8 'CAPP_3018-470UF,2.5V,20%,ALUM,A':
 GROUP='PWR_BULK_CAP',
 ROOM='PVCCIN_CPU0_DECAP_VR';

SECTION_NUMBER 1
 '@BASEBOARD_FAB2_LIB.BASEBOARD_FAB2(SCH_1):PAGE203_I32@MSTR_DISCRETE.CAPP(CHIPS)':
 C_PATH='@baseboard_fab2_lib.baseboard_fab2(sch_1):page203_i32@mstr_discrete.cap~
p(chips)',
 P_PATH='@baseboard_fab2_lib.baseboard_fab2(sch_1):page203_i32@mstr_discrete.cap~
p(chips)',
 PATH='I32',
 DRAWING='@BASEBOARD_FAB2_LIB.BASEBOARD_FAB2(SCH_1):PAGE203',
 TOLERANCE='20%',
 SEC_TYPE='3018',
 MATERIAL='ALUM',
 BOM_COST='PROC_VRD_VCCIN_CPU0',
 PHYS_PAGE='203',
 XY='(-3200,2600)',
 ROT='0',
 VER='1',
 VALUE='470UF',
 PACK_TYPE='3018',
 PART_NUMBER='699013-049',
 LOCATION='C6P8',
 ROOM='PVCCIN_CPU0_DECAP_VR',
 GROUP='PWR_BULK_CAP',
 SEC='1',
 CDS_LIB='mstr_discrete',
 CDS_PART_NAME='CAPP_3018-470UF,2.5V,20%,ALUM,A',
 VOLTAGE='2.5V',
 PRIM_FILE='./archive_libs/mstr_discrete/capp/chips/chips.prt';

PART_NAME
 C6P9 'CAP_A_0402V-0.1UF,16V,10%,X7R,A':
 ROOM='DB1200ZL';

SECTION_NUMBER 1
 '@BASEBOARD_FAB2_LIB.BASEBOARD_FAB2(SCH_1):PAGE102_I79@DEV_DISCRETE.CAP_A(CHIPS)':
 C_PATH='@baseboard_fab2_lib.baseboard_fab2(sch_1):page102_i79@dev_discrete.cap_~
a(chips)',
 P_PATH='@baseboard_fab2_lib.baseboard_fab2(sch_1):page102_i79@dev_discrete.cap_~
a(chips)',
 PATH='I79',
 DRAWING='@BASEBOARD_FAB2_LIB.BASEBOARD_FAB2(SCH_1):PAGE102',
 TOLERANCE='10%',
 SEC_TYPE='0402V',
 MATERIAL='X7R',
 BOM_COST='SYS_CLOCK',
 PHYS_PAGE='102',
 XY='(2275,900)',
 ROT='0',
 VER='1',
 VALUE='0.1UF',
 PACK_TYPE='0402V',
 PART_NUMBER='A36096-030',
 LOCATION='C6P9',
 ROOM='DB1200ZL',
 SEC='1',
 CDS_LIB='dev_discrete',
 CDS_PART_NAME='CAP_A_0402V-0.1UF,16V,10%,X7R,A',
 VOLTAGE='16V',
 PRIM_FILE='./archive_libs/discrete/cap_a/chips/chips.prt';

PART_NAME
 C6P10 'CAP_A_0402V-0.1UF,16V,10%,X7R,A':
 ROOM='DB1200ZL';

SECTION_NUMBER 1
 '@BASEBOARD_FAB2_LIB.BASEBOARD_FAB2(SCH_1):PAGE102_I13@DEV_DISCRETE.CAP_A(CHIPS)':
 C_PATH='@baseboard_fab2_lib.baseboard_fab2(sch_1):page102_i13@dev_discrete.cap_~
a(chips)',
 P_PATH='@baseboard_fab2_lib.baseboard_fab2(sch_1):page102_i13@dev_discrete.cap_~
a(chips)',
 PATH='I13',
 DRAWING='@BASEBOARD_FAB2_LIB.BASEBOARD_FAB2(SCH_1):PAGE102',
 TOLERANCE='10%',
 SEC_TYPE='0402V',
 MATERIAL='X7R',
 BOM_COST='SYS_CLOCK',
 PHYS_PAGE='102',
 XY='(3050,900)',
 ROT='0',
 VER='1',
 VALUE='0.1UF',
 PACK_TYPE='0402V',
 PART_NUMBER='A36096-030',
 LOCATION='C6P10',
 ROOM='DB1200ZL',
 SEC='1',
 CDS_LIB='dev_discrete',
 CDS_PART_NAME='CAP_A_0402V-0.1UF,16V,10%,X7R,A',
 VOLTAGE='16V',
 PRIM_FILE='./archive_libs/discrete/cap_a/chips/chips.prt';

PART_NAME
 C6P11 'CAP_A_0402V-0.1UF,16V,10%,X7R,A':
 ROOM='DB1200ZL';

SECTION_NUMBER 1
 '@BASEBOARD_FAB2_LIB.BASEBOARD_FAB2(SCH_1):PAGE102_I16@DEV_DISCRETE.CAP_A(CHIPS)':
 C_PATH='@baseboard_fab2_lib.baseboard_fab2(sch_1):page102_i16@dev_discrete.cap_~
a(chips)',
 P_PATH='@baseboard_fab2_lib.baseboard_fab2(sch_1):page102_i16@dev_discrete.cap_~
a(chips)',
 PATH='I16',
 DRAWING='@BASEBOARD_FAB2_LIB.BASEBOARD_FAB2(SCH_1):PAGE102',
 TOLERANCE='10%',
 SEC_TYPE='0402V',
 MATERIAL='X7R',
 BOM_COST='SYS_CLOCK',
 PHYS_PAGE='102',
 XY='(3700,900)',
 ROT='0',
 VER='1',
 VALUE='0.1UF',
 PACK_TYPE='0402V',
 PART_NUMBER='A36096-030',
 LOCATION='C6P11',
 ROOM='DB1200ZL',
 SEC='1',
 CDS_LIB='dev_discrete',
 CDS_PART_NAME='CAP_A_0402V-0.1UF,16V,10%,X7R,A',
 VOLTAGE='16V',
 PRIM_FILE='./archive_libs/discrete/cap_a/chips/chips.prt';

PART_NAME
 C6P12 'CAP_A_0402V-0.1UF,16V,10%,X7R,A':
 ROOM='DB1200ZL';

SECTION_NUMBER 1
 '@BASEBOARD_FAB2_LIB.BASEBOARD_FAB2(SCH_1):PAGE102_I15@DEV_DISCRETE.CAP_A(CHIPS)':
 C_PATH='@baseboard_fab2_lib.baseboard_fab2(sch_1):page102_i15@dev_discrete.cap_~
a(chips)',
 P_PATH='@baseboard_fab2_lib.baseboard_fab2(sch_1):page102_i15@dev_discrete.cap_~
a(chips)',
 PATH='I15',
 DRAWING='@BASEBOARD_FAB2_LIB.BASEBOARD_FAB2(SCH_1):PAGE102',
 TOLERANCE='10%',
 SEC_TYPE='0402V',
 MATERIAL='X7R',
 BOM_COST='SYS_CLOCK',
 PHYS_PAGE='102',
 XY='(3475,900)',
 ROT='0',
 VER='1',
 VALUE='0.1UF',
 PACK_TYPE='0402V',
 PART_NUMBER='A36096-030',
 LOCATION='C6P12',
 ROOM='DB1200ZL',
 SEC='1',
 CDS_LIB='dev_discrete',
 CDS_PART_NAME='CAP_A_0402V-0.1UF,16V,10%,X7R,A',
 VOLTAGE='16V',
 PRIM_FILE='./archive_libs/discrete/cap_a/chips/chips.prt';

PART_NAME
 C6P13 'CAP_0805-10UF,16V,10%,X6S,C953A':
 ROOM='PVCCIN_CPU0_PWR_VR';

SECTION_NUMBER 1
 '@BASEBOARD_FAB2_LIB.BASEBOARD_FAB2(SCH_1):PAGE202_I38@MSTR_DISCRETE.CAP(CHIPS)':
 C_PATH='@baseboard_fab2_lib.baseboard_fab2(sch_1):page202_i38@mstr_discrete.cap~
(chips)',
 P_PATH='@baseboard_fab2_lib.baseboard_fab2(sch_1):page202_i38@mstr_discrete.cap~
(chips)',
 PATH='I38',
 DRAWING='@BASEBOARD_FAB2_LIB.BASEBOARD_FAB2(SCH_1):PAGE202',
 TOLERANCE='10%',
 SEC_TYPE='0805',
 MATERIAL='X6S',
 PHYS_PAGE='202',
 XY='(-6825,4075)',
 ROT='0',
 VER='1',
 VALUE='10UF',
 PACK_TYPE='0805',
 PART_NUMBER='C95333-007',
 LOCATION='C6P13',
 ROOM='PVCCIN_CPU0_PWR_VR',
 SEC='1',
 CDS_LIB='mstr_discrete',
 CDS_PART_NAME='CAP_0805-10UF,16V,10%,X6S,C953A',
 VOLTAGE='16V',
 PRIM_FILE='./archive_libs/mstr_discrete/cap/chips/chips.prt';

PART_NAME
 C6P14 'CAPP_3018-470UF,2.5V,20%,ALUM,A':
 GROUP='PWR_BULK_CAP',
 ROOM='PVCCIN_CPU0_DECAP_VR';

SECTION_NUMBER 1
 '@BASEBOARD_FAB2_LIB.BASEBOARD_FAB2(SCH_1):PAGE203_I29@MSTR_DISCRETE.CAPP(CHIPS)':
 C_PATH='@baseboard_fab2_lib.baseboard_fab2(sch_1):page203_i29@mstr_discrete.cap~
p(chips)',
 P_PATH='@baseboard_fab2_lib.baseboard_fab2(sch_1):page203_i29@mstr_discrete.cap~
p(chips)',
 PATH='I29',
 DRAWING='@BASEBOARD_FAB2_LIB.BASEBOARD_FAB2(SCH_1):PAGE203',
 TOLERANCE='20%',
 SEC_TYPE='3018',
 MATERIAL='ALUM',
 BOM_COST='PROC_VRD_VCCIN_CPU0',
 PHYS_PAGE='203',
 XY='(-2300,2600)',
 ROT='0',
 VER='1',
 VALUE='470UF',
 PACK_TYPE='3018',
 PART_NUMBER='699013-049',
 LOCATION='C6P14',
 ROOM='PVCCIN_CPU0_DECAP_VR',
 GROUP='PWR_BULK_CAP',
 SEC='1',
 CDS_LIB='mstr_discrete',
 CDS_PART_NAME='CAPP_3018-470UF,2.5V,20%,ALUM,A',
 VOLTAGE='2.5V',
 PRIM_FILE='./archive_libs/mstr_discrete/capp/chips/chips.prt';

PART_NAME
 C6P15 'CAP_0805-10UF,16V,10%,X6S,C953A':
 ROOM='PVCCIN_CPU0_PWR_VR';

SECTION_NUMBER 1
 '@BASEBOARD_FAB2_LIB.BASEBOARD_FAB2(SCH_1):PAGE203_I58@MSTR_DISCRETE.CAP(CHIPS)':
 C_PATH='@baseboard_fab2_lib.baseboard_fab2(sch_1):page203_i58@mstr_discrete.cap~
(chips)',
 P_PATH='@baseboard_fab2_lib.baseboard_fab2(sch_1):page203_i58@mstr_discrete.cap~
(chips)',
 PATH='I58',
 DRAWING='@BASEBOARD_FAB2_LIB.BASEBOARD_FAB2(SCH_1):PAGE203',
 TOLERANCE='10%',
 SEC_TYPE='0805',
 MATERIAL='X6S',
 PHYS_PAGE='203',
 XY='(-6825,1475)',
 ROT='0',
 VER='1',
 VALUE='10UF',
 PACK_TYPE='0805',
 PART_NUMBER='C95333-007',
 LOCATION='C6P15',
 ROOM='PVCCIN_CPU0_PWR_VR',
 SEC='1',
 CDS_LIB='mstr_discrete',
 CDS_PART_NAME='CAP_0805-10UF,16V,10%,X6S,C953A',
 VOLTAGE='16V',
 PRIM_FILE='./archive_libs/mstr_discrete/cap/chips/chips.prt';

PART_NAME
 C6P16 'CAP_A_0603V-22.0UF,4V,20%,X6S,A':
 GROUP='PWR_MLCC_CAP';

SECTION_NUMBER 1
 '@BASEBOARD_FAB2_LIB.BASEBOARD_FAB2(SCH_1):PAGE202_I62@DEV_DISCRETE.CAP_A(CHIPS)':
 C_PATH='@baseboard_fab2_lib.baseboard_fab2(sch_1):page202_i62@dev_discrete.cap_~
a(chips)',
 P_PATH='@baseboard_fab2_lib.baseboard_fab2(sch_1):page202_i62@dev_discrete.cap_~
a(chips)',
 PATH='I62',
 DRAWING='@BASEBOARD_FAB2_LIB.BASEBOARD_FAB2(SCH_1):PAGE202',
 TOLERANCE='20%',
 SEC_TYPE='0603V',
 MATERIAL='X6S',
 PHYS_PAGE='202',
 XY='(-500,750)',
 ROT='0',
 VER='1',
 VALUE='22.0UF',
 PACK_TYPE='0603V',
 PART_NUMBER='E15431-004',
 LOCATION='C6P16',
 GROUP='PWR_MLCC_CAP',
 SEC='1',
 CDS_LIB='dev_discrete',
 CDS_PART_NAME='CAP_A_0603V-22.0UF,4V,20%,X6S,A',
 VOLTAGE='4V',
 PRIM_FILE='./archive_libs/discrete/cap_a/chips/chips.prt';

PART_NAME
 C6P17 'CAP_0805-10UF,16V,10%,X6S,C953A':
 ROOM='PVCCIN_CPU0_PWR_VR';

SECTION_NUMBER 1
 '@BASEBOARD_FAB2_LIB.BASEBOARD_FAB2(SCH_1):PAGE204_I38@MSTR_DISCRETE.CAP(CHIPS)':
 C_PATH='@baseboard_fab2_lib.baseboard_fab2(sch_1):page204_i38@mstr_discrete.cap~
(chips)',
 P_PATH='@baseboard_fab2_lib.baseboard_fab2(sch_1):page204_i38@mstr_discrete.cap~
(chips)',
 PATH='I38',
 DRAWING='@BASEBOARD_FAB2_LIB.BASEBOARD_FAB2(SCH_1):PAGE204',
 TOLERANCE='10%',
 SEC_TYPE='0805',
 MATERIAL='X6S',
 PHYS_PAGE='204',
 XY='(-6900,4175)',
 ROT='0',
 VER='1',
 VALUE='10UF',
 PACK_TYPE='0805',
 PART_NUMBER='C95333-007',
 LOCATION='C6P17',
 ROOM='PVCCIN_CPU0_PWR_VR',
 SEC='1',
 CDS_LIB='mstr_discrete',
 CDS_PART_NAME='CAP_0805-10UF,16V,10%,X6S,C953A',
 VOLTAGE='16V',
 PRIM_FILE='./archive_libs/mstr_discrete/cap/chips/chips.prt';

PART_NAME
 C6P18 'CAPP_3018-470UF,2.5V,20%,ALUM,A':
 GROUP='PWR_BULK_CAP',
 ROOM='PVCCIN_CPU0_DECAP_VR';

SECTION_NUMBER 1
 '@BASEBOARD_FAB2_LIB.BASEBOARD_FAB2(SCH_1):PAGE203_I30@MSTR_DISCRETE.CAPP(CHIPS)':
 C_PATH='@baseboard_fab2_lib.baseboard_fab2(sch_1):page203_i30@mstr_discrete.cap~
p(chips)',
 P_PATH='@baseboard_fab2_lib.baseboard_fab2(sch_1):page203_i30@mstr_discrete.cap~
p(chips)',
 PATH='I30',
 DRAWING='@BASEBOARD_FAB2_LIB.BASEBOARD_FAB2(SCH_1):PAGE203',
 TOLERANCE='20%',
 SEC_TYPE='3018',
 MATERIAL='ALUM',
 BOM_COST='PROC_VRD_VCCIN_CPU0',
 PHYS_PAGE='203',
 XY='(-2750,2600)',
 ROT='0',
 VER='1',
 VALUE='470UF',
 PACK_TYPE='3018',
 PART_NUMBER='699013-049',
 LOCATION='C6P18',
 ROOM='PVCCIN_CPU0_DECAP_VR',
 GROUP='PWR_BULK_CAP',
 SEC='1',
 CDS_LIB='mstr_discrete',
 CDS_PART_NAME='CAPP_3018-470UF,2.5V,20%,ALUM,A',
 VOLTAGE='2.5V',
 PRIM_FILE='./archive_libs/mstr_discrete/capp/chips/chips.prt';

PART_NAME
 C6P19 'CAP_0805-10UF,16V,10%,X6S,C953A':
 ROOM='PVCCIN_CPU0_PWR_VR';

SECTION_NUMBER 1
 '@BASEBOARD_FAB2_LIB.BASEBOARD_FAB2(SCH_1):PAGE203_I54@MSTR_DISCRETE.CAP(CHIPS)':
 C_PATH='@baseboard_fab2_lib.baseboard_fab2(sch_1):page203_i54@mstr_discrete.cap~
(chips)',
 P_PATH='@baseboard_fab2_lib.baseboard_fab2(sch_1):page203_i54@mstr_discrete.cap~
(chips)',
 PATH='I54',
 DRAWING='@BASEBOARD_FAB2_LIB.BASEBOARD_FAB2(SCH_1):PAGE203',
 TOLERANCE='10%',
 SEC_TYPE='0805',
 MATERIAL='X6S',
 PHYS_PAGE='203',
 XY='(-7000,4175)',
 ROT='0',
 VER='1',
 VALUE='10UF',
 PACK_TYPE='0805',
 PART_NUMBER='C95333-007',
 LOCATION='C6P19',
 ROOM='PVCCIN_CPU0_PWR_VR',
 SEC='1',
 CDS_LIB='mstr_discrete',
 CDS_PART_NAME='CAP_0805-10UF,16V,10%,X6S,C953A',
 VOLTAGE='16V',
 PRIM_FILE='./archive_libs/mstr_discrete/cap/chips/chips.prt';

PART_NAME
 C6P20 'CAP_0805-10UF,16V,10%,X6S,C953A':
 ROOM='PVCCIN_CPU0_PWR_VR';

SECTION_NUMBER 1
 '@BASEBOARD_FAB2_LIB.BASEBOARD_FAB2(SCH_1):PAGE203_I57@MSTR_DISCRETE.CAP(CHIPS)':
 C_PATH='@baseboard_fab2_lib.baseboard_fab2(sch_1):page203_i57@mstr_discrete.cap~
(chips)',
 P_PATH='@baseboard_fab2_lib.baseboard_fab2(sch_1):page203_i57@mstr_discrete.cap~
(chips)',
 PATH='I57',
 DRAWING='@BASEBOARD_FAB2_LIB.BASEBOARD_FAB2(SCH_1):PAGE203',
 TOLERANCE='10%',
 SEC_TYPE='0805',
 MATERIAL='X6S',
 PHYS_PAGE='203',
 XY='(-6550,1475)',
 ROT='0',
 VER='1',
 VALUE='10UF',
 PACK_TYPE='0805',
 PART_NUMBER='C95333-007',
 LOCATION='C6P20',
 ROOM='PVCCIN_CPU0_PWR_VR',
 SEC='1',
 CDS_LIB='mstr_discrete',
 CDS_PART_NAME='CAP_0805-10UF,16V,10%,X6S,C953A',
 VOLTAGE='16V',
 PRIM_FILE='./archive_libs/mstr_discrete/cap/chips/chips.prt';

PART_NAME
 C6P21 'CAP_A_0603V-22.0UF,4V,20%,X6S,A':
 GROUP='PWR_MLCC_CAP',
 ROOM='PVCCIN_CPU0_PWR_VR';

SECTION_NUMBER 1
 '@BASEBOARD_FAB2_LIB.BASEBOARD_FAB2(SCH_1):PAGE203_I66@DEV_DISCRETE.CAP_A(CHIPS)':
 C_PATH='@baseboard_fab2_lib.baseboard_fab2(sch_1):page203_i66@dev_discrete.cap_~
a(chips)',
 P_PATH='@baseboard_fab2_lib.baseboard_fab2(sch_1):page203_i66@dev_discrete.cap_~
a(chips)',
 PATH='I66',
 DRAWING='@BASEBOARD_FAB2_LIB.BASEBOARD_FAB2(SCH_1):PAGE203',
 TOLERANCE='20%',
 SEC_TYPE='0603V',
 MATERIAL='X6S',
 BOM_COST='PROC_VRD_VCCIN_CPU0',
 PHYS_PAGE='203',
 XY='(-800,3450)',
 ROT='0',
 VER='1',
 VALUE='22.0UF',
 PACK_TYPE='0603V',
 PART_NUMBER='E15431-004',
 LOCATION='C6P21',
 ROOM='PVCCIN_CPU0_PWR_VR',
 GROUP='PWR_MLCC_CAP',
 SEC='1',
 CDS_LIB='dev_discrete',
 CDS_PART_NAME='CAP_A_0603V-22.0UF,4V,20%,X6S,A',
 VOLTAGE='4V',
 PRIM_FILE='./archive_libs/discrete/cap_a/chips/chips.prt';

PART_NAME
 C6P22 'CAP_0805-10UF,16V,10%,X6S,C953A':
 ROOM='PVCCIN_CPU0_PWR_VR';

SECTION_NUMBER 1
 '@BASEBOARD_FAB2_LIB.BASEBOARD_FAB2(SCH_1):PAGE202_I49@MSTR_DISCRETE.CAP(CHIPS)':
 C_PATH='@baseboard_fab2_lib.baseboard_fab2(sch_1):page202_i49@mstr_discrete.cap~
(chips)',
 P_PATH='@baseboard_fab2_lib.baseboard_fab2(sch_1):page202_i49@mstr_discrete.cap~
(chips)',
 PATH='I49',
 DRAWING='@BASEBOARD_FAB2_LIB.BASEBOARD_FAB2(SCH_1):PAGE202',
 TOLERANCE='10%',
 SEC_TYPE='0805',
 MATERIAL='X6S',
 PHYS_PAGE='202',
 XY='(-6900,1475)',
 ROT='0',
 VER='1',
 VALUE='10UF',
 PACK_TYPE='0805',
 PART_NUMBER='C95333-007',
 LOCATION='C6P22',
 ROOM='PVCCIN_CPU0_PWR_VR',
 SEC='1',
 CDS_LIB='mstr_discrete',
 CDS_PART_NAME='CAP_0805-10UF,16V,10%,X6S,C953A',
 VOLTAGE='16V',
 PRIM_FILE='./archive_libs/mstr_discrete/cap/chips/chips.prt';

PART_NAME
 C6P23 'CAPP_3018-470UF,2.5V,20%,ALUM,A':
 GROUP='PWR_BULK_CAP',
 ROOM='PVCCIN_CPU0_DECAP_VR';

SECTION_NUMBER 1
 '@BASEBOARD_FAB2_LIB.BASEBOARD_FAB2(SCH_1):PAGE203_I28@MSTR_DISCRETE.CAPP(CHIPS)':
 C_PATH='@baseboard_fab2_lib.baseboard_fab2(sch_1):page203_i28@mstr_discrete.cap~
p(chips)',
 P_PATH='@baseboard_fab2_lib.baseboard_fab2(sch_1):page203_i28@mstr_discrete.cap~
p(chips)',
 PATH='I28',
 DRAWING='@BASEBOARD_FAB2_LIB.BASEBOARD_FAB2(SCH_1):PAGE203',
 TOLERANCE='20%',
 SEC_TYPE='3018',
 MATERIAL='ALUM',
 BOM_COST='PROC_VRD_VCCIN_CPU0',
 PHYS_PAGE='203',
 XY='(-1850,2600)',
 ROT='0',
 VER='1',
 VALUE='470UF',
 PACK_TYPE='3018',
 PART_NUMBER='699013-049',
 LOCATION='C6P23',
 ROOM='PVCCIN_CPU0_DECAP_VR',
 GROUP='PWR_BULK_CAP',
 SEC='1',
 CDS_LIB='mstr_discrete',
 CDS_PART_NAME='CAPP_3018-470UF,2.5V,20%,ALUM,A',
 VOLTAGE='2.5V',
 PRIM_FILE='./archive_libs/mstr_discrete/capp/chips/chips.prt';

PART_NAME
 C6P24 'CAP_0805-10UF,16V,10%,X6S,C953A':
 ROOM='PVCCIN_CPU0_PWR_VR';

SECTION_NUMBER 1
 '@BASEBOARD_FAB2_LIB.BASEBOARD_FAB2(SCH_1):PAGE203_I1@MSTR_DISCRETE.CAP(CHIPS)':
 C_PATH='@baseboard_fab2_lib.baseboard_fab2(sch_1):page203_i1@mstr_discrete.cap(~
chips)',
 P_PATH='@baseboard_fab2_lib.baseboard_fab2(sch_1):page203_i1@mstr_discrete.cap(~
chips)',
 PATH='I1',
 DRAWING='@BASEBOARD_FAB2_LIB.BASEBOARD_FAB2(SCH_1):PAGE203',
 TOLERANCE='10%',
 SEC_TYPE='0805',
 MATERIAL='X6S',
 PHYS_PAGE='203',
 XY='(-6350,4175)',
 ROT='0',
 VER='1',
 VALUE='10UF',
 PACK_TYPE='0805',
 PART_NUMBER='C95333-007',
 LOCATION='C6P24',
 ROOM='PVCCIN_CPU0_PWR_VR',
 SEC='1',
 CDS_LIB='mstr_discrete',
 CDS_PART_NAME='CAP_0805-10UF,16V,10%,X6S,C953A',
 VOLTAGE='16V',
 PRIM_FILE='./archive_libs/mstr_discrete/cap/chips/chips.prt';

PART_NAME
 C6R2 'CAP_A_0603V-22.0UF,4V,20%,X6S,A':
 GROUP='PWR_MLCC_CAP';

SECTION_NUMBER 1
 '@BASEBOARD_FAB2_LIB.BASEBOARD_FAB2(SCH_1):PAGE204_I70@DEV_DISCRETE.CAP_A(CHIPS)':
 C_PATH='@baseboard_fab2_lib.baseboard_fab2(sch_1):page204_i70@dev_discrete.cap_~
a(chips)',
 P_PATH='@baseboard_fab2_lib.baseboard_fab2(sch_1):page204_i70@dev_discrete.cap_~
a(chips)',
 PATH='I70',
 DRAWING='@BASEBOARD_FAB2_LIB.BASEBOARD_FAB2(SCH_1):PAGE204',
 TOLERANCE='20%',
 SEC_TYPE='0603V',
 MATERIAL='X6S',
 PHYS_PAGE='204',
 XY='(-400,3425)',
 ROT='0',
 VER='1',
 VALUE='22.0UF',
 PACK_TYPE='0603V',
 PART_NUMBER='E15431-004',
 LOCATION='C6R2',
 GROUP='PWR_MLCC_CAP',
 SEC='1',
 CDS_LIB='dev_discrete',
 CDS_PART_NAME='CAP_A_0603V-22.0UF,4V,20%,X6S,A',
 VOLTAGE='4V',
 PRIM_FILE='./archive_libs/discrete/cap_a/chips/chips.prt';

PART_NAME
 C6R3 'CAPP_3018-470UF,2.5V,20%,ALUM,A':
 GROUP='PWR_BULK_CAP',
 ROOM='PVCCIN_CPU0_DECAP_VR';

SECTION_NUMBER 1
 '@BASEBOARD_FAB2_LIB.BASEBOARD_FAB2(SCH_1):PAGE203_I16@MSTR_DISCRETE.CAPP(CHIPS)':
 C_PATH='@baseboard_fab2_lib.baseboard_fab2(sch_1):page203_i16@mstr_discrete.cap~
p(chips)',
 P_PATH='@baseboard_fab2_lib.baseboard_fab2(sch_1):page203_i16@mstr_discrete.cap~
p(chips)',
 PATH='I16',
 DRAWING='@BASEBOARD_FAB2_LIB.BASEBOARD_FAB2(SCH_1):PAGE203',
 TOLERANCE='20%',
 SEC_TYPE='3018',
 MATERIAL='ALUM',
 BOM_COST='PROC_VRD_VCCIN_CPU0',
 PHYS_PAGE='203',
 XY='(-925,2600)',
 ROT='0',
 VER='1',
 VALUE='470UF',
 PACK_TYPE='3018',
 PART_NUMBER='699013-049',
 LOCATION='C6R3',
 ROOM='PVCCIN_CPU0_DECAP_VR',
 GROUP='PWR_BULK_CAP',
 SEC='1',
 CDS_LIB='mstr_discrete',
 CDS_PART_NAME='CAPP_3018-470UF,2.5V,20%,ALUM,A',
 VOLTAGE='2.5V',
 PRIM_FILE='./archive_libs/mstr_discrete/capp/chips/chips.prt';

PART_NAME
 C6R4 'CAP_0805-10UF,16V,10%,X6S,C953A':
 ROOM='PVCCIN_CPU0_PWR_VR';

SECTION_NUMBER 1
 '@BASEBOARD_FAB2_LIB.BASEBOARD_FAB2(SCH_1):PAGE202_I48@MSTR_DISCRETE.CAP(CHIPS)':
 C_PATH='@baseboard_fab2_lib.baseboard_fab2(sch_1):page202_i48@mstr_discrete.cap~
(chips)',
 P_PATH='@baseboard_fab2_lib.baseboard_fab2(sch_1):page202_i48@mstr_discrete.cap~
(chips)',
 PATH='I48',
 DRAWING='@BASEBOARD_FAB2_LIB.BASEBOARD_FAB2(SCH_1):PAGE202',
 TOLERANCE='10%',
 SEC_TYPE='0805',
 MATERIAL='X6S',
 PHYS_PAGE='202',
 XY='(-6625,1475)',
 ROT='0',
 VER='1',
 VALUE='10UF',
 PACK_TYPE='0805',
 PART_NUMBER='C95333-007',
 LOCATION='C6R4',
 ROOM='PVCCIN_CPU0_PWR_VR',
 SEC='1',
 CDS_LIB='mstr_discrete',
 CDS_PART_NAME='CAP_0805-10UF,16V,10%,X6S,C953A',
 VOLTAGE='16V',
 PRIM_FILE='./archive_libs/mstr_discrete/cap/chips/chips.prt';

PART_NAME
 C6R5 'CAPP_3018-470UF,2.5V,20%,ALUM,A':
 GROUP='PWR_BULK_CAP',
 ROOM='PVCCIO_CPU1';

SECTION_NUMBER 1
 '@BASEBOARD_FAB2_LIB.BASEBOARD_FAB2(SCH_1):PAGE214_I24@MSTR_DISCRETE.CAPP(CHIPS)':
 C_PATH='@baseboard_fab2_lib.baseboard_fab2(sch_1):page214_i24@mstr_discrete.cap~
p(chips)',
 P_PATH='@baseboard_fab2_lib.baseboard_fab2(sch_1):page214_i24@mstr_discrete.cap~
p(chips)',
 PATH='I24',
 DRAWING='@BASEBOARD_FAB2_LIB.BASEBOARD_FAB2(SCH_1):PAGE214',
 TOLERANCE='20%',
 SEC_TYPE='3018',
 MATERIAL='ALUM',
 BOM_COST='PROC_VRD_PVCCIO_CPU1',
 PHYS_PAGE='214',
 XY='(2100,2300)',
 ROT='2',
 VER='1',
 VALUE='470UF',
 PACK_TYPE='3018',
 PART_NUMBER='699013-049',
 LOCATION='C6R5',
 ROOM='PVCCIO_CPU1',
 GROUP='PWR_BULK_CAP',
 SEC='1',
 CDS_LIB='mstr_discrete',
 CDS_PART_NAME='CAPP_3018-470UF,2.5V,20%,ALUM,A',
 VOLTAGE='2.5V',
 PRIM_FILE='./archive_libs/mstr_discrete/capp/chips/chips.prt';

PART_NAME
 C6R6 'CAP_0805-10UF,16V,10%,X6S,C953A':
 ROOM='PVCCIN_CPU0_PWR_VR';

SECTION_NUMBER 1
 '@BASEBOARD_FAB2_LIB.BASEBOARD_FAB2(SCH_1):PAGE203_I2@MSTR_DISCRETE.CAP(CHIPS)':
 C_PATH='@baseboard_fab2_lib.baseboard_fab2(sch_1):page203_i2@mstr_discrete.cap(~
chips)',
 P_PATH='@baseboard_fab2_lib.baseboard_fab2(sch_1):page203_i2@mstr_discrete.cap(~
chips)',
 PATH='I2',
 DRAWING='@BASEBOARD_FAB2_LIB.BASEBOARD_FAB2(SCH_1):PAGE203',
 TOLERANCE='10%',
 SEC_TYPE='0805',
 MATERIAL='X6S',
 PHYS_PAGE='203',
 XY='(-6700,4175)',
 ROT='0',
 VER='1',
 VALUE='10UF',
 PACK_TYPE='0805',
 PART_NUMBER='C95333-007',
 LOCATION='C6R6',
 ROOM='PVCCIN_CPU0_PWR_VR',
 SEC='1',
 CDS_LIB='mstr_discrete',
 CDS_PART_NAME='CAP_0805-10UF,16V,10%,X6S,C953A',
 VOLTAGE='16V',
 PRIM_FILE='./archive_libs/mstr_discrete/cap/chips/chips.prt';

PART_NAME
 C6R7 'CAP_A_0603V-22.0UF,4V,20%,X6S,A':
 GROUP='PWR_MLCC_CAP',
 ROOM='PVCCIN_CPU0_PWR_VR';

SECTION_NUMBER 1
 '@BASEBOARD_FAB2_LIB.BASEBOARD_FAB2(SCH_1):PAGE202_I9@DEV_DISCRETE.CAP_A(CHIPS)':
 C_PATH='@baseboard_fab2_lib.baseboard_fab2(sch_1):page202_i9@dev_discrete.cap_a~
(chips)',
 P_PATH='@baseboard_fab2_lib.baseboard_fab2(sch_1):page202_i9@dev_discrete.cap_a~
(chips)',
 PATH='I9',
 DRAWING='@BASEBOARD_FAB2_LIB.BASEBOARD_FAB2(SCH_1):PAGE202',
 TOLERANCE='20%',
 SEC_TYPE='0603V',
 MATERIAL='X6S',
 BOM_COST='PROC_VRD_VCCIN_CPU0',
 PHYS_PAGE='202',
 XY='(-1250,3300)',
 ROT='0',
 VER='1',
 VALUE='22.0UF',
 PACK_TYPE='0603V',
 PART_NUMBER='E15431-004',
 LOCATION='C6R7',
 ROOM='PVCCIN_CPU0_PWR_VR',
 GROUP='PWR_MLCC_CAP',
 SEC='1',
 CDS_LIB='dev_discrete',
 CDS_PART_NAME='CAP_A_0603V-22.0UF,4V,20%,X6S,A',
 VOLTAGE='4V',
 PRIM_FILE='./archive_libs/discrete/cap_a/chips/chips.prt';

PART_NAME
 C6R8 'CAP_0805-10UF,16V,10%,X6S,C953A':
 ROOM='PVCCIO_CPU1';

SECTION_NUMBER 1
 '@BASEBOARD_FAB2_LIB.BASEBOARD_FAB2(SCH_1):PAGE214_I83@MSTR_DISCRETE.CAP(CHIPS)':
 C_PATH='@baseboard_fab2_lib.baseboard_fab2(sch_1):page214_i83@mstr_discrete.cap~
(chips)',
 P_PATH='@baseboard_fab2_lib.baseboard_fab2(sch_1):page214_i83@mstr_discrete.cap~
(chips)',
 PATH='I83',
 DRAWING='@BASEBOARD_FAB2_LIB.BASEBOARD_FAB2(SCH_1):PAGE214',
 TOLERANCE='10%',
 SEC_TYPE='0805',
 MATERIAL='X6S',
 PHYS_PAGE='214',
 XY='(-3100,4150)',
 ROT='0',
 VER='1',
 VALUE='10UF',
 PACK_TYPE='0805',
 PART_NUMBER='C95333-007',
 LOCATION='C6R8',
 ROOM='PVCCIO_CPU1',
 SEC='1',
 CDS_LIB='mstr_discrete',
 CDS_PART_NAME='CAP_0805-10UF,16V,10%,X6S,C953A',
 VOLTAGE='16V',
 PRIM_FILE='./archive_libs/mstr_discrete/cap/chips/chips.prt';

PART_NAME
 C6R9 'CAPP_3018-470UF,2.5V,20%,ALUM,A':
 GROUP='PWR_BULK_CAP',
 ROOM='PVCCIN_CPU0_DECAP_VR';

SECTION_NUMBER 1
 '@BASEBOARD_FAB2_LIB.BASEBOARD_FAB2(SCH_1):PAGE203_I18@MSTR_DISCRETE.CAPP(CHIPS)':
 C_PATH='@baseboard_fab2_lib.baseboard_fab2(sch_1):page203_i18@mstr_discrete.cap~
p(chips)',
 P_PATH='@baseboard_fab2_lib.baseboard_fab2(sch_1):page203_i18@mstr_discrete.cap~
p(chips)',
 PATH='I18',
 DRAWING='@BASEBOARD_FAB2_LIB.BASEBOARD_FAB2(SCH_1):PAGE203',
 TOLERANCE='20%',
 SEC_TYPE='3018',
 MATERIAL='ALUM',
 BOM_COST='PROC_VRD_VCCIN_CPU0',
 PHYS_PAGE='203',
 XY='(-1400,2600)',
 ROT='0',
 VER='1',
 VALUE='470UF',
 PACK_TYPE='3018',
 PART_NUMBER='699013-049',
 LOCATION='C6R9',
 ROOM='PVCCIN_CPU0_DECAP_VR',
 GROUP='PWR_BULK_CAP',
 SEC='1',
 CDS_LIB='mstr_discrete',
 CDS_PART_NAME='CAPP_3018-470UF,2.5V,20%,ALUM,A',
 VOLTAGE='2.5V',
 PRIM_FILE='./archive_libs/mstr_discrete/capp/chips/chips.prt';

PART_NAME
 C6R10 'CAP_0805-10UF,16V,10%,X6S,C953A':
 ROOM='PVCCIO_CPU1';

SECTION_NUMBER 1
 '@BASEBOARD_FAB2_LIB.BASEBOARD_FAB2(SCH_1):PAGE214_I81@MSTR_DISCRETE.CAP(CHIPS)':
 C_PATH='@baseboard_fab2_lib.baseboard_fab2(sch_1):page214_i81@mstr_discrete.cap~
(chips)',
 P_PATH='@baseboard_fab2_lib.baseboard_fab2(sch_1):page214_i81@mstr_discrete.cap~
(chips)',
 PATH='I81',
 DRAWING='@BASEBOARD_FAB2_LIB.BASEBOARD_FAB2(SCH_1):PAGE214',
 TOLERANCE='10%',
 SEC_TYPE='0805',
 MATERIAL='X6S',
 PHYS_PAGE='214',
 XY='(-2800,4150)',
 ROT='0',
 VER='1',
 VALUE='10UF',
 PACK_TYPE='0805',
 PART_NUMBER='C95333-007',
 LOCATION='C6R10',
 ROOM='PVCCIO_CPU1',
 SEC='1',
 CDS_LIB='mstr_discrete',
 CDS_PART_NAME='CAP_0805-10UF,16V,10%,X6S,C953A',
 VOLTAGE='16V',
 PRIM_FILE='./archive_libs/mstr_discrete/cap/chips/chips.prt';

PART_NAME
 C6R11 'CAP_0805-10UF,16V,10%,X6S,C953A':
 ROOM='PVCCIN_CPU0_PWR_VR';

SECTION_NUMBER 1
 '@BASEBOARD_FAB2_LIB.BASEBOARD_FAB2(SCH_1):PAGE202_I37@MSTR_DISCRETE.CAP(CHIPS)':
 C_PATH='@baseboard_fab2_lib.baseboard_fab2(sch_1):page202_i37@mstr_discrete.cap~
(chips)',
 P_PATH='@baseboard_fab2_lib.baseboard_fab2(sch_1):page202_i37@mstr_discrete.cap~
(chips)',
 PATH='I37',
 DRAWING='@BASEBOARD_FAB2_LIB.BASEBOARD_FAB2(SCH_1):PAGE202',
 TOLERANCE='10%',
 SEC_TYPE='0805',
 MATERIAL='X6S',
 PHYS_PAGE='202',
 XY='(-6550,4075)',
 ROT='0',
 VER='1',
 VALUE='10UF',
 PACK_TYPE='0805',
 PART_NUMBER='C95333-007',
 LOCATION='C6R11',
 ROOM='PVCCIN_CPU0_PWR_VR',
 SEC='1',
 CDS_LIB='mstr_discrete',
 CDS_PART_NAME='CAP_0805-10UF,16V,10%,X6S,C953A',
 VOLTAGE='16V',
 PRIM_FILE='./archive_libs/mstr_discrete/cap/chips/chips.prt';

PART_NAME
 C6R12 'CAPP_3018-470UF,2.5V,20%,ALUM,A':
 GROUP='PWR_BULK_CAP',
 ROOM='PVCCIO_CPU1';

SECTION_NUMBER 1
 '@BASEBOARD_FAB2_LIB.BASEBOARD_FAB2(SCH_1):PAGE214_I177@MSTR_DISCRETE.CAPP(CHIPS)':
 C_PATH='@baseboard_fab2_lib.baseboard_fab2(sch_1):page214_i177@mstr_discrete.ca~
pp(chips)',
 P_PATH='@baseboard_fab2_lib.baseboard_fab2(sch_1):page214_i177@mstr_discrete.ca~
pp(chips)',
 PATH='I177',
 DRAWING='@BASEBOARD_FAB2_LIB.BASEBOARD_FAB2(SCH_1):PAGE214',
 TOLERANCE='20%',
 SEC_TYPE='3018',
 MATERIAL='ALUM',
 BOM_COST='PROC_VRD_PVCCIO_CPU1',
 PHYS_PAGE='214',
 XY='(2650,2300)',
 ROT='2',
 VER='1',
 VALUE='470UF',
 PACK_TYPE='3018',
 PART_NUMBER='699013-049',
 LOCATION='C6R12',
 ROOM='PVCCIO_CPU1',
 GROUP='PWR_BULK_CAP',
 SEC='1',
 CDS_LIB='mstr_discrete',
 CDS_PART_NAME='CAPP_3018-470UF,2.5V,20%,ALUM,A',
 VOLTAGE='2.5V',
 PRIM_FILE='./archive_libs/mstr_discrete/capp/chips/chips.prt';

PART_NAME
 C6R13 'CAP_0805-10UF,16V,10%,X6S,C953A':
 ROOM='PVCCIN_CPU0_PWR_VR';

SECTION_NUMBER 1
 '@BASEBOARD_FAB2_LIB.BASEBOARD_FAB2(SCH_1):PAGE202_I42@MSTR_DISCRETE.CAP(CHIPS)':
 C_PATH='@baseboard_fab2_lib.baseboard_fab2(sch_1):page202_i42@mstr_discrete.cap~
(chips)',
 P_PATH='@baseboard_fab2_lib.baseboard_fab2(sch_1):page202_i42@mstr_discrete.cap~
(chips)',
 PATH='I42',
 DRAWING='@BASEBOARD_FAB2_LIB.BASEBOARD_FAB2(SCH_1):PAGE202',
 TOLERANCE='10%',
 SEC_TYPE='0805',
 MATERIAL='X6S',
 PHYS_PAGE='202',
 XY='(-7100,4075)',
 ROT='0',
 VER='1',
 VALUE='10UF',
 PACK_TYPE='0805',
 PART_NUMBER='C95333-007',
 LOCATION='C6R13',
 ROOM='PVCCIN_CPU0_PWR_VR',
 SEC='1',
 CDS_LIB='mstr_discrete',
 CDS_PART_NAME='CAP_0805-10UF,16V,10%,X6S,C953A',
 VOLTAGE='16V',
 PRIM_FILE='./archive_libs/mstr_discrete/cap/chips/chips.prt';

PART_NAME
 C6R14 'CAP_0805-10UF,16V,10%,X6S,C953A':
 ROOM='PVCCIO_CPU1';

SECTION_NUMBER 1
 '@BASEBOARD_FAB2_LIB.BASEBOARD_FAB2(SCH_1):PAGE214_I80@MSTR_DISCRETE.CAP(CHIPS)':
 C_PATH='@baseboard_fab2_lib.baseboard_fab2(sch_1):page214_i80@mstr_discrete.cap~
(chips)',
 P_PATH='@baseboard_fab2_lib.baseboard_fab2(sch_1):page214_i80@mstr_discrete.cap~
(chips)',
 PATH='I80',
 DRAWING='@BASEBOARD_FAB2_LIB.BASEBOARD_FAB2(SCH_1):PAGE214',
 TOLERANCE='10%',
 SEC_TYPE='0805',
 MATERIAL='X6S',
 PHYS_PAGE='214',
 XY='(-2525,4150)',
 ROT='0',
 VER='1',
 VALUE='10UF',
 PACK_TYPE='0805',
 PART_NUMBER='C95333-007',
 LOCATION='C6R14',
 ROOM='PVCCIO_CPU1',
 SEC='1',
 CDS_LIB='mstr_discrete',
 CDS_PART_NAME='CAP_0805-10UF,16V,10%,X6S,C953A',
 VOLTAGE='16V',
 PRIM_FILE='./archive_libs/mstr_discrete/cap/chips/chips.prt';

PART_NAME
 C6R16 'CAPP_3018-470UF,2.5V,20%,ALUM,A':
 GROUP='PWR_MCP_CAP',
 ROOM='PVMCP_MCP_CPU1_VR';

SECTION_NUMBER 1
 '@BASEBOARD_FAB2_LIB.BASEBOARD_FAB2(SCH_1):PAGE193_I62@MSTR_DISCRETE.CAPP(CHIPS)':
 C_PATH='@baseboard_fab2_lib.baseboard_fab2(sch_1):page193_i62@mstr_discrete.cap~
p(chips)',
 P_PATH='@baseboard_fab2_lib.baseboard_fab2(sch_1):page193_i62@mstr_discrete.cap~
p(chips)',
 PATH='I62',
 DRAWING='@BASEBOARD_FAB2_LIB.BASEBOARD_FAB2(SCH_1):PAGE193',
 TOLERANCE='20%',
 SEC_TYPE='3018',
 MATERIAL='ALUM',
 BOM_COST='PVMCP_MCP_CPU1_VR',
 PHYS_PAGE='193',
 XY='(-1600,3100)',
 ROT='0',
 VER='1',
 VALUE='470UF',
 PACK_TYPE='3018',
 PART_NUMBER='699013-049',
 LOCATION='C6R16',
 ROOM='PVMCP_MCP_CPU1_VR',
 GROUP='PWR_MCP_CAP',
 SEC='1',
 CDS_LIB='mstr_discrete',
 CDS_PART_NAME='CAPP_3018-470UF,2.5V,20%,ALUM,A',
 VOLTAGE='2.5V',
 PRIM_FILE='./archive_libs/mstr_discrete/capp/chips/chips.prt';

PART_NAME
 C6T1 'CAP_A_0402V-0.01UF,25V,10%,X7RA':
 ROOM='DDR4_CH_A';

SECTION_NUMBER 1
 '@BASEBOARD_FAB2_LIB.BASEBOARD_FAB2(SCH_1):PAGE44_I2@DEV_DISCRETE.CAP_A(CHIPS)':
 C_PATH='@baseboard_fab2_lib.baseboard_fab2(sch_1):page44_i2@dev_discrete.cap_a(~
chips)',
 P_PATH='@baseboard_fab2_lib.baseboard_fab2(sch_1):page44_i2@dev_discrete.cap_a(~
chips)',
 PATH='I2',
 DRAWING='@BASEBOARD_FAB2_LIB.BASEBOARD_FAB2(SCH_1):PAGE44',
 TOLERANCE='10%',
 SEC_TYPE='0402V',
 MATERIAL='X7R',
 BOM_COST='MEM',
 PHYS_PAGE='44',
 XY='(-2650,1000)',
 ROT='2',
 VER='1',
 VALUE='0.01UF',
 PACK_TYPE='0402V',
 PART_NUMBER='A36096-045',
 LOCATION='C6T1',
 ROOM='DDR4_CH_A',
 SEC='1',
 CDS_LIB='dev_discrete',
 CDS_PART_NAME='CAP_A_0402V-0.01UF,25V,10%,X7RA',
 VOLTAGE='25V',
 PRIM_FILE='./archive_libs/discrete/cap_a/chips/chips.prt';

PART_NAME
 C6T2 'CAP_0805-10UF,16V,10%,X7R,G106A':
 ROOM='PVDDQ_ABC_PWR_VR';

SECTION_NUMBER 1
 '@BASEBOARD_FAB2_LIB.BASEBOARD_FAB2(SCH_1):PAGE197_I71@MSTR_DISCRETE.CAP(CHIPS)':
 C_PATH='@baseboard_fab2_lib.baseboard_fab2(sch_1):page197_i71@mstr_discrete.cap~
(chips)',
 P_PATH='@baseboard_fab2_lib.baseboard_fab2(sch_1):page197_i71@mstr_discrete.cap~
(chips)',
 PATH='I71',
 DRAWING='@BASEBOARD_FAB2_LIB.BASEBOARD_FAB2(SCH_1):PAGE197',
 TOLERANCE='10%',
 MATERIAL='X7R',
 PHYS_PAGE='197',
 XY='(1325,3750)',
 ROT='0',
 VER='1',
 VALUE='10UF',
 PACK_TYPE='0805',
 PART_NUMBER='G10601-001',
 LOCATION='C6T2',
 ROOM='PVDDQ_ABC_PWR_VR',
 CDS_LIB='mstr_discrete',
 CDS_PART_NAME='CAP_0805-10UF,16V,10%,X7R,G106A',
 VOLTAGE='16V',
 PRIM_FILE='./archive_libs/mstr_discrete/cap/chips/chips.prt';

PART_NAME
 C6U2 'CAP_0805-47UF,4V,20%,X6S,C9533A':
 GROUP='PWR_MLCC_CAP',
 ROOM='PVPP_KLM_VR',
 REUSE_ID='33';

SECTION_NUMBER 1
 '@BASEBOARD_FAB2_LIB.BASEBOARD_FAB2(SCH_1):PAGE233_I223@MSTR_DISCRETE.CAP(CHIPS)':
 C_PATH='@baseboard_fab2_lib.baseboard_fab2(sch_1):page233_i223@mstr_discrete.ca~
p(chips)',
 P_PATH='@baseboard_fab2_lib.baseboard_fab2(sch_1):page233_i223@mstr_discrete.ca~
p(chips)',
 PATH='I223',
 DRAWING='@BASEBOARD_FAB2_LIB.BASEBOARD_FAB2(SCH_1):PAGE233',
 TOLERANCE='20%',
 MATERIAL='X6S',
 BOM_COST='PVPP_KLM_VR',
 PHYS_PAGE='233',
 REUSE_ID='33',
 XY='(-775,3525)',
 ROT='0',
 VER='1',
 VALUE='47UF',
 PACK_TYPE='0805',
 PART_NUMBER='C95333-006',
 LOCATION='C6U2',
 ROOM='PVPP_KLM_VR',
 GROUP='PWR_MLCC_CAP',
 CDS_LIB='mstr_discrete',
 CDS_PART_NAME='CAP_0805-47UF,4V,20%,X6S,C9533A',
 VOLTAGE='4V',
 PRIM_FILE='./archive_libs/mstr_discrete/cap/chips/chips.prt';

PART_NAME
 C6U3 'CAP_0805-47UF,4V,20%,X6S,C9533A':
 GROUP='PWR_MLCC_CAP',
 ROOM='PVPP_KLM_VR',
 REUSE_ID='33';

SECTION_NUMBER 1
 '@BASEBOARD_FAB2_LIB.BASEBOARD_FAB2(SCH_1):PAGE233_I221@MSTR_DISCRETE.CAP(CHIPS)':
 C_PATH='@baseboard_fab2_lib.baseboard_fab2(sch_1):page233_i221@mstr_discrete.ca~
p(chips)',
 P_PATH='@baseboard_fab2_lib.baseboard_fab2(sch_1):page233_i221@mstr_discrete.ca~
p(chips)',
 PATH='I221',
 DRAWING='@BASEBOARD_FAB2_LIB.BASEBOARD_FAB2(SCH_1):PAGE233',
 TOLERANCE='20%',
 MATERIAL='X6S',
 BOM_COST='PVPP_KLM_VR',
 PHYS_PAGE='233',
 REUSE_ID='33',
 XY='(-1075,3525)',
 ROT='0',
 VER='1',
 VALUE='47UF',
 PACK_TYPE='0805',
 PART_NUMBER='C95333-006',
 LOCATION='C6U3',
 ROOM='PVPP_KLM_VR',
 GROUP='PWR_MLCC_CAP',
 CDS_LIB='mstr_discrete',
 CDS_PART_NAME='CAP_0805-47UF,4V,20%,X6S,C9533A',
 VOLTAGE='4V',
 PRIM_FILE='./archive_libs/mstr_discrete/cap/chips/chips.prt';

PART_NAME
 C6U4 'CAP_0805-10UF,16V,10%,X6S,C953A':;

SECTION_NUMBER 1
 '@BASEBOARD_FAB2_LIB.BASEBOARD_FAB2(SCH_1):PAGE233_I248@MSTR_DISCRETE.CAP(CHIPS)':
 C_PATH='@baseboard_fab2_lib.baseboard_fab2(sch_1):page233_i248@mstr_discrete.ca~
p(chips)',
 P_PATH='@baseboard_fab2_lib.baseboard_fab2(sch_1):page233_i248@mstr_discrete.ca~
p(chips)',
 PATH='I248',
 DRAWING='@BASEBOARD_FAB2_LIB.BASEBOARD_FAB2(SCH_1):PAGE233',
 TOLERANCE='10%',
 SEC_TYPE='0805',
 MATERIAL='X6S',
 PHYS_PAGE='233',
 XY='(-6600,4000)',
 ROT='0',
 VER='1',
 VALUE='10UF',
 PACK_TYPE='0805',
 PART_NUMBER='C95333-007',
 LOCATION='C6U4',
 SEC='1',
 CDS_LIB='mstr_discrete',
 CDS_PART_NAME='CAP_0805-10UF,16V,10%,X6S,C953A',
 VOLTAGE='16V',
 PRIM_FILE='./archive_libs/mstr_discrete/cap/chips/chips.prt';

PART_NAME
 C6U5 'CAP_A_0402V-0.1UF,16V,10%,X7R,A':;

SECTION_NUMBER 1
 '@BASEBOARD_FAB2_LIB.BASEBOARD_FAB2(SCH_1):PAGE233_I242@DEV_DISCRETE.CAP_A(CHIPS)':
 C_PATH='@baseboard_fab2_lib.baseboard_fab2(sch_1):page233_i242@dev_discrete.cap~
_a(chips)',
 P_PATH='@baseboard_fab2_lib.baseboard_fab2(sch_1):page233_i242@dev_discrete.cap~
_a(chips)',
 PATH='I242',
 DRAWING='@BASEBOARD_FAB2_LIB.BASEBOARD_FAB2(SCH_1):PAGE233',
 TOLERANCE='10%',
 SEC_TYPE='0402V',
 MATERIAL='X7R',
 PHYS_PAGE='233',
 XY='(-5050,3325)',
 ROT='0',
 VER='1',
 VALUE='0.1UF',
 PACK_TYPE='0402V',
 PART_NUMBER='A36096-030',
 LOCATION='C6U5',
 SEC='1',
 CDS_LIB='dev_discrete',
 CDS_PART_NAME='CAP_A_0402V-0.1UF,16V,10%,X7R,A',
 VOLTAGE='16V',
 PRIM_FILE='./archive_libs/discrete/cap_a/chips/chips.prt';

PART_NAME
 C6U6 'CAP_0603-4.7UF,6.3V,10%,X6S,E1A':
 ROOM='PVPP_KLM_VR',
 REUSE_ID='26';

SECTION_NUMBER 1
 '@BASEBOARD_FAB2_LIB.BASEBOARD_FAB2(SCH_1):PAGE233_I187@MSTR_DISCRETE.CAP(CHIPS)':
 C_PATH='@baseboard_fab2_lib.baseboard_fab2(sch_1):page233_i187@mstr_discrete.ca~
p(chips)',
 P_PATH='@baseboard_fab2_lib.baseboard_fab2(sch_1):page233_i187@mstr_discrete.ca~
p(chips)',
 PATH='I187',
 DRAWING='@BASEBOARD_FAB2_LIB.BASEBOARD_FAB2(SCH_1):PAGE233',
 CONFIG='078.47521.08BD',
 TOLERANCE='10%',
 SEC_TYPE='0603',
 MATERIAL='X6S',
 BOM_COST='PVPP_KLM_VR',
 PHYS_PAGE='233',
 REUSE_ID='26',
 XY='(-5800,2350)',
 ROT='0',
 VER='1',
 VALUE='4.7UF',
 PACK_TYPE='0603',
 PART_NUMBER='E15431-003',
 LOCATION='C6U6',
 ROOM='PVPP_KLM_VR',
 SEC='1',
 CDS_LIB='mstr_discrete',
 CDS_PART_NAME='CAP_0603-4.7UF,6.3V,10%,X6S,E1A',
 VOLTAGE='6.3V',
 PRIM_FILE='./archive_libs/mstr_discrete/cap/chips/chips.prt';

PART_NAME
 C6U7 'CAP_0805-10UF,16V,10%,X6S,C953A':;

SECTION_NUMBER 1
 '@BASEBOARD_FAB2_LIB.BASEBOARD_FAB2(SCH_1):PAGE233_I254@MSTR_DISCRETE.CAP(CHIPS)':
 C_PATH='@baseboard_fab2_lib.baseboard_fab2(sch_1):page233_i254@mstr_discrete.ca~
p(chips)',
 P_PATH='@baseboard_fab2_lib.baseboard_fab2(sch_1):page233_i254@mstr_discrete.ca~
p(chips)',
 PATH='I254',
 DRAWING='@BASEBOARD_FAB2_LIB.BASEBOARD_FAB2(SCH_1):PAGE233',
 TOLERANCE='10%',
 SEC_TYPE='0805',
 MATERIAL='X6S',
 PHYS_PAGE='233',
 XY='(-5875,4000)',
 ROT='0',
 VER='1',
 VALUE='10UF',
 PACK_TYPE='0805',
 PART_NUMBER='C95333-007',
 LOCATION='C6U7',
 SEC='1',
 CDS_LIB='mstr_discrete',
 CDS_PART_NAME='CAP_0805-10UF,16V,10%,X6S,C953A',
 VOLTAGE='16V',
 PRIM_FILE='./archive_libs/mstr_discrete/cap/chips/chips.prt';

PART_NAME
 C6U8 'CAP_0805-10UF,16V,10%,X6S,C953A':;

SECTION_NUMBER 1
 '@BASEBOARD_FAB2_LIB.BASEBOARD_FAB2(SCH_1):PAGE233_I255@MSTR_DISCRETE.CAP(CHIPS)':
 C_PATH='@baseboard_fab2_lib.baseboard_fab2(sch_1):page233_i255@mstr_discrete.ca~
p(chips)',
 P_PATH='@baseboard_fab2_lib.baseboard_fab2(sch_1):page233_i255@mstr_discrete.ca~
p(chips)',
 PATH='I255',
 DRAWING='@BASEBOARD_FAB2_LIB.BASEBOARD_FAB2(SCH_1):PAGE233',
 TOLERANCE='10%',
 SEC_TYPE='0805',
 MATERIAL='X6S',
 PHYS_PAGE='233',
 XY='(-5450,4000)',
 ROT='0',
 VER='1',
 VALUE='10UF',
 PACK_TYPE='0805',
 PART_NUMBER='C95333-007',
 LOCATION='C6U8',
 SEC='1',
 CDS_LIB='mstr_discrete',
 CDS_PART_NAME='CAP_0805-10UF,16V,10%,X6S,C953A',
 VOLTAGE='16V',
 PRIM_FILE='./archive_libs/mstr_discrete/cap/chips/chips.prt';

PART_NAME
 C6U9 'CAP_A_0402V-0.01UF,25V,10%,X7RA':
 ROOM='DDR4_CH_A';

SECTION_NUMBER 1
 '@BASEBOARD_FAB2_LIB.BASEBOARD_FAB2(SCH_1):PAGE46_I5@DEV_DISCRETE.CAP_A(CHIPS)':
 C_PATH='@baseboard_fab2_lib.baseboard_fab2(sch_1):page46_i5@dev_discrete.cap_a(~
chips)',
 P_PATH='@baseboard_fab2_lib.baseboard_fab2(sch_1):page46_i5@dev_discrete.cap_a(~
chips)',
 PATH='I5',
 DRAWING='@BASEBOARD_FAB2_LIB.BASEBOARD_FAB2(SCH_1):PAGE46',
 TOLERANCE='10%',
 SEC_TYPE='0402V',
 MATERIAL='X7R',
 BOM_COST='MEM',
 PHYS_PAGE='46',
 XY='(-2975,900)',
 ROT='2',
 VER='1',
 VALUE='0.01UF',
 PACK_TYPE='0402V',
 PART_NUMBER='A36096-045',
 LOCATION='C6U9',
 ROOM='DDR4_CH_A',
 SEC='1',
 CDS_LIB='dev_discrete',
 CDS_PART_NAME='CAP_A_0402V-0.01UF,25V,10%,X7RA',
 VOLTAGE='25V',
 PRIM_FILE='./archive_libs/discrete/cap_a/chips/chips.prt';

PART_NAME
 C6U10 'CAP_0805-10UF,16V,10%,X7R,G106A':
 ROOM='PVDDQ_ABC_PWR_VR';

SECTION_NUMBER 1
 '@BASEBOARD_FAB2_LIB.BASEBOARD_FAB2(SCH_1):PAGE197_I84@MSTR_DISCRETE.CAP(CHIPS)':
 C_PATH='@baseboard_fab2_lib.baseboard_fab2(sch_1):page197_i84@mstr_discrete.cap~
(chips)',
 P_PATH='@baseboard_fab2_lib.baseboard_fab2(sch_1):page197_i84@mstr_discrete.cap~
(chips)',
 PATH='I84',
 DRAWING='@BASEBOARD_FAB2_LIB.BASEBOARD_FAB2(SCH_1):PAGE197',
 TOLERANCE='10%',
 MATERIAL='X7R',
 PHYS_PAGE='197',
 XY='(1325,4400)',
 ROT='0',
 VER='1',
 VALUE='10UF',
 PACK_TYPE='0805',
 PART_NUMBER='G10601-001',
 LOCATION='C6U10',
 ROOM='PVDDQ_ABC_PWR_VR',
 CDS_LIB='mstr_discrete',
 CDS_PART_NAME='CAP_0805-10UF,16V,10%,X7R,G106A',
 VOLTAGE='16V',
 PRIM_FILE='./archive_libs/mstr_discrete/cap/chips/chips.prt';

PART_NAME
 C6U11 'CAP_0603-4.7UF,6.3V,10%,X6S,E1A':
 ROOM='VTT_GHJ_PWR_VR';

SECTION_NUMBER 1
 '@BASEBOARD_FAB2_LIB.BASEBOARD_FAB2(SCH_1):PAGE229_I14@MSTR_DISCRETE.CAP(CHIPS)':
 C_PATH='@baseboard_fab2_lib.baseboard_fab2(sch_1):page229_i14@mstr_discrete.cap~
(chips)',
 P_PATH='@baseboard_fab2_lib.baseboard_fab2(sch_1):page229_i14@mstr_discrete.cap~
(chips)',
 PATH='I14',
 DRAWING='@BASEBOARD_FAB2_LIB.BASEBOARD_FAB2(SCH_1):PAGE229',
 TOLERANCE='10%',
 SEC_TYPE='0603',
 MATERIAL='X6S',
 PHYS_PAGE='229',
 XY='(200,825)',
 ROT='0',
 VER='1',
 VALUE='4.7UF',
 PACK_TYPE='0603',
 PART_NUMBER='E15431-003',
 LOCATION='C6U11',
 ROOM='VTT_GHJ_PWR_VR',
 SEC='1',
 CDS_LIB='mstr_discrete',
 CDS_PART_NAME='CAP_0603-4.7UF,6.3V,10%,X6S,E1A',
 VOLTAGE='6.3V',
 PRIM_FILE='./archive_libs/mstr_discrete/cap/chips/chips.prt';

PART_NAME
 C6U12 'CAP_0603-4.7UF,6.3V,10%,X6S,E1A':
 ROOM='VTT_ABC_PWR_VR';

SECTION_NUMBER 1
 '@BASEBOARD_FAB2_LIB.BASEBOARD_FAB2(SCH_1):PAGE221_I11@MSTR_DISCRETE.CAP(CHIPS)':
 C_PATH='@baseboard_fab2_lib.baseboard_fab2(sch_1):page221_i11@mstr_discrete.cap~
(chips)',
 P_PATH='@baseboard_fab2_lib.baseboard_fab2(sch_1):page221_i11@mstr_discrete.cap~
(chips)',
 PATH='I11',
 DRAWING='@BASEBOARD_FAB2_LIB.BASEBOARD_FAB2(SCH_1):PAGE221',
 TOLERANCE='10%',
 SEC_TYPE='0603',
 MATERIAL='X6S',
 PHYS_PAGE='221',
 XY='(50,925)',
 ROT='0',
 VER='1',
 VALUE='4.7UF',
 PACK_TYPE='0603',
 PART_NUMBER='E15431-003',
 LOCATION='C6U12',
 ROOM='VTT_ABC_PWR_VR',
 SEC='1',
 CDS_LIB='mstr_discrete',
 CDS_PART_NAME='CAP_0603-4.7UF,6.3V,10%,X6S,E1A',
 VOLTAGE='6.3V',
 PRIM_FILE='./archive_libs/mstr_discrete/cap/chips/chips.prt';

PART_NAME
 C6U13 'CAP_0603LF-10UF,4V,20%,X6S,E15A':
 ROOM='VTT_GHJ_PWR_VR';

SECTION_NUMBER 1
 '@BASEBOARD_FAB2_LIB.BASEBOARD_FAB2(SCH_1):PAGE229_I11@MSTR_DISCRETE.CAP(CHIPS)':
 C_PATH='@baseboard_fab2_lib.baseboard_fab2(sch_1):page229_i11@mstr_discrete.cap~
(chips)',
 P_PATH='@baseboard_fab2_lib.baseboard_fab2(sch_1):page229_i11@mstr_discrete.cap~
(chips)',
 PATH='I11',
 DRAWING='@BASEBOARD_FAB2_LIB.BASEBOARD_FAB2(SCH_1):PAGE229',
 TOLERANCE='20%',
 SEC_TYPE='0603LF',
 MATERIAL='X6S',
 BOM_COST='MEM_VRD_VTT_GHJ',
 PHYS_PAGE='229',
 XY='(-75,2200)',
 ROT='0',
 VER='1',
 VALUE='10UF',
 PACK_TYPE='0603LF',
 PART_NUMBER='E15431-001',
 LOCATION='C6U13',
 ROOM='VTT_GHJ_PWR_VR',
 SEC='1',
 CDS_LIB='mstr_discrete',
 CDS_PART_NAME='CAP_0603LF-10UF,4V,20%,X6S,E15A',
 VOLTAGE='4V',
 PRIM_FILE='./archive_libs/mstr_discrete/cap/chips/chips.prt';

PART_NAME
 C6U14 'CAP_0603LF-10UF,4V,20%,X6S,E15A':
 ROOM='VTT_GHJ_PWR_VR';

SECTION_NUMBER 1
 '@BASEBOARD_FAB2_LIB.BASEBOARD_FAB2(SCH_1):PAGE229_I18@MSTR_DISCRETE.CAP(CHIPS)':
 C_PATH='@baseboard_fab2_lib.baseboard_fab2(sch_1):page229_i18@mstr_discrete.cap~
(chips)',
 P_PATH='@baseboard_fab2_lib.baseboard_fab2(sch_1):page229_i18@mstr_discrete.cap~
(chips)',
 PATH='I18',
 DRAWING='@BASEBOARD_FAB2_LIB.BASEBOARD_FAB2(SCH_1):PAGE229',
 TOLERANCE='20%',
 SEC_TYPE='0603LF',
 MATERIAL='X6S',
 BOM_COST='MEM_VRD_VTT_GHJ',
 PHYS_PAGE='229',
 XY='(350,2200)',
 ROT='0',
 VER='1',
 VALUE='10UF',
 PACK_TYPE='0603LF',
 PART_NUMBER='E15431-001',
 LOCATION='C6U14',
 ROOM='VTT_GHJ_PWR_VR',
 SEC='1',
 CDS_LIB='mstr_discrete',
 CDS_PART_NAME='CAP_0603LF-10UF,4V,20%,X6S,E15A',
 VOLTAGE='4V',
 PRIM_FILE='./archive_libs/mstr_discrete/cap/chips/chips.prt';

PART_NAME
 C6U15 'CAP_0603LF-10UF,4V,20%,X6S,E15A':
 ROOM='VTT_ABC_PWR_VR';

SECTION_NUMBER 1
 '@BASEBOARD_FAB2_LIB.BASEBOARD_FAB2(SCH_1):PAGE221_I18@MSTR_DISCRETE.CAP(CHIPS)':
 C_PATH='@baseboard_fab2_lib.baseboard_fab2(sch_1):page221_i18@mstr_discrete.cap~
(chips)',
 P_PATH='@baseboard_fab2_lib.baseboard_fab2(sch_1):page221_i18@mstr_discrete.cap~
(chips)',
 PATH='I18',
 DRAWING='@BASEBOARD_FAB2_LIB.BASEBOARD_FAB2(SCH_1):PAGE221',
 TOLERANCE='20%',
 SEC_TYPE='0603LF',
 MATERIAL='X6S',
 BOM_COST='MEM_VRD_VTT_ABC',
 PHYS_PAGE='221',
 XY='(-225,2250)',
 ROT='0',
 VER='1',
 VALUE='10UF',
 PACK_TYPE='0603LF',
 PART_NUMBER='E15431-001',
 LOCATION='C6U15',
 ROOM='VTT_ABC_PWR_VR',
 SEC='1',
 CDS_LIB='mstr_discrete',
 CDS_PART_NAME='CAP_0603LF-10UF,4V,20%,X6S,E15A',
 VOLTAGE='4V',
 PRIM_FILE='./archive_libs/mstr_discrete/cap/chips/chips.prt';

PART_NAME
 C6U16 'CAP_0603LF-10UF,4V,20%,X6S,E15A':
 ROOM='VTT_ABC_PWR_VR';

SECTION_NUMBER 1
 '@BASEBOARD_FAB2_LIB.BASEBOARD_FAB2(SCH_1):PAGE221_I19@MSTR_DISCRETE.CAP(CHIPS)':
 C_PATH='@baseboard_fab2_lib.baseboard_fab2(sch_1):page221_i19@mstr_discrete.cap~
(chips)',
 P_PATH='@baseboard_fab2_lib.baseboard_fab2(sch_1):page221_i19@mstr_discrete.cap~
(chips)',
 PATH='I19',
 DRAWING='@BASEBOARD_FAB2_LIB.BASEBOARD_FAB2(SCH_1):PAGE221',
 TOLERANCE='20%',
 SEC_TYPE='0603LF',
 MATERIAL='X6S',
 BOM_COST='MEM_VRD_VTT_ABC',
 PHYS_PAGE='221',
 XY='(200,2275)',
 ROT='0',
 VER='1',
 VALUE='10UF',
 PACK_TYPE='0603LF',
 PART_NUMBER='E15431-001',
 LOCATION='C6U16',
 ROOM='VTT_ABC_PWR_VR',
 SEC='1',
 CDS_LIB='mstr_discrete',
 CDS_PART_NAME='CAP_0603LF-10UF,4V,20%,X6S,E15A',
 VOLTAGE='4V',
 PRIM_FILE='./archive_libs/mstr_discrete/cap/chips/chips.prt';

PART_NAME
 C6U17 'CAP_A_0402V-0.01UF,25V,10%,X7RA':
 ROOM='DDR4_CH_B';

SECTION_NUMBER 1
 '@BASEBOARD_FAB2_LIB.BASEBOARD_FAB2(SCH_1):PAGE48_I176@DEV_DISCRETE.CAP_A(CHIPS)':
 C_PATH='@baseboard_fab2_lib.baseboard_fab2(sch_1):page48_i176@dev_discrete.cap_~
a(chips)',
 P_PATH='@baseboard_fab2_lib.baseboard_fab2(sch_1):page48_i176@dev_discrete.cap_~
a(chips)',
 PATH='I176',
 DRAWING='@BASEBOARD_FAB2_LIB.BASEBOARD_FAB2(SCH_1):PAGE48',
 TOLERANCE='10%',
 SEC_TYPE='0402V',
 MATERIAL='X7R',
 BOM_COST='MEM',
 PHYS_PAGE='48',
 XY='(-4650,1500)',
 ROT='2',
 VER='1',
 VALUE='0.01UF',
 PACK_TYPE='0402V',
 PART_NUMBER='A36096-045',
 LOCATION='C6U17',
 ROOM='DDR4_CH_B',
 SEC='1',
 CDS_LIB='dev_discrete',
 CDS_PART_NAME='CAP_A_0402V-0.01UF,25V,10%,X7RA',
 VOLTAGE='25V',
 PRIM_FILE='./archive_libs/discrete/cap_a/chips/chips.prt';

PART_NAME
 C6U18 'CAP_0805-10UF,16V,10%,X7R,G106A':
 ROOM='PVDDQ_ABC_PWR_VR';

SECTION_NUMBER 1
 '@BASEBOARD_FAB2_LIB.BASEBOARD_FAB2(SCH_1):PAGE197_I69@MSTR_DISCRETE.CAP(CHIPS)':
 C_PATH='@baseboard_fab2_lib.baseboard_fab2(sch_1):page197_i69@mstr_discrete.cap~
(chips)',
 P_PATH='@baseboard_fab2_lib.baseboard_fab2(sch_1):page197_i69@mstr_discrete.cap~
(chips)',
 PATH='I69',
 DRAWING='@BASEBOARD_FAB2_LIB.BASEBOARD_FAB2(SCH_1):PAGE197',
 TOLERANCE='10%',
 MATERIAL='X7R',
 PHYS_PAGE='197',
 XY='(1325,3175)',
 ROT='0',
 VER='1',
 VALUE='10UF',
 PACK_TYPE='0805',
 PART_NUMBER='G10601-001',
 LOCATION='C6U18',
 ROOM='PVDDQ_ABC_PWR_VR',
 CDS_LIB='mstr_discrete',
 CDS_PART_NAME='CAP_0805-10UF,16V,10%,X7R,G106A',
 VOLTAGE='16V',
 PRIM_FILE='./archive_libs/mstr_discrete/cap/chips/chips.prt';

PART_NAME
 C6W1 'CAP_A_0402V-0.1UF,16V,10%,X7R,A':
 ROOM='VDDQ_KLM_PWR_VR';

SECTION_NUMBER 1
 '@BASEBOARD_FAB2_LIB.BASEBOARD_FAB2(SCH_1):PAGE247_I151@DEV_DISCRETE.CAP_A(CHIPS)':
 C_PATH='@baseboard_fab2_lib.baseboard_fab2(sch_1):page247_i151@dev_discrete.cap~
_a(chips)',
 P_PATH='@baseboard_fab2_lib.baseboard_fab2(sch_1):page247_i151@dev_discrete.cap~
_a(chips)',
 PATH='I151',
 DRAWING='@BASEBOARD_FAB2_LIB.BASEBOARD_FAB2(SCH_1):PAGE247',
 TOLERANCE='10%',
 SEC_TYPE='0402V',
 MATERIAL='X7R',
 PHYS_PAGE='247',
 XY='(-5200,4200)',
 ROT='0',
 VER='1',
 VALUE='0.1UF',
 PACK_TYPE='0402V',
 PART_NUMBER='A36096-030',
 LOCATION='C6W1',
 ROOM='VDDQ_KLM_PWR_VR',
 SEC='1',
 CDS_LIB='dev_discrete',
 CDS_PART_NAME='CAP_A_0402V-0.1UF,16V,10%,X7R,A',
 VOLTAGE='16V',
 PRIM_FILE='./archive_libs/discrete/cap_a/chips/chips.prt';

PART_NAME
 C6W2 'CAP_A_0402V-0.1UF,16V,10%,X7R,A':
 ROOM='SMB_PE_HP_CPU1';

SECTION_NUMBER 1
 '@BASEBOARD_FAB2_LIB.BASEBOARD_FAB2(SCH_1):PAGE247_I107@DEV_DISCRETE.CAP_A(CHIPS)':
 C_PATH='@baseboard_fab2_lib.baseboard_fab2(sch_1):page247_i107@dev_discrete.cap~
_a(chips)',
 P_PATH='@baseboard_fab2_lib.baseboard_fab2(sch_1):page247_i107@dev_discrete.cap~
_a(chips)',
 PATH='I107',
 DRAWING='@BASEBOARD_FAB2_LIB.BASEBOARD_FAB2(SCH_1):PAGE247',
 TOLERANCE='10%',
 SEC_TYPE='0402V',
 MATERIAL='X7R',
 PHYS_PAGE='247',
 XY='(-5500,1250)',
 ROT='2',
 VER='1',
 VALUE='0.1UF',
 PACK_TYPE='0402V',
 PART_NUMBER='A36096-030',
 LOCATION='C6W2',
 ROOM='SMB_PE_HP_CPU1',
 SEC='1',
 CDS_LIB='dev_discrete',
 CDS_PART_NAME='CAP_A_0402V-0.1UF,16V,10%,X7R,A',
 VOLTAGE='16V',
 PRIM_FILE='./archive_libs/discrete/cap_a/chips/chips.prt';

PART_NAME
 C6W3 'CAP_A_0402V-0.1UF,16V,10%,X7R,A':
 ROOM='TEMP_SENSORS';

SECTION_NUMBER 1
 '@BASEBOARD_FAB2_LIB.BASEBOARD_FAB2(SCH_1):PAGE247_I85@DEV_DISCRETE.CAP_A(CHIPS)':
 C_PATH='@baseboard_fab2_lib.baseboard_fab2(sch_1):page247_i85@dev_discrete.cap_~
a(chips)',
 P_PATH='@baseboard_fab2_lib.baseboard_fab2(sch_1):page247_i85@dev_discrete.cap_~
a(chips)',
 PATH='I85',
 DRAWING='@BASEBOARD_FAB2_LIB.BASEBOARD_FAB2(SCH_1):PAGE247',
 TOLERANCE='10%',
 SEC_TYPE='0402V',
 MATERIAL='X7R',
 BOM_COST='SM_THERM',
 PHYS_PAGE='247',
 XY='(-1775,2300)',
 ROT='0',
 VER='1',
 VALUE='0.1UF',
 PACK_TYPE='0402V',
 PART_NUMBER='A36096-030',
 LOCATION='C6W3',
 ROOM='TEMP_SENSORS',
 SEC='1',
 CDS_LIB='dev_discrete',
 CDS_PART_NAME='CAP_A_0402V-0.1UF,16V,10%,X7R,A',
 VOLTAGE='16V',
 PRIM_FILE='./archive_libs/discrete/cap_a/chips/chips.prt';

PART_NAME
 C6W4 'CAP_A_0402V-0.1UF,16V,10%,X7R,A':
 ROOM='SMB_PE_HP_CPU1';

SECTION_NUMBER 1
 '@BASEBOARD_FAB2_LIB.BASEBOARD_FAB2(SCH_1):PAGE247_I105@DEV_DISCRETE.CAP_A(CHIPS)':
 C_PATH='@baseboard_fab2_lib.baseboard_fab2(sch_1):page247_i105@dev_discrete.cap~
_a(chips)',
 P_PATH='@baseboard_fab2_lib.baseboard_fab2(sch_1):page247_i105@dev_discrete.cap~
_a(chips)',
 PATH='I105',
 DRAWING='@BASEBOARD_FAB2_LIB.BASEBOARD_FAB2(SCH_1):PAGE247',
 TOLERANCE='10%',
 SEC_TYPE='0402V',
 MATERIAL='X7R',
 PHYS_PAGE='247',
 XY='(-7250,1250)',
 ROT='0',
 VER='1',
 VALUE='0.1UF',
 PACK_TYPE='0402V',
 PART_NUMBER='A36096-030',
 LOCATION='C6W4',
 ROOM='SMB_PE_HP_CPU1',
 SEC='1',
 CDS_LIB='dev_discrete',
 CDS_PART_NAME='CAP_A_0402V-0.1UF,16V,10%,X7R,A',
 VOLTAGE='16V',
 PRIM_FILE='./archive_libs/discrete/cap_a/chips/chips.prt';

PART_NAME
 C6W10 'CAP_A_0402V-0.1UF,16V,10%,X7R,A':
 ROOM='VDDQ_KLM_PWR_VR';

SECTION_NUMBER 1
 '@BASEBOARD_FAB2_LIB.BASEBOARD_FAB2(SCH_1):PAGE176_I139@DEV_DISCRETE.CAP_A(CHIPS)':
 C_PATH='@baseboard_fab2_lib.baseboard_fab2(sch_1):page176_i139@dev_discrete.cap~
_a(chips)',
 P_PATH='@baseboard_fab2_lib.baseboard_fab2(sch_1):page176_i139@dev_discrete.cap~
_a(chips)',
 PATH='I139',
 DRAWING='@BASEBOARD_FAB2_LIB.BASEBOARD_FAB2(SCH_1):PAGE176',
 TOLERANCE='10%',
 SEC_TYPE='0402V',
 MATERIAL='X7R',
 PHYS_PAGE='176',
 XY='(-200,1500)',
 ROT='0',
 VER='1',
 VALUE='0.1UF',
 PACK_TYPE='0402V',
 PART_NUMBER='A36096-030',
 LOCATION='C6W10',
 ROOM='VDDQ_KLM_PWR_VR',
 SEC='1',
 CDS_LIB='dev_discrete',
 CDS_PART_NAME='CAP_A_0402V-0.1UF,16V,10%,X7R,A',
 VOLTAGE='16V',
 PRIM_FILE='./archive_libs/discrete/cap_a/chips/chips.prt';

PART_NAME
 C6W11 'CAP_0805-100UF,4V,20%,X5R,6024A':
 GROUP='PWR_MLCC_CAP',
 ROOM='VDDQ_ABC_PWR_VR';

SECTION_NUMBER 1
 '@BASEBOARD_FAB2_LIB.BASEBOARD_FAB2(SCH_1):PAGE221_I44@MSTR_DISCRETE.CAP(CHIPS)':
 C_PATH='@baseboard_fab2_lib.baseboard_fab2(sch_1):page221_i44@mstr_discrete.cap~
(chips)',
 P_PATH='@baseboard_fab2_lib.baseboard_fab2(sch_1):page221_i44@mstr_discrete.cap~
(chips)',
 PATH='I44',
 DRAWING='@BASEBOARD_FAB2_LIB.BASEBOARD_FAB2(SCH_1):PAGE221',
 NEW_PN='078.1071T.M002',
 NEW_MATERIAL='X6S',
 TOLERANCE='20%',
 SEC_TYPE='0805',
 MATERIAL='X5R',
 BOM_COST='MEM_VRD_PVDDQ_CD',
 PHYS_PAGE='221',
 XY='(4425,975)',
 ROT='0',
 VER='1',
 VALUE='100UF',
 PACK_TYPE='0805',
 PART_NUMBER='602433-112',
 LOCATION='C6W11',
 ROOM='VDDQ_ABC_PWR_VR',
 GROUP='PWR_MLCC_CAP',
 SEC='1',
 CDS_LIB='mstr_discrete',
 CDS_PART_NAME='CAP_0805-100UF,4V,20%,X5R,6024A',
 VOLTAGE='4V',
 PRIM_FILE='./archive_libs/mstr_discrete/cap/chips/chips.prt';

PART_NAME
 C6W12 'CAP_0805-100UF,4V,20%,X5R,6024A':
 GROUP='PWR_MLCC_CAP',
 ROOM='VDDQ_ABC_PWR_VR';

SECTION_NUMBER 1
 '@BASEBOARD_FAB2_LIB.BASEBOARD_FAB2(SCH_1):PAGE229_I43@MSTR_DISCRETE.CAP(CHIPS)':
 C_PATH='@baseboard_fab2_lib.baseboard_fab2(sch_1):page229_i43@mstr_discrete.cap~
(chips)',
 P_PATH='@baseboard_fab2_lib.baseboard_fab2(sch_1):page229_i43@mstr_discrete.cap~
(chips)',
 PATH='I43',
 DRAWING='@BASEBOARD_FAB2_LIB.BASEBOARD_FAB2(SCH_1):PAGE229',
 NEW_PN='078.1071T.M002',
 NEW_MATERIAL='X6S',
 TOLERANCE='20%',
 SEC_TYPE='0805',
 MATERIAL='X5R',
 BOM_COST='MEM_VRD_PVDDQ_CD',
 PHYS_PAGE='229',
 XY='(4700,900)',
 ROT='0',
 VER='1',
 VALUE='100UF',
 PACK_TYPE='0805',
 PART_NUMBER='602433-112',
 LOCATION='C6W12',
 ROOM='VDDQ_ABC_PWR_VR',
 GROUP='PWR_MLCC_CAP',
 SEC='1',
 CDS_LIB='mstr_discrete',
 CDS_PART_NAME='CAP_0805-100UF,4V,20%,X5R,6024A',
 VOLTAGE='4V',
 PRIM_FILE='./archive_libs/mstr_discrete/cap/chips/chips.prt';

PART_NAME
 C6W13 'CAP_0805-100UF,4V,20%,X5R,6024A':
 GROUP='PWR_MLCC_CAP',
 ROOM='VDDQ_ABC_PWR_VR';

SECTION_NUMBER 1
 '@BASEBOARD_FAB2_LIB.BASEBOARD_FAB2(SCH_1):PAGE230_I43@MSTR_DISCRETE.CAP(CHIPS)':
 C_PATH='@baseboard_fab2_lib.baseboard_fab2(sch_1):page230_i43@mstr_discrete.cap~
(chips)',
 P_PATH='@baseboard_fab2_lib.baseboard_fab2(sch_1):page230_i43@mstr_discrete.cap~
(chips)',
 PATH='I43',
 DRAWING='@BASEBOARD_FAB2_LIB.BASEBOARD_FAB2(SCH_1):PAGE230',
 NEW_PN='078.1071T.M002',
 NEW_MATERIAL='X6S',
 TOLERANCE='20%',
 SEC_TYPE='0805',
 MATERIAL='X5R',
 BOM_COST='MEM_VRD_PVDDQ_CD',
 PHYS_PAGE='230',
 XY='(3125,325)',
 ROT='0',
 VER='1',
 VALUE='100UF',
 PACK_TYPE='0805',
 PART_NUMBER='602433-112',
 LOCATION='C6W13',
 ROOM='VDDQ_ABC_PWR_VR',
 GROUP='PWR_MLCC_CAP',
 SEC='1',
 CDS_LIB='mstr_discrete',
 CDS_PART_NAME='CAP_0805-100UF,4V,20%,X5R,6024A',
 VOLTAGE='4V',
 PRIM_FILE='./archive_libs/mstr_discrete/cap/chips/chips.prt';

PART_NAME
 C6W14 'CAP_A_0402V-0.1UF,16V,10%,X7R,A':
 ROOM='VDDQ_KLM_PWR_VR';

SECTION_NUMBER 1
 '@BASEBOARD_FAB2_LIB.BASEBOARD_FAB2(SCH_1):PAGE164_I66@DEV_DISCRETE.CAP_A(CHIPS)':
 C_PATH='@baseboard_fab2_lib.baseboard_fab2(sch_1):page164_i66@dev_discrete.cap_~
a(chips)',
 P_PATH='@baseboard_fab2_lib.baseboard_fab2(sch_1):page164_i66@dev_discrete.cap_~
a(chips)',
 PATH='I66',
 DRAWING='@BASEBOARD_FAB2_LIB.BASEBOARD_FAB2(SCH_1):PAGE164',
 TOLERANCE='10%',
 SEC_TYPE='0402V',
 MATERIAL='X7R',
 PHYS_PAGE='164',
 XY='(-3400,3900)',
 ROT='0',
 VER='1',
 VALUE='0.1UF',
 PACK_TYPE='0402V',
 PART_NUMBER='A36096-030',
 LOCATION='C6W14',
 ROOM='VDDQ_KLM_PWR_VR',
 SEC='1',
 CDS_LIB='dev_discrete',
 CDS_PART_NAME='CAP_A_0402V-0.1UF,16V,10%,X7R,A',
 VOLTAGE='16V',
 PRIM_FILE='./archive_libs/discrete/cap_a/chips/chips.prt';

PART_NAME
 C7A5 'CAP_A_0402V-0.1UF,16V,10%,X7R,A':
 ROOM='VDDQ_DEF_PWR_VR';

SECTION_NUMBER 1
 '@BASEBOARD_FAB2_LIB.BASEBOARD_FAB2(SCH_1):PAGE219_I51@DEV_DISCRETE.CAP_A(CHIPS)':
 C_PATH='@baseboard_fab2_lib.baseboard_fab2(sch_1):page219_i51@dev_discrete.cap_~
a(chips)',
 P_PATH='@baseboard_fab2_lib.baseboard_fab2(sch_1):page219_i51@dev_discrete.cap_~
a(chips)',
 PATH='I51',
 DRAWING='@BASEBOARD_FAB2_LIB.BASEBOARD_FAB2(SCH_1):PAGE219',
 TOLERANCE='10%',
 SEC_TYPE='0402V',
 MATERIAL='X7R',
 PHYS_PAGE='219',
 XY='(-1175,2425)',
 ROT='0',
 VER='1',
 VALUE='0.1UF',
 PACK_TYPE='0402V',
 PART_NUMBER='A36096-030',
 LOCATION='C7A5',
 ROOM='VDDQ_DEF_PWR_VR',
 SEC='1',
 CDS_LIB='dev_discrete',
 CDS_PART_NAME='CAP_A_0402V-0.1UF,16V,10%,X7R,A',
 VOLTAGE='16V',
 PRIM_FILE='./archive_libs/discrete/cap_a/chips/chips.prt';

PART_NAME
 C7A6 'CAP_0402-1.0UF,16V,10%,X6S,D97A':
 ROOM='P1V05_PCH_STBY_VR';

SECTION_NUMBER 1
 '@BASEBOARD_FAB2_LIB.BASEBOARD_FAB2(SCH_1):PAGE236_I19@MSTR_DISCRETE.CAP(CHIPS)':
 C_PATH='@baseboard_fab2_lib.baseboard_fab2(sch_1):page236_i19@mstr_discrete.cap~
(chips)',
 P_PATH='@baseboard_fab2_lib.baseboard_fab2(sch_1):page236_i19@mstr_discrete.cap~
(chips)',
 PATH='I19',
 DRAWING='@BASEBOARD_FAB2_LIB.BASEBOARD_FAB2(SCH_1):PAGE236',
 TOLERANCE='10%',
 SEC_TYPE='0402',
 MATERIAL='X6S',
 PHYS_PAGE='236',
 XY='(7300,4500)',
 ROT='0',
 VER='1',
 VALUE='1.0UF',
 PACK_TYPE='0402',
 PART_NUMBER='D97712-011',
 LOCATION='C7A6',
 ROOM='P1V05_PCH_STBY_VR',
 SEC='1',
 CDS_LIB='mstr_discrete',
 CDS_PART_NAME='CAP_0402-1.0UF,16V,10%,X6S,D97A',
 VOLTAGE='16V',
 PRIM_FILE='./archive_libs/mstr_discrete/cap/chips/chips.prt';

PART_NAME
 C7A7 'CAP_0402-1.0UF,16V,10%,X6S,D97A':
 ROOM='PVNN_PCH_STBY';

SECTION_NUMBER 1
 '@BASEBOARD_FAB2_LIB.BASEBOARD_FAB2(SCH_1):PAGE236_I22@MSTR_DISCRETE.CAP(CHIPS)':
 C_PATH='@baseboard_fab2_lib.baseboard_fab2(sch_1):page236_i22@mstr_discrete.cap~
(chips)',
 P_PATH='@baseboard_fab2_lib.baseboard_fab2(sch_1):page236_i22@mstr_discrete.cap~
(chips)',
 PATH='I22',
 DRAWING='@BASEBOARD_FAB2_LIB.BASEBOARD_FAB2(SCH_1):PAGE236',
 TOLERANCE='10%',
 SEC_TYPE='0402',
 MATERIAL='X6S',
 PHYS_PAGE='236',
 XY='(6775,4500)',
 ROT='0',
 VER='1',
 VALUE='1.0UF',
 PACK_TYPE='0402',
 PART_NUMBER='D97712-011',
 LOCATION='C7A7',
 ROOM='PVNN_PCH_STBY',
 SEC='1',
 CDS_LIB='mstr_discrete',
 CDS_PART_NAME='CAP_0402-1.0UF,16V,10%,X6S,D97A',
 VOLTAGE='16V',
 PRIM_FILE='./archive_libs/mstr_discrete/cap/chips/chips.prt';

PART_NAME
 C7A8 'CAP_0402-0.22UF,16V,10%,X7R,A3A':
 ROOM='PVNN_PCH_STBY';

SECTION_NUMBER 1
 '@BASEBOARD_FAB2_LIB.BASEBOARD_FAB2(SCH_1):PAGE236_I16@MSTR_DISCRETE.CAP(CHIPS)':
 C_PATH='@baseboard_fab2_lib.baseboard_fab2(sch_1):page236_i16@mstr_discrete.cap~
(chips)',
 P_PATH='@baseboard_fab2_lib.baseboard_fab2(sch_1):page236_i16@mstr_discrete.cap~
(chips)',
 PATH='I16',
 DRAWING='@BASEBOARD_FAB2_LIB.BASEBOARD_FAB2(SCH_1):PAGE236',
 TOLERANCE='10%',
 SEC_TYPE='0402',
 MATERIAL='X7R',
 PHYS_PAGE='236',
 XY='(8125,4575)',
 ROT='0',
 VER='1',
 VALUE='0.22UF',
 PACK_TYPE='0402',
 PART_NUMBER='A36096-155',
 LOCATION='C7A8',
 ROOM='PVNN_PCH_STBY',
 SEC='1',
 CDS_LIB='mstr_discrete',
 CDS_PART_NAME='CAP_0402-0.22UF,16V,10%,X7R,A3A',
 VOLTAGE='16V',
 PRIM_FILE='./archive_libs/mstr_discrete/cap/chips/chips.prt';

PART_NAME
 C7A9 'CAP_0402-1.0UF,16V,10%,X6S,D97A':
 ROOM='P1V05_PCH_STBY_VR';

SECTION_NUMBER 1
 '@BASEBOARD_FAB2_LIB.BASEBOARD_FAB2(SCH_1):PAGE236_I33@MSTR_DISCRETE.CAP(CHIPS)':
 C_PATH='@baseboard_fab2_lib.baseboard_fab2(sch_1):page236_i33@mstr_discrete.cap~
(chips)',
 P_PATH='@baseboard_fab2_lib.baseboard_fab2(sch_1):page236_i33@mstr_discrete.cap~
(chips)',
 PATH='I33',
 DRAWING='@BASEBOARD_FAB2_LIB.BASEBOARD_FAB2(SCH_1):PAGE236',
 TOLERANCE='10%',
 SEC_TYPE='0402',
 MATERIAL='X6S',
 PHYS_PAGE='236',
 XY='(6700,2800)',
 ROT='0',
 VER='1',
 VALUE='1.0UF',
 PACK_TYPE='0402',
 PART_NUMBER='D97712-011',
 LOCATION='C7A9',
 ROOM='P1V05_PCH_STBY_VR',
 SEC='1',
 CDS_LIB='mstr_discrete',
 CDS_PART_NAME='CAP_0402-1.0UF,16V,10%,X6S,D97A',
 VOLTAGE='16V',
 PRIM_FILE='./archive_libs/mstr_discrete/cap/chips/chips.prt';

PART_NAME
 C7A10 'CAP_0402-1.0UF,16V,10%,X6S,D97A':
 ROOM='P1V05_PCH_STBY_VR';

SECTION_NUMBER 1
 '@BASEBOARD_FAB2_LIB.BASEBOARD_FAB2(SCH_1):PAGE236_I36@MSTR_DISCRETE.CAP(CHIPS)':
 C_PATH='@baseboard_fab2_lib.baseboard_fab2(sch_1):page236_i36@mstr_discrete.cap~
(chips)',
 P_PATH='@baseboard_fab2_lib.baseboard_fab2(sch_1):page236_i36@mstr_discrete.cap~
(chips)',
 PATH='I36',
 DRAWING='@BASEBOARD_FAB2_LIB.BASEBOARD_FAB2(SCH_1):PAGE236',
 TOLERANCE='10%',
 SEC_TYPE='0402',
 MATERIAL='X6S',
 PHYS_PAGE='236',
 XY='(7175,2800)',
 ROT='0',
 VER='1',
 VALUE='1.0UF',
 PACK_TYPE='0402',
 PART_NUMBER='D97712-011',
 LOCATION='C7A10',
 ROOM='P1V05_PCH_STBY_VR',
 SEC='1',
 CDS_LIB='mstr_discrete',
 CDS_PART_NAME='CAP_0402-1.0UF,16V,10%,X6S,D97A',
 VOLTAGE='16V',
 PRIM_FILE='./archive_libs/mstr_discrete/cap/chips/chips.prt';

PART_NAME
 C7A11 'CAP_0402-1.0UF,16V,10%,X6S,D97A':
 ROOM='VDDQ_DEF_PWR_VR';

SECTION_NUMBER 1
 '@BASEBOARD_FAB2_LIB.BASEBOARD_FAB2(SCH_1):PAGE219_I48@MSTR_DISCRETE.CAP(CHIPS)':
 C_PATH='@baseboard_fab2_lib.baseboard_fab2(sch_1):page219_i48@mstr_discrete.cap~
(chips)',
 P_PATH='@baseboard_fab2_lib.baseboard_fab2(sch_1):page219_i48@mstr_discrete.cap~
(chips)',
 PATH='I48',
 DRAWING='@BASEBOARD_FAB2_LIB.BASEBOARD_FAB2(SCH_1):PAGE219',
 TOLERANCE='10%',
 SEC_TYPE='0402',
 MATERIAL='X6S',
 PHYS_PAGE='219',
 XY='(-1475,2425)',
 ROT='0',
 VER='1',
 VALUE='1.0UF',
 PACK_TYPE='0402',
 PART_NUMBER='D97712-011',
 LOCATION='C7A11',
 ROOM='VDDQ_DEF_PWR_VR',
 SEC='1',
 CDS_LIB='mstr_discrete',
 CDS_PART_NAME='CAP_0402-1.0UF,16V,10%,X6S,D97A',
 VOLTAGE='16V',
 PRIM_FILE='./archive_libs/mstr_discrete/cap/chips/chips.prt';

PART_NAME
 C7A12 'CAP_0402-0.220UF,16V,10%,X7R,AA':
 ROOM='VDDQ_DEF_PWR_VR';

SECTION_NUMBER 1
 '@BASEBOARD_FAB2_LIB.BASEBOARD_FAB2(SCH_1):PAGE219_I44@MSTR_DISCRETE.CAP(CHIPS)':
 C_PATH='@baseboard_fab2_lib.baseboard_fab2(sch_1):page219_i44@mstr_discrete.cap~
(chips)',
 P_PATH='@baseboard_fab2_lib.baseboard_fab2(sch_1):page219_i44@mstr_discrete.cap~
(chips)',
 PATH='I44',
 DRAWING='@BASEBOARD_FAB2_LIB.BASEBOARD_FAB2(SCH_1):PAGE219',
 SPOF='TRUE',
 TOLERANCE='10%',
 SEC_TYPE='0402',
 MATERIAL='X7R',
 PHYS_PAGE='219',
 XY='(-1100,1775)',
 ROT='2',
 VER='1',
 VALUE='0.220UF',
 PACK_TYPE='0402',
 PART_NUMBER='A36096-104',
 LOCATION='C7A12',
 ROOM='VDDQ_DEF_PWR_VR',
 SEC='1',
 CDS_LIB='mstr_discrete',
 CDS_PART_NAME='CAP_0402-0.220UF,16V,10%,X7R,AA',
 VOLTAGE='16V',
 PRIM_FILE='./archive_libs/mstr_discrete/cap/chips/chips.prt';

PART_NAME
 C7A13 'SC22U16V5MX-4-GP_SMD-BCG5-SC22A':;

SECTION_NUMBER 1
 '@BASEBOARD_FAB2_LIB.BASEBOARD_FAB2(SCH_1):PAGE236_I161@W_HDL.SC22U16V5MX-4-GP(CHIPS)':
 C_PATH='@baseboard_fab2_lib.baseboard_fab2(sch_1):page236_i161@w_hdl.\sc22u16v5~
mx-4-gp\(chips)',
 P_PATH='@baseboard_fab2_lib.baseboard_fab2(sch_1):page236_i161@w_hdl.\sc22u16v5~
mx-4-gp\(chips)',
 PATH='I161',
 DRAWING='@BASEBOARD_FAB2_LIB.BASEBOARD_FAB2(SCH_1):PAGE236',
 TYPE='X6S',
 PACK_SIZE='0805',
 RATED='16V',
 ATTRIBUTE='22UF',
 TOLERANCE='20%',
 SEC_TYPE='SMD-BCG5',
 PHYS_PAGE='236',
 XY='(11800,975)',
 ROT='0',
 VER='1',
 VALUE='SC22U16V5MX-4-GP',
 PACK_TYPE='SMD-BCG5',
 PART_NUMBER='078.22611.0811',
 LOCATION='C7A13',
 SEC='1',
 CDS_LIB='w_hdl',
 CDS_PART_NAME='SC22U16V5MX-4-GP_SMD-BCG5-SC22A',
 PRIM_FILE='C:/<user>/w_hdl/sc22u16v5mx#2d4#2dgp/chips/chips.prt';

PART_NAME
 C7A14 'SC22U16V5MX-4-GP_SMD-BCG5-SC22A':;

SECTION_NUMBER 1
 '@BASEBOARD_FAB2_LIB.BASEBOARD_FAB2(SCH_1):PAGE236_I172@W_HDL.SC22U16V5MX-4-GP(CHIPS)':
 C_PATH='@baseboard_fab2_lib.baseboard_fab2(sch_1):page236_i172@w_hdl.\sc22u16v5~
mx-4-gp\(chips)',
 P_PATH='@baseboard_fab2_lib.baseboard_fab2(sch_1):page236_i172@w_hdl.\sc22u16v5~
mx-4-gp\(chips)',
 PATH='I172',
 DRAWING='@BASEBOARD_FAB2_LIB.BASEBOARD_FAB2(SCH_1):PAGE236',
 TYPE='X6S',
 PACK_SIZE='0805',
 RATED='16V',
 ATTRIBUTE='22UF',
 TOLERANCE='20%',
 SEC_TYPE='SMD-BCG5',
 PHYS_PAGE='236',
 XY='(10550,975)',
 ROT='0',
 VER='1',
 VALUE='SC22U16V5MX-4-GP',
 PACK_TYPE='SMD-BCG5',
 PART_NUMBER='078.22611.0811',
 LOCATION='C7A14',
 SEC='1',
 CDS_LIB='w_hdl',
 CDS_PART_NAME='SC22U16V5MX-4-GP_SMD-BCG5-SC22A',
 PRIM_FILE='C:/<user>/w_hdl/sc22u16v5mx#2d4#2dgp/chips/chips.prt';

PART_NAME
 C7A16 'CAP_0402-1.0UF,16V,10%,X6S,D97A':
 ROOM='VDDQ_DEF_PWR_VR';

SECTION_NUMBER 1
 '@BASEBOARD_FAB2_LIB.BASEBOARD_FAB2(SCH_1):PAGE219_I50@MSTR_DISCRETE.CAP(CHIPS)':
 C_PATH='@baseboard_fab2_lib.baseboard_fab2(sch_1):page219_i50@mstr_discrete.cap~
(chips)',
 P_PATH='@baseboard_fab2_lib.baseboard_fab2(sch_1):page219_i50@mstr_discrete.cap~
(chips)',
 PATH='I50',
 DRAWING='@BASEBOARD_FAB2_LIB.BASEBOARD_FAB2(SCH_1):PAGE219',
 TOLERANCE='10%',
 SEC_TYPE='0402',
 MATERIAL='X6S',
 PHYS_PAGE='219',
 XY='(-875,2425)',
 ROT='0',
 VER='1',
 VALUE='1.0UF',
 PACK_TYPE='0402',
 PART_NUMBER='D97712-011',
 LOCATION='C7A16',
 ROOM='VDDQ_DEF_PWR_VR',
 SEC='1',
 CDS_LIB='mstr_discrete',
 CDS_PART_NAME='CAP_0402-1.0UF,16V,10%,X6S,D97A',
 VOLTAGE='16V',
 PRIM_FILE='./archive_libs/mstr_discrete/cap/chips/chips.prt';

PART_NAME
 C7A17 'CAP_0402-0.22UF,16V,10%,X7R,A3A':
 ROOM='VDDQ_DEF_PWR_VR';

SECTION_NUMBER 1
 '@BASEBOARD_FAB2_LIB.BASEBOARD_FAB2(SCH_1):PAGE219_I54@MSTR_DISCRETE.CAP(CHIPS)':
 C_PATH='@baseboard_fab2_lib.baseboard_fab2(sch_1):page219_i54@mstr_discrete.cap~
(chips)',
 P_PATH='@baseboard_fab2_lib.baseboard_fab2(sch_1):page219_i54@mstr_discrete.cap~
(chips)',
 PATH='I54',
 DRAWING='@BASEBOARD_FAB2_LIB.BASEBOARD_FAB2(SCH_1):PAGE219',
 TOLERANCE='10%',
 SEC_TYPE='0402',
 MATERIAL='X7R',
 PHYS_PAGE='219',
 XY='(-125,2425)',
 ROT='0',
 VER='1',
 VALUE='0.22UF',
 PACK_TYPE='0402',
 PART_NUMBER='A36096-155',
 LOCATION='C7A17',
 ROOM='VDDQ_DEF_PWR_VR',
 SEC='1',
 CDS_LIB='mstr_discrete',
 CDS_PART_NAME='CAP_0402-0.22UF,16V,10%,X7R,A3A',
 VOLTAGE='16V',
 PRIM_FILE='./archive_libs/mstr_discrete/cap/chips/chips.prt';

PART_NAME
 C7A18 'SC1U10V2KX-4-GP_SMD-BCG6-SC1U1A':;

SECTION_NUMBER 1
 '@BASEBOARD_FAB2_LIB.BASEBOARD_FAB2(SCH_1):PAGE219_I151@W_HDL.SC1U10V2KX-4-GP(CHIPS)':
 C_PATH='@baseboard_fab2_lib.baseboard_fab2(sch_1):page219_i151@w_hdl.\sc1u10v2k~
x-4-gp\(chips)',
 P_PATH='@baseboard_fab2_lib.baseboard_fab2(sch_1):page219_i151@w_hdl.\sc1u10v2k~
x-4-gp\(chips)',
 PATH='I151',
 DRAWING='@BASEBOARD_FAB2_LIB.BASEBOARD_FAB2(SCH_1):PAGE219',
 PACK_SIZE='0402',
 RATED='10V',
 ATTRIBUTE='1UF',
 TOLERANCE='10%',
 SEC_TYPE='SMD-BCG6',
 PHYS_PAGE='219',
 XY='(-450,2350)',
 ROT='0',
 VER='1',
 VALUE='SC1U10V2KX-4-GP',
 PACK_TYPE='SMD-BCG6',
 PART_NUMBER='78.10523.8FL',
 LOCATION='C7A18',
 SEC='1',
 CDS_LIB='w_hdl',
 CDS_PART_NAME='SC1U10V2KX-4-GP_SMD-BCG6-SC1U1A',
 PRIM_FILE='C:/<user>/w_hdl/sc1u10v2kx#2d4#2dgp/chips/chips.prt';

PART_NAME
 C7A20 'CAP_A_0402V-0.1UF,16V,10%,X7R,A':
 ROOM='VDDQ_DEF_PWR_VR';

SECTION_NUMBER 1
 '@BASEBOARD_FAB2_LIB.BASEBOARD_FAB2(SCH_1):PAGE219_I78@DEV_DISCRETE.CAP_A(CHIPS)':
 C_PATH='@baseboard_fab2_lib.baseboard_fab2(sch_1):page219_i78@dev_discrete.cap_~
a(chips)',
 P_PATH='@baseboard_fab2_lib.baseboard_fab2(sch_1):page219_i78@dev_discrete.cap_~
a(chips)',
 PATH='I78',
 DRAWING='@BASEBOARD_FAB2_LIB.BASEBOARD_FAB2(SCH_1):PAGE219',
 TOLERANCE='10%',
 SEC_TYPE='0402V',
 MATERIAL='X7R',
 PHYS_PAGE='219',
 XY='(-1250,75)',
 ROT='0',
 VER='1',
 VALUE='0.1UF',
 PACK_TYPE='0402V',
 PART_NUMBER='A36096-030',
 LOCATION='C7A20',
 ROOM='VDDQ_DEF_PWR_VR',
 SEC='1',
 CDS_LIB='dev_discrete',
 CDS_PART_NAME='CAP_A_0402V-0.1UF,16V,10%,X7R,A',
 VOLTAGE='16V',
 PRIM_FILE='./archive_libs/discrete/cap_a/chips/chips.prt';

PART_NAME
 C7A21 'CAP_0402-1.0UF,16V,10%,X6S,D97A':
 ROOM='VDDQ_DEF_PWR_VR';

SECTION_NUMBER 1
 '@BASEBOARD_FAB2_LIB.BASEBOARD_FAB2(SCH_1):PAGE219_I79@MSTR_DISCRETE.CAP(CHIPS)':
 C_PATH='@baseboard_fab2_lib.baseboard_fab2(sch_1):page219_i79@mstr_discrete.cap~
(chips)',
 P_PATH='@baseboard_fab2_lib.baseboard_fab2(sch_1):page219_i79@mstr_discrete.cap~
(chips)',
 PATH='I79',
 DRAWING='@BASEBOARD_FAB2_LIB.BASEBOARD_FAB2(SCH_1):PAGE219',
 TOLERANCE='10%',
 SEC_TYPE='0402',
 MATERIAL='X6S',
 PHYS_PAGE='219',
 XY='(-1525,75)',
 ROT='0',
 VER='1',
 VALUE='1.0UF',
 PACK_TYPE='0402',
 PART_NUMBER='D97712-011',
 LOCATION='C7A21',
 ROOM='VDDQ_DEF_PWR_VR',
 SEC='1',
 CDS_LIB='mstr_discrete',
 CDS_PART_NAME='CAP_0402-1.0UF,16V,10%,X6S,D97A',
 VOLTAGE='16V',
 PRIM_FILE='./archive_libs/mstr_discrete/cap/chips/chips.prt';

PART_NAME
 C7A22 'CAP_0402-0.220UF,16V,10%,X7R,AA':
 ROOM='VDDQ_DEF_PWR_VR';

SECTION_NUMBER 1
 '@BASEBOARD_FAB2_LIB.BASEBOARD_FAB2(SCH_1):PAGE219_I75@MSTR_DISCRETE.CAP(CHIPS)':
 C_PATH='@baseboard_fab2_lib.baseboard_fab2(sch_1):page219_i75@mstr_discrete.cap~
(chips)',
 P_PATH='@baseboard_fab2_lib.baseboard_fab2(sch_1):page219_i75@mstr_discrete.cap~
(chips)',
 PATH='I75',
 DRAWING='@BASEBOARD_FAB2_LIB.BASEBOARD_FAB2(SCH_1):PAGE219',
 BOM_SS='NOPOP',
 SPOF='TRUE',
 TOLERANCE='10%',
 SEC_TYPE='0402',
 MATERIAL='X7R',
 PHYS_PAGE='219',
 XY='(-800,-525)',
 ROT='2',
 VER='1',
 VALUE='0.220UF',
 PACK_TYPE='0402',
 PART_NUMBER='A36096-104',
 LOCATION='C7A22',
 ROOM='VDDQ_DEF_PWR_VR',
 SEC='1',
 CDS_LIB='mstr_discrete',
 CDS_PART_NAME='CAP_0402-0.220UF,16V,10%,X7R,AA',
 VOLTAGE='16V',
 PRIM_FILE='./archive_libs/mstr_discrete/cap/chips/chips.prt';

PART_NAME
 C7A24 'CAP_0402-1.0UF,16V,10%,X6S,D97A':
 ROOM='VDDQ_DEF_PWR_VR';

SECTION_NUMBER 1
 '@BASEBOARD_FAB2_LIB.BASEBOARD_FAB2(SCH_1):PAGE219_I77@MSTR_DISCRETE.CAP(CHIPS)':
 C_PATH='@baseboard_fab2_lib.baseboard_fab2(sch_1):page219_i77@mstr_discrete.cap~
(chips)',
 P_PATH='@baseboard_fab2_lib.baseboard_fab2(sch_1):page219_i77@mstr_discrete.cap~
(chips)',
 PATH='I77',
 DRAWING='@BASEBOARD_FAB2_LIB.BASEBOARD_FAB2(SCH_1):PAGE219',
 BOM_SS='NOPOP',
 TOLERANCE='10%',
 SEC_TYPE='0402',
 MATERIAL='X6S',
 PHYS_PAGE='219',
 XY='(-925,75)',
 ROT='0',
 VER='1',
 VALUE='1.0UF',
 PACK_TYPE='0402',
 PART_NUMBER='D97712-011',
 LOCATION='C7A24',
 ROOM='VDDQ_DEF_PWR_VR',
 SEC='1',
 CDS_LIB='mstr_discrete',
 CDS_PART_NAME='CAP_0402-1.0UF,16V,10%,X6S,D97A',
 VOLTAGE='16V',
 PRIM_FILE='./archive_libs/mstr_discrete/cap/chips/chips.prt';

PART_NAME
 C7A25 'CAP_0402-0.22UF,16V,10%,X7R,A3A':
 ROOM='VDDQ_DEF_PWR_VR';

SECTION_NUMBER 1
 '@BASEBOARD_FAB2_LIB.BASEBOARD_FAB2(SCH_1):PAGE219_I72@MSTR_DISCRETE.CAP(CHIPS)':
 C_PATH='@baseboard_fab2_lib.baseboard_fab2(sch_1):page219_i72@mstr_discrete.cap~
(chips)',
 P_PATH='@baseboard_fab2_lib.baseboard_fab2(sch_1):page219_i72@mstr_discrete.cap~
(chips)',
 PATH='I72',
 DRAWING='@BASEBOARD_FAB2_LIB.BASEBOARD_FAB2(SCH_1):PAGE219',
 BOM_SS='NOPOP',
 TOLERANCE='10%',
 SEC_TYPE='0402',
 MATERIAL='X7R',
 PHYS_PAGE='219',
 XY='(-100,175)',
 ROT='0',
 VER='1',
 VALUE='0.22UF',
 PACK_TYPE='0402',
 PART_NUMBER='A36096-155',
 LOCATION='C7A25',
 ROOM='VDDQ_DEF_PWR_VR',
 SEC='1',
 CDS_LIB='mstr_discrete',
 CDS_PART_NAME='CAP_0402-0.22UF,16V,10%,X7R,A3A',
 VOLTAGE='16V',
 PRIM_FILE='./archive_libs/mstr_discrete/cap/chips/chips.prt';

PART_NAME
 C7A26 'SC1U10V2KX-4-GP_SMD-BCG6-SC1U1A':;

SECTION_NUMBER 1
 '@BASEBOARD_FAB2_LIB.BASEBOARD_FAB2(SCH_1):PAGE219_I152@W_HDL.SC1U10V2KX-4-GP(CHIPS)':
 C_PATH='@baseboard_fab2_lib.baseboard_fab2(sch_1):page219_i152@w_hdl.\sc1u10v2k~
x-4-gp\(chips)',
 P_PATH='@baseboard_fab2_lib.baseboard_fab2(sch_1):page219_i152@w_hdl.\sc1u10v2k~
x-4-gp\(chips)',
 PATH='I152',
 DRAWING='@BASEBOARD_FAB2_LIB.BASEBOARD_FAB2(SCH_1):PAGE219',
 PACK_SIZE='0402',
 RATED='10V',
 ATTRIBUTE='1UF',
 BOM_SS='NOPOP',
 TOLERANCE='10%',
 SEC_TYPE='SMD-BCG6',
 PHYS_PAGE='219',
 XY='(-525,100)',
 ROT='0',
 VER='1',
 VALUE='SC1U10V2KX-4-GP',
 PACK_TYPE='SMD-BCG6',
 PART_NUMBER='78.10523.8FL',
 LOCATION='C7A26',
 SEC='1',
 CDS_LIB='w_hdl',
 CDS_PART_NAME='SC1U10V2KX-4-GP_SMD-BCG6-SC1U1A',
 PRIM_FILE='C:/<user>/w_hdl/sc1u10v2kx#2d4#2dgp/chips/chips.prt';

PART_NAME
 C7A27 'CAPP_SM-470UF,2V,20%,ALUM,6990A':
 ROOM='PVNN_PCH_STBY';

SECTION_NUMBER 1
 '@BASEBOARD_FAB2_LIB.BASEBOARD_FAB2(SCH_1):PAGE236_I75@MSTR_DISCRETE.CAPP(CHIPS)':
 C_PATH='@baseboard_fab2_lib.baseboard_fab2(sch_1):page236_i75@mstr_discrete.cap~
p(chips)',
 P_PATH='@baseboard_fab2_lib.baseboard_fab2(sch_1):page236_i75@mstr_discrete.cap~
p(chips)',
 PATH='I75',
 DRAWING='@BASEBOARD_FAB2_LIB.BASEBOARD_FAB2(SCH_1):PAGE236',
 TOLERANCE='20%',
 SEC_TYPE='SM',
 MATERIAL='ALUM',
 PHYS_PAGE='236',
 XY='(12850,3775)',
 ROT='0',
 VER='1',
 VALUE='470UF',
 PACK_TYPE='SM',
 PART_NUMBER='699013-031',
 LOCATION='C7A27',
 ROOM='PVNN_PCH_STBY',
 SEC='1',
 CDS_LIB='mstr_discrete',
 CDS_PART_NAME='CAPP_SM-470UF,2V,20%,ALUM,6990A',
 VOLTAGE='2V',
 PRIM_FILE='./archive_libs/mstr_discrete/capp/chips/chips.prt';

PART_NAME
 C7A28 'CAP_0402LF-220PF,50V,10%,X7R,AA':
 ROOM='VDDQ_DEF_PWR_VR';

SECTION_NUMBER 1
 '@BASEBOARD_FAB2_LIB.BASEBOARD_FAB2(SCH_1):PAGE218_I14@MSTR_DISCRETE.CAP(CHIPS)':
 C_PATH='@baseboard_fab2_lib.baseboard_fab2(sch_1):page218_i14@mstr_discrete.cap~
(chips)',
 P_PATH='@baseboard_fab2_lib.baseboard_fab2(sch_1):page218_i14@mstr_discrete.cap~
(chips)',
 PATH='I14',
 DRAWING='@BASEBOARD_FAB2_LIB.BASEBOARD_FAB2(SCH_1):PAGE218',
 TOLERANCE='10%',
 SEC_TYPE='0402LF',
 MATERIAL='X7R',
 PHYS_PAGE='218',
 XY='(-2650,725)',
 ROT='0',
 VER='1',
 VALUE='220PF',
 PACK_TYPE='0402LF',
 PART_NUMBER='A36096-050',
 LOCATION='C7A28',
 ROOM='VDDQ_DEF_PWR_VR',
 SEC='1',
 CDS_LIB='mstr_discrete',
 CDS_PART_NAME='CAP_0402LF-220PF,50V,10%,X7R,AA',
 VOLTAGE='50V',
 PRIM_FILE='./archive_libs/mstr_discrete/cap/chips/chips.prt';

PART_NAME
 C7A29 'CAP_0402LF-220PF,50V,10%,X7R,AA':
 ROOM='VDDQ_DEF_PWR_VR';

SECTION_NUMBER 1
 '@BASEBOARD_FAB2_LIB.BASEBOARD_FAB2(SCH_1):PAGE218_I16@MSTR_DISCRETE.CAP(CHIPS)':
 C_PATH='@baseboard_fab2_lib.baseboard_fab2(sch_1):page218_i16@mstr_discrete.cap~
(chips)',
 P_PATH='@baseboard_fab2_lib.baseboard_fab2(sch_1):page218_i16@mstr_discrete.cap~
(chips)',
 PATH='I16',
 DRAWING='@BASEBOARD_FAB2_LIB.BASEBOARD_FAB2(SCH_1):PAGE218',
 TOLERANCE='10%',
 SEC_TYPE='0402LF',
 MATERIAL='X7R',
 PHYS_PAGE='218',
 XY='(-1250,450)',
 ROT='2',
 VER='1',
 VALUE='220PF',
 PACK_TYPE='0402LF',
 PART_NUMBER='A36096-050',
 LOCATION='C7A29',
 ROOM='VDDQ_DEF_PWR_VR',
 SEC='1',
 CDS_LIB='mstr_discrete',
 CDS_PART_NAME='CAP_0402LF-220PF,50V,10%,X7R,AA',
 VOLTAGE='50V',
 PRIM_FILE='./archive_libs/mstr_discrete/cap/chips/chips.prt';

PART_NAME
 C7A30 'CAP_0805LF-22UF,4V,20%,X6S,C95A':
 ROOM='PVNN_PCH_STBY';

SECTION_NUMBER 1
 '@BASEBOARD_FAB2_LIB.BASEBOARD_FAB2(SCH_1):PAGE236_I9@MSTR_DISCRETE.CAP(CHIPS)':
 C_PATH='@baseboard_fab2_lib.baseboard_fab2(sch_1):page236_i9@mstr_discrete.cap(~
chips)',
 P_PATH='@baseboard_fab2_lib.baseboard_fab2(sch_1):page236_i9@mstr_discrete.cap(~
chips)',
 PATH='I9',
 DRAWING='@BASEBOARD_FAB2_LIB.BASEBOARD_FAB2(SCH_1):PAGE236',
 TOLERANCE='20%',
 SEC_TYPE='0805LF',
 MATERIAL='X6S',
 BOM_COST='PROC_VRD_PVCCIO_CPU0',
 PHYS_PAGE='236',
 XY='(11725,3775)',
 ROT='0',
 VER='1',
 VALUE='22UF',
 PACK_TYPE='0805LF',
 PART_NUMBER='C95333-002',
 LOCATION='C7A30',
 ROOM='PVNN_PCH_STBY',
 SEC='1',
 CDS_LIB='mstr_discrete',
 CDS_PART_NAME='CAP_0805LF-22UF,4V,20%,X6S,C95A',
 VOLTAGE='4V',
 PRIM_FILE='./archive_libs/mstr_discrete/cap/chips/chips.prt';

PART_NAME
 C7A31 'CAP_0805-47UF,4V,20%,X6S,C9533A':
 ROOM='SB_DECOUPLING';

SECTION_NUMBER 1
 '@BASEBOARD_FAB2_LIB.BASEBOARD_FAB2(SCH_1):PAGE132_I40@MSTR_DISCRETE.CAP(CHIPS)':
 C_PATH='@baseboard_fab2_lib.baseboard_fab2(sch_1):page132_i40@mstr_discrete.cap~
(chips)',
 P_PATH='@baseboard_fab2_lib.baseboard_fab2(sch_1):page132_i40@mstr_discrete.cap~
(chips)',
 PATH='I40',
 DRAWING='@BASEBOARD_FAB2_LIB.BASEBOARD_FAB2(SCH_1):PAGE132',
 TOLERANCE='20%',
 MATERIAL='X6S',
 BOM_COST='SB',
 PHYS_PAGE='132',
 XY='(-1100,1900)',
 ROT='0',
 VER='1',
 VALUE='47UF',
 PACK_TYPE='0805',
 PART_NUMBER='C95333-006',
 LOCATION='C7A31',
 ROOM='SB_DECOUPLING',
 CDS_LIB='mstr_discrete',
 CDS_PART_NAME='CAP_0805-47UF,4V,20%,X6S,C9533A',
 VOLTAGE='4V',
 PRIM_FILE='./archive_libs/mstr_discrete/cap/chips/chips.prt';

PART_NAME
 C7A32 'CAP_0805-47UF,4V,20%,X6S,C9533A':
 ROOM='SB_DECOUPLING';

SECTION_NUMBER 1
 '@BASEBOARD_FAB2_LIB.BASEBOARD_FAB2(SCH_1):PAGE132_I38@MSTR_DISCRETE.CAP(CHIPS)':
 C_PATH='@baseboard_fab2_lib.baseboard_fab2(sch_1):page132_i38@mstr_discrete.cap~
(chips)',
 P_PATH='@baseboard_fab2_lib.baseboard_fab2(sch_1):page132_i38@mstr_discrete.cap~
(chips)',
 PATH='I38',
 DRAWING='@BASEBOARD_FAB2_LIB.BASEBOARD_FAB2(SCH_1):PAGE132',
 TOLERANCE='20%',
 MATERIAL='X6S',
 BOM_COST='SB',
 PHYS_PAGE='132',
 XY='(-650,1900)',
 ROT='0',
 VER='1',
 VALUE='47UF',
 PACK_TYPE='0805',
 PART_NUMBER='C95333-006',
 LOCATION='C7A32',
 ROOM='SB_DECOUPLING',
 CDS_LIB='mstr_discrete',
 CDS_PART_NAME='CAP_0805-47UF,4V,20%,X6S,C9533A',
 VOLTAGE='4V',
 PRIM_FILE='./archive_libs/mstr_discrete/cap/chips/chips.prt';

PART_NAME
 C7A33 'CAP_0805-47UF,4V,20%,X6S,C9533A':
 ROOM='SB_DECOUPLING';

SECTION_NUMBER 1
 '@BASEBOARD_FAB2_LIB.BASEBOARD_FAB2(SCH_1):PAGE132_I23@MSTR_DISCRETE.CAP(CHIPS)':
 C_PATH='@baseboard_fab2_lib.baseboard_fab2(sch_1):page132_i23@mstr_discrete.cap~
(chips)',
 P_PATH='@baseboard_fab2_lib.baseboard_fab2(sch_1):page132_i23@mstr_discrete.cap~
(chips)',
 PATH='I23',
 DRAWING='@BASEBOARD_FAB2_LIB.BASEBOARD_FAB2(SCH_1):PAGE132',
 TOLERANCE='20%',
 MATERIAL='X6S',
 BOM_COST='SB',
 PHYS_PAGE='132',
 XY='(2150,1575)',
 ROT='0',
 VER='1',
 VALUE='47UF',
 PACK_TYPE='0805',
 PART_NUMBER='C95333-006',
 LOCATION='C7A33',
 ROOM='SB_DECOUPLING',
 CDS_LIB='mstr_discrete',
 CDS_PART_NAME='CAP_0805-47UF,4V,20%,X6S,C9533A',
 VOLTAGE='4V',
 PRIM_FILE='./archive_libs/mstr_discrete/cap/chips/chips.prt';

PART_NAME
 C7A34 'CAP_0402LF-3300PF,50V,10%,EMPTA':
 ROOM='PVPP_KLM_VR',
 REUSE_ID='26';

SECTION_NUMBER 1
 '@BASEBOARD_FAB2_LIB.BASEBOARD_FAB2(SCH_1):PAGE232_I220@MSTR_DISCRETE.CAP(CHIPS)':
 C_PATH='@baseboard_fab2_lib.baseboard_fab2(sch_1):page232_i220@mstr_discrete.ca~
p(chips)',
 P_PATH='@baseboard_fab2_lib.baseboard_fab2(sch_1):page232_i220@mstr_discrete.ca~
p(chips)',
 PATH='I220',
 DRAWING='@BASEBOARD_FAB2_LIB.BASEBOARD_FAB2(SCH_1):PAGE232',
 TOLERANCE='10%',
 SEC_TYPE='0402LF',
 MATERIAL='EMPTY',
 BOM_COST='PVPP_KLM_VR',
 PHYS_PAGE='232',
 REUSE_ID='26',
 XY='(-2875,3700)',
 ROT='0',
 VER='1',
 VALUE='3300PF',
 PACK_TYPE='0402LF',
 PART_NUMBER='A36096-091',
 LOCATION='C7A34',
 ROOM='PVPP_KLM_VR',
 SEC='1',
 CDS_LIB='mstr_discrete',
 CDS_PART_NAME='CAP_0402LF-3300PF,50V,10%,EMPTA',
 VOLTAGE='50V',
 PRIM_FILE='./archive_libs/mstr_discrete/cap/chips/chips.prt';

PART_NAME
 C7A36 'CAP_A_0603V-22.0UF,4V,20%,X6S,A':
 ROOM='SB_DECOUPLING';

SECTION_NUMBER 1
 '@BASEBOARD_FAB2_LIB.BASEBOARD_FAB2(SCH_1):PAGE132_I11@DEV_DISCRETE.CAP_A(CHIPS)':
 C_PATH='@baseboard_fab2_lib.baseboard_fab2(sch_1):page132_i11@dev_discrete.cap_~
a(chips)',
 P_PATH='@baseboard_fab2_lib.baseboard_fab2(sch_1):page132_i11@dev_discrete.cap_~
a(chips)',
 PATH='I11',
 DRAWING='@BASEBOARD_FAB2_LIB.BASEBOARD_FAB2(SCH_1):PAGE132',
 TOLERANCE='20%',
 MATERIAL='X6S',
 BOM_COST='SB',
 PHYS_PAGE='132',
 XY='(2200,3500)',
 ROT='0',
 VER='1',
 VALUE='22.0UF',
 PACK_TYPE='0603V',
 PART_NUMBER='E15431-004',
 LOCATION='C7A36',
 ROOM='SB_DECOUPLING',
 CDS_LIB='dev_discrete',
 CDS_PART_NAME='CAP_A_0603V-22.0UF,4V,20%,X6S,A',
 VOLTAGE='4V',
 PRIM_FILE='./archive_libs/discrete/cap_a/chips/chips.prt';

PART_NAME
 C7A37 'CAP_A_0402V-1.0UF,6.3V,10%,X6SA':
 ROOM='VDDQ_DEF_PWR_VR';

SECTION_NUMBER 1
 '@BASEBOARD_FAB2_LIB.BASEBOARD_FAB2(SCH_1):PAGE218_I40@DEV_DISCRETE.CAP_A(CHIPS)':
 C_PATH='@baseboard_fab2_lib.baseboard_fab2(sch_1):page218_i40@dev_discrete.cap_~
a(chips)',
 P_PATH='@baseboard_fab2_lib.baseboard_fab2(sch_1):page218_i40@dev_discrete.cap_~
a(chips)',
 PATH='I40',
 DRAWING='@BASEBOARD_FAB2_LIB.BASEBOARD_FAB2(SCH_1):PAGE218',
 TOLERANCE='10%',
 SEC_TYPE='0402V',
 MATERIAL='X6S',
 PHYS_PAGE='218',
 XY='(250,2800)',
 ROT='0',
 VER='1',
 VALUE='1.0UF',
 PACK_TYPE='0402V',
 PART_NUMBER='D97712-004',
 LOCATION='C7A37',
 ROOM='VDDQ_DEF_PWR_VR',
 SEC='1',
 CDS_LIB='dev_discrete',
 CDS_PART_NAME='CAP_A_0402V-1.0UF,6.3V,10%,X6SA',
 VOLTAGE='6.3V',
 PRIM_FILE='./archive_libs/discrete/cap_a/chips/chips.prt';

PART_NAME
 C7A38 'CAP_A_0402V-0.1UF,16V,10%,X7R,A':
 ROOM='VDDQ_DEF_PWR_VR';

SECTION_NUMBER 1
 '@BASEBOARD_FAB2_LIB.BASEBOARD_FAB2(SCH_1):PAGE218_I38@DEV_DISCRETE.CAP_A(CHIPS)':
 C_PATH='@baseboard_fab2_lib.baseboard_fab2(sch_1):page218_i38@dev_discrete.cap_~
a(chips)',
 P_PATH='@baseboard_fab2_lib.baseboard_fab2(sch_1):page218_i38@dev_discrete.cap_~
a(chips)',
 PATH='I38',
 DRAWING='@BASEBOARD_FAB2_LIB.BASEBOARD_FAB2(SCH_1):PAGE218',
 TOLERANCE='10%',
 SEC_TYPE='0402V',
 MATERIAL='X7R',
 PHYS_PAGE='218',
 XY='(-150,2800)',
 ROT='0',
 VER='1',
 VALUE='0.1UF',
 PACK_TYPE='0402V',
 PART_NUMBER='A36096-030',
 LOCATION='C7A38',
 ROOM='VDDQ_DEF_PWR_VR',
 SEC='1',
 CDS_LIB='dev_discrete',
 CDS_PART_NAME='CAP_A_0402V-0.1UF,16V,10%,X7R,A',
 VOLTAGE='16V',
 PRIM_FILE='./archive_libs/discrete/cap_a/chips/chips.prt';

PART_NAME
 C7A39 'CAP_A_0402V-0.1UF,16V,10%,X7R,A':
 ROOM='PVNN_PCH_STBY';

SECTION_NUMBER 1
 '@BASEBOARD_FAB2_LIB.BASEBOARD_FAB2(SCH_1):PAGE236_I20@DEV_DISCRETE.CAP_A(CHIPS)':
 C_PATH='@baseboard_fab2_lib.baseboard_fab2(sch_1):page236_i20@dev_discrete.cap_~
a(chips)',
 P_PATH='@baseboard_fab2_lib.baseboard_fab2(sch_1):page236_i20@dev_discrete.cap_~
a(chips)',
 PATH='I20',
 DRAWING='@BASEBOARD_FAB2_LIB.BASEBOARD_FAB2(SCH_1):PAGE236',
 TOLERANCE='10%',
 SEC_TYPE='0402V',
 MATERIAL='X7R',
 PHYS_PAGE='236',
 XY='(7025,4550)',
 ROT='0',
 VER='1',
 VALUE='0.1UF',
 PACK_TYPE='0402V',
 PART_NUMBER='A36096-030',
 LOCATION='C7A39',
 ROOM='PVNN_PCH_STBY',
 SEC='1',
 CDS_LIB='dev_discrete',
 CDS_PART_NAME='CAP_A_0402V-0.1UF,16V,10%,X7R,A',
 VOLTAGE='16V',
 PRIM_FILE='./archive_libs/discrete/cap_a/chips/chips.prt';

PART_NAME
 C7A40 'CAP_A_0402V-0.1UF,16V,10%,X7R,A':
 ROOM='P1V05_PCH_STBY_VR';

SECTION_NUMBER 1
 '@BASEBOARD_FAB2_LIB.BASEBOARD_FAB2(SCH_1):PAGE236_I35@DEV_DISCRETE.CAP_A(CHIPS)':
 C_PATH='@baseboard_fab2_lib.baseboard_fab2(sch_1):page236_i35@dev_discrete.cap_~
a(chips)',
 P_PATH='@baseboard_fab2_lib.baseboard_fab2(sch_1):page236_i35@dev_discrete.cap_~
a(chips)',
 PATH='I35',
 DRAWING='@BASEBOARD_FAB2_LIB.BASEBOARD_FAB2(SCH_1):PAGE236',
 TOLERANCE='10%',
 SEC_TYPE='0402V',
 MATERIAL='X7R',
 PHYS_PAGE='236',
 XY='(6925,2875)',
 ROT='0',
 VER='1',
 VALUE='0.1UF',
 PACK_TYPE='0402V',
 PART_NUMBER='A36096-030',
 LOCATION='C7A40',
 ROOM='P1V05_PCH_STBY_VR',
 SEC='1',
 CDS_LIB='dev_discrete',
 CDS_PART_NAME='CAP_A_0402V-0.1UF,16V,10%,X7R,A',
 VOLTAGE='16V',
 PRIM_FILE='./archive_libs/discrete/cap_a/chips/chips.prt';

PART_NAME
 C7A41 'CAP_0402-0.22UF,16V,10%,X7R,A3A':
 ROOM='P1V05_PCH_STBY_VR';

SECTION_NUMBER 1
 '@BASEBOARD_FAB2_LIB.BASEBOARD_FAB2(SCH_1):PAGE236_I39@MSTR_DISCRETE.CAP(CHIPS)':
 C_PATH='@baseboard_fab2_lib.baseboard_fab2(sch_1):page236_i39@mstr_discrete.cap~
(chips)',
 P_PATH='@baseboard_fab2_lib.baseboard_fab2(sch_1):page236_i39@mstr_discrete.cap~
(chips)',
 PATH='I39',
 DRAWING='@BASEBOARD_FAB2_LIB.BASEBOARD_FAB2(SCH_1):PAGE236',
 TOLERANCE='10%',
 SEC_TYPE='0402',
 MATERIAL='X7R',
 PHYS_PAGE='236',
 XY='(8000,2875)',
 ROT='0',
 VER='1',
 VALUE='0.22UF',
 PACK_TYPE='0402',
 PART_NUMBER='A36096-155',
 LOCATION='C7A41',
 ROOM='P1V05_PCH_STBY_VR',
 SEC='1',
 CDS_LIB='mstr_discrete',
 CDS_PART_NAME='CAP_0402-0.22UF,16V,10%,X7R,A3A',
 VOLTAGE='16V',
 PRIM_FILE='./archive_libs/mstr_discrete/cap/chips/chips.prt';

PART_NAME
 C7A42 'CAP_0805LF-22UF,4V,20%,X6S,C95A':
 ROOM='P1V05_PCH_STBY_VR';

SECTION_NUMBER 1
 '@BASEBOARD_FAB2_LIB.BASEBOARD_FAB2(SCH_1):PAGE236_I46@MSTR_DISCRETE.CAP(CHIPS)':
 C_PATH='@baseboard_fab2_lib.baseboard_fab2(sch_1):page236_i46@mstr_discrete.cap~
(chips)',
 P_PATH='@baseboard_fab2_lib.baseboard_fab2(sch_1):page236_i46@mstr_discrete.cap~
(chips)',
 PATH='I46',
 DRAWING='@BASEBOARD_FAB2_LIB.BASEBOARD_FAB2(SCH_1):PAGE236',
 TOLERANCE='20%',
 SEC_TYPE='0805LF',
 MATERIAL='X6S',
 BOM_COST='PROC_VRD_PVCCIO_CPU0',
 PHYS_PAGE='236',
 XY='(11650,2050)',
 ROT='0',
 VER='1',
 VALUE='22UF',
 PACK_TYPE='0805LF',
 PART_NUMBER='C95333-002',
 LOCATION='C7A42',
 ROOM='P1V05_PCH_STBY_VR',
 SEC='1',
 CDS_LIB='mstr_discrete',
 CDS_PART_NAME='CAP_0805LF-22UF,4V,20%,X6S,C95A',
 VOLTAGE='4V',
 PRIM_FILE='./archive_libs/mstr_discrete/cap/chips/chips.prt';

PART_NAME
 C7A43 'CAP_0402-0.220UF,16V,10%,X7R,AA':
 ROOM='PVNN_PCH_STBY';

SECTION_NUMBER 1
 '@BASEBOARD_FAB2_LIB.BASEBOARD_FAB2(SCH_1):PAGE236_I21@MSTR_DISCRETE.CAP(CHIPS)':
 C_PATH='@baseboard_fab2_lib.baseboard_fab2(sch_1):page236_i21@mstr_discrete.cap~
(chips)',
 P_PATH='@baseboard_fab2_lib.baseboard_fab2(sch_1):page236_i21@mstr_discrete.cap~
(chips)',
 PATH='I21',
 DRAWING='@BASEBOARD_FAB2_LIB.BASEBOARD_FAB2(SCH_1):PAGE236',
 SPOF='TRUE',
 TOLERANCE='10%',
 SEC_TYPE='0402',
 MATERIAL='X7R',
 PHYS_PAGE='236',
 XY='(6975,3850)',
 ROT='2',
 VER='1',
 VALUE='0.220UF',
 PACK_TYPE='0402',
 PART_NUMBER='A36096-104',
 LOCATION='C7A43',
 ROOM='PVNN_PCH_STBY',
 SEC='1',
 CDS_LIB='mstr_discrete',
 CDS_PART_NAME='CAP_0402-0.220UF,16V,10%,X7R,AA',
 VOLTAGE='16V',
 PRIM_FILE='./archive_libs/mstr_discrete/cap/chips/chips.prt';

PART_NAME
 C7A44 'CAP_0402-0.220UF,16V,10%,X7R,AA':
 ROOM='P1V05_PCH_STBY_VR';

SECTION_NUMBER 1
 '@BASEBOARD_FAB2_LIB.BASEBOARD_FAB2(SCH_1):PAGE236_I34@MSTR_DISCRETE.CAP(CHIPS)':
 C_PATH='@baseboard_fab2_lib.baseboard_fab2(sch_1):page236_i34@mstr_discrete.cap~
(chips)',
 P_PATH='@baseboard_fab2_lib.baseboard_fab2(sch_1):page236_i34@mstr_discrete.cap~
(chips)',
 PATH='I34',
 DRAWING='@BASEBOARD_FAB2_LIB.BASEBOARD_FAB2(SCH_1):PAGE236',
 SPOF='TRUE',
 TOLERANCE='10%',
 SEC_TYPE='0402',
 MATERIAL='X7R',
 PHYS_PAGE='236',
 XY='(7050,2100)',
 ROT='2',
 VER='1',
 VALUE='0.220UF',
 PACK_TYPE='0402',
 PART_NUMBER='A36096-104',
 LOCATION='C7A44',
 ROOM='P1V05_PCH_STBY_VR',
 SEC='1',
 CDS_LIB='mstr_discrete',
 CDS_PART_NAME='CAP_0402-0.220UF,16V,10%,X7R,AA',
 VOLTAGE='16V',
 PRIM_FILE='./archive_libs/mstr_discrete/cap/chips/chips.prt';

PART_NAME
 C7B1 'CAP_A_0402V-1.0UF,6.3V,10%,X6SA':
 ROOM='VDDQ_DEF_PWR_VR';

SECTION_NUMBER 1
 '@BASEBOARD_FAB2_LIB.BASEBOARD_FAB2(SCH_1):PAGE218_I30@DEV_DISCRETE.CAP_A(CHIPS)':
 C_PATH='@baseboard_fab2_lib.baseboard_fab2(sch_1):page218_i30@dev_discrete.cap_~
a(chips)',
 P_PATH='@baseboard_fab2_lib.baseboard_fab2(sch_1):page218_i30@dev_discrete.cap_~
a(chips)',
 PATH='I30',
 DRAWING='@BASEBOARD_FAB2_LIB.BASEBOARD_FAB2(SCH_1):PAGE218',
 TOLERANCE='10%',
 SEC_TYPE='0402V',
 MATERIAL='X6S',
 PHYS_PAGE='218',
 XY='(2350,-100)',
 ROT='0',
 VER='1',
 VALUE='1.0UF',
 PACK_TYPE='0402V',
 PART_NUMBER='D97712-004',
 LOCATION='C7B1',
 ROOM='VDDQ_DEF_PWR_VR',
 SEC='1',
 CDS_LIB='dev_discrete',
 CDS_PART_NAME='CAP_A_0402V-1.0UF,6.3V,10%,X6SA',
 VOLTAGE='6.3V',
 PRIM_FILE='./archive_libs/discrete/cap_a/chips/chips.prt';

PART_NAME
 C7B2 'CAP_A_0402V-0.1UF,16V,10%,X7R,A':
 ROOM='VDDQ_DEF_PWR_VR';

SECTION_NUMBER 1
 '@BASEBOARD_FAB2_LIB.BASEBOARD_FAB2(SCH_1):PAGE218_I28@DEV_DISCRETE.CAP_A(CHIPS)':
 C_PATH='@baseboard_fab2_lib.baseboard_fab2(sch_1):page218_i28@dev_discrete.cap_~
a(chips)',
 P_PATH='@baseboard_fab2_lib.baseboard_fab2(sch_1):page218_i28@dev_discrete.cap_~
a(chips)',
 PATH='I28',
 DRAWING='@BASEBOARD_FAB2_LIB.BASEBOARD_FAB2(SCH_1):PAGE218',
 TOLERANCE='10%',
 SEC_TYPE='0402V',
 MATERIAL='X7R',
 PHYS_PAGE='218',
 XY='(1950,-100)',
 ROT='0',
 VER='1',
 VALUE='0.1UF',
 PACK_TYPE='0402V',
 PART_NUMBER='A36096-030',
 LOCATION='C7B2',
 ROOM='VDDQ_DEF_PWR_VR',
 SEC='1',
 CDS_LIB='dev_discrete',
 CDS_PART_NAME='CAP_A_0402V-0.1UF,16V,10%,X7R,A',
 VOLTAGE='16V',
 PRIM_FILE='./archive_libs/discrete/cap_a/chips/chips.prt';

PART_NAME
 C7B3 'CAP_0402LF-1000PF,50V,10%,X7R,A':
 ROOM='VDDQ_DEF_PWR_VR';

SECTION_NUMBER 1
 '@BASEBOARD_FAB2_LIB.BASEBOARD_FAB2(SCH_1):PAGE218_I41@MSTR_DISCRETE.CAP(CHIPS)':
 C_PATH='@baseboard_fab2_lib.baseboard_fab2(sch_1):page218_i41@mstr_discrete.cap~
(chips)',
 P_PATH='@baseboard_fab2_lib.baseboard_fab2(sch_1):page218_i41@mstr_discrete.cap~
(chips)',
 PATH='I41',
 DRAWING='@BASEBOARD_FAB2_LIB.BASEBOARD_FAB2(SCH_1):PAGE218',
 TOLERANCE='10%',
 SEC_TYPE='0402LF',
 MATERIAL='X7R',
 PHYS_PAGE='218',
 XY='(1625,925)',
 ROT='0',
 VER='1',
 VALUE='1000PF',
 PACK_TYPE='0402LF',
 PART_NUMBER='A36096-046',
 LOCATION='C7B3',
 ROOM='VDDQ_DEF_PWR_VR',
 SEC='1',
 CDS_LIB='mstr_discrete',
 CDS_PART_NAME='CAP_0402LF-1000PF,50V,10%,X7R,A',
 VOLTAGE='50V',
 PRIM_FILE='./archive_libs/mstr_discrete/cap/chips/chips.prt';

PART_NAME
 C7B4 'CAP_0805-47UF,4V,20%,X6S,C9533A':
 ROOM='SB_DECOUPLING';

SECTION_NUMBER 1
 '@BASEBOARD_FAB2_LIB.BASEBOARD_FAB2(SCH_1):PAGE132_I24@MSTR_DISCRETE.CAP(CHIPS)':
 C_PATH='@baseboard_fab2_lib.baseboard_fab2(sch_1):page132_i24@mstr_discrete.cap~
(chips)',
 P_PATH='@baseboard_fab2_lib.baseboard_fab2(sch_1):page132_i24@mstr_discrete.cap~
(chips)',
 PATH='I24',
 DRAWING='@BASEBOARD_FAB2_LIB.BASEBOARD_FAB2(SCH_1):PAGE132',
 TOLERANCE='20%',
 MATERIAL='X6S',
 BOM_COST='SB',
 PHYS_PAGE='132',
 XY='(1700,1575)',
 ROT='0',
 VER='1',
 VALUE='47UF',
 PACK_TYPE='0805',
 PART_NUMBER='C95333-006',
 LOCATION='C7B4',
 ROOM='SB_DECOUPLING',
 CDS_LIB='mstr_discrete',
 CDS_PART_NAME='CAP_0805-47UF,4V,20%,X6S,C9533A',
 VOLTAGE='4V',
 PRIM_FILE='./archive_libs/mstr_discrete/cap/chips/chips.prt';

PART_NAME
 C7B5 'CAP_0805-10UF,16V,10%,X6S,C953A':;

SECTION_NUMBER 1
 '@BASEBOARD_FAB2_LIB.BASEBOARD_FAB2(SCH_1):PAGE232_I262@MSTR_DISCRETE.CAP(CHIPS)':
 C_PATH='@baseboard_fab2_lib.baseboard_fab2(sch_1):page232_i262@mstr_discrete.ca~
p(chips)',
 P_PATH='@baseboard_fab2_lib.baseboard_fab2(sch_1):page232_i262@mstr_discrete.ca~
p(chips)',
 PATH='I262',
 DRAWING='@BASEBOARD_FAB2_LIB.BASEBOARD_FAB2(SCH_1):PAGE232',
 TOLERANCE='10%',
 SEC_TYPE='0805',
 MATERIAL='X6S',
 PHYS_PAGE='232',
 XY='(-5850,4100)',
 ROT='0',
 VER='1',
 VALUE='10UF',
 PACK_TYPE='0805',
 PART_NUMBER='C95333-007',
 LOCATION='C7B5',
 SEC='1',
 CDS_LIB='mstr_discrete',
 CDS_PART_NAME='CAP_0805-10UF,16V,10%,X6S,C953A',
 VOLTAGE='16V',
 PRIM_FILE='./archive_libs/mstr_discrete/cap/chips/chips.prt';

PART_NAME
 C7B6 'CAP_A_0402V-0.1UF,16V,10%,X7R,A':;

SECTION_NUMBER 1
 '@BASEBOARD_FAB2_LIB.BASEBOARD_FAB2(SCH_1):PAGE232_I252@DEV_DISCRETE.CAP_A(CHIPS)':
 C_PATH='@baseboard_fab2_lib.baseboard_fab2(sch_1):page232_i252@dev_discrete.cap~
_a(chips)',
 P_PATH='@baseboard_fab2_lib.baseboard_fab2(sch_1):page232_i252@dev_discrete.cap~
_a(chips)',
 PATH='I252',
 DRAWING='@BASEBOARD_FAB2_LIB.BASEBOARD_FAB2(SCH_1):PAGE232',
 TOLERANCE='10%',
 SEC_TYPE='0402V',
 MATERIAL='X7R',
 PHYS_PAGE='232',
 XY='(-5475,3525)',
 ROT='0',
 VER='1',
 VALUE='0.1UF',
 PACK_TYPE='0402V',
 PART_NUMBER='A36096-030',
 LOCATION='C7B6',
 SEC='1',
 CDS_LIB='dev_discrete',
 CDS_PART_NAME='CAP_A_0402V-0.1UF,16V,10%,X7R,A',
 VOLTAGE='16V',
 PRIM_FILE='./archive_libs/discrete/cap_a/chips/chips.prt';

PART_NAME
 C7B7 'CAP_0805-47UF,4V,20%,X6S,C9533A':
 GROUP='PWR_MLCC_CAP',
 ROOM='PVPP_KLM_VR',
 REUSE_ID='33';

SECTION_NUMBER 1
 '@BASEBOARD_FAB2_LIB.BASEBOARD_FAB2(SCH_1):PAGE232_I238@MSTR_DISCRETE.CAP(CHIPS)':
 C_PATH='@baseboard_fab2_lib.baseboard_fab2(sch_1):page232_i238@mstr_discrete.ca~
p(chips)',
 P_PATH='@baseboard_fab2_lib.baseboard_fab2(sch_1):page232_i238@mstr_discrete.ca~
p(chips)',
 PATH='I238',
 DRAWING='@BASEBOARD_FAB2_LIB.BASEBOARD_FAB2(SCH_1):PAGE232',
 TOLERANCE='20%',
 MATERIAL='X6S',
 BOM_COST='PVPP_KLM_VR',
 PHYS_PAGE='232',
 REUSE_ID='33',
 XY='(-1200,3675)',
 ROT='0',
 VER='1',
 VALUE='47UF',
 PACK_TYPE='0805',
 PART_NUMBER='C95333-006',
 LOCATION='C7B7',
 ROOM='PVPP_KLM_VR',
 GROUP='PWR_MLCC_CAP',
 CDS_LIB='mstr_discrete',
 CDS_PART_NAME='CAP_0805-47UF,4V,20%,X6S,C9533A',
 VOLTAGE='4V',
 PRIM_FILE='./archive_libs/mstr_discrete/cap/chips/chips.prt';

PART_NAME
 C7B8 'SC22U16V5MX-4-GP_SMD-BCG5-SC22A':;

SECTION_NUMBER 1
 '@BASEBOARD_FAB2_LIB.BASEBOARD_FAB2(SCH_1):PAGE232_I309@W_HDL.SC22U16V5MX-4-GP(CHIPS)':
 C_PATH='@baseboard_fab2_lib.baseboard_fab2(sch_1):page232_i309@w_hdl.\sc22u16v5~
mx-4-gp\(chips)',
 P_PATH='@baseboard_fab2_lib.baseboard_fab2(sch_1):page232_i309@w_hdl.\sc22u16v5~
mx-4-gp\(chips)',
 PATH='I309',
 DRAWING='@BASEBOARD_FAB2_LIB.BASEBOARD_FAB2(SCH_1):PAGE232',
 TYPE='X6S',
 PACK_SIZE='0805',
 RATED='16V',
 ATTRIBUTE='22UF',
 TOLERANCE='20%',
 SEC_TYPE='SMD-BCG5',
 PHYS_PAGE='232',
 XY='(-7600,4100)',
 ROT='0',
 VER='1',
 VALUE='SC22U16V5MX-4-GP',
 PACK_TYPE='SMD-BCG5',
 PART_NUMBER='078.22611.0811',
 LOCATION='C7B8',
 SEC='1',
 CDS_LIB='w_hdl',
 CDS_PART_NAME='SC22U16V5MX-4-GP_SMD-BCG5-SC22A',
 PRIM_FILE='C:/<user>/w_hdl/sc22u16v5mx#2d4#2dgp/chips/chips.prt';

PART_NAME
 C7B9 'CAP_0402LF-1000PF,50V,10%,EMPTA':
 ROOM='PVPP_KLM_VR',
 REUSE_ID='1';

SECTION_NUMBER 1
 '@BASEBOARD_FAB2_LIB.BASEBOARD_FAB2(SCH_1):PAGE232_I185@MSTR_DISCRETE.CAP(CHIPS)':
 C_PATH='@baseboard_fab2_lib.baseboard_fab2(sch_1):page232_i185@mstr_discrete.ca~
p(chips)',
 P_PATH='@baseboard_fab2_lib.baseboard_fab2(sch_1):page232_i185@mstr_discrete.ca~
p(chips)',
 PATH='I185',
 DRAWING='@BASEBOARD_FAB2_LIB.BASEBOARD_FAB2(SCH_1):PAGE232',
 FIN='VR_1P2',
 TOLERANCE='10%',
 MATERIAL='EMPTY',
 BOM_COST='PVPP_KLM_VR',
 PHYS_PAGE='232',
 REUSE_ID='1',
 XY='(-6825,2500)',
 ROT='2',
 VER='1',
 VALUE='1000PF',
 PACK_TYPE='0402LF',
 PART_NUMBER='A36096-046',
 LOCATION='C7B9',
 ROOM='PVPP_KLM_VR',
 CDS_LIB='mstr_discrete',
 CDS_PART_NAME='CAP_0402LF-1000PF,50V,10%,EMPTA',
 VOLTAGE='50V',
 PRIM_FILE='./archive_libs/mstr_discrete/cap/chips/chips.prt';

PART_NAME
 C7B10 'CAP_0402LF-100.0PF,50V,5%,COG,A':
 ROOM='PVPP_KLM_VR',
 REUSE_ID='27';

SECTION_NUMBER 1
 '@BASEBOARD_FAB2_LIB.BASEBOARD_FAB2(SCH_1):PAGE232_I301@MSTR_DISCRETE.CAP(CHIPS)':
 C_PATH='@baseboard_fab2_lib.baseboard_fab2(sch_1):page232_i301@mstr_discrete.ca~
p(chips)',
 P_PATH='@baseboard_fab2_lib.baseboard_fab2(sch_1):page232_i301@mstr_discrete.ca~
p(chips)',
 PATH='I301',
 DRAWING='@BASEBOARD_FAB2_LIB.BASEBOARD_FAB2(SCH_1):PAGE232',
 TOLERANCE='5%',
 SEC_TYPE='0402LF',
 MATERIAL='COG',
 BOM_COST='PVPP_KLM_VR',
 PHYS_PAGE='232',
 REUSE_ID='27',
 XY='(-2600,2825)',
 ROT='2',
 VER='2',
 VALUE='100.0PF',
 PACK_TYPE='0402LF',
 PART_NUMBER='A36095-026',
 LOCATION='C7B10',
 ROOM='PVPP_KLM_VR',
 SEC='1',
 CDS_LIB='mstr_discrete',
 CDS_PART_NAME='CAP_0402LF-100.0PF,50V,5%,COG,A',
 VOLTAGE='50V',
 PRIM_FILE='./archive_libs/mstr_discrete/cap/chips/chips.prt';

PART_NAME
 C7B11 'CAP_0402-0.027UF,16V,10%,X7R,AA':
 ROOM='PVPP_KLM_VR',
 REUSE_ID='26';

SECTION_NUMBER 1
 '@BASEBOARD_FAB2_LIB.BASEBOARD_FAB2(SCH_1):PAGE232_I197@MSTR_DISCRETE.CAP(CHIPS)':
 C_PATH='@baseboard_fab2_lib.baseboard_fab2(sch_1):page232_i197@mstr_discrete.ca~
p(chips)',
 P_PATH='@baseboard_fab2_lib.baseboard_fab2(sch_1):page232_i197@mstr_discrete.ca~
p(chips)',
 PATH='I197',
 DRAWING='@BASEBOARD_FAB2_LIB.BASEBOARD_FAB2(SCH_1):PAGE232',
 TOLERANCE='10%',
 SEC_TYPE='0402',
 MATERIAL='X7R',
 BOM_COST='PVPP_KLM_VR',
 PHYS_PAGE='232',
 REUSE_ID='26',
 XY='(-5425,2175)',
 ROT='0',
 VER='1',
 VALUE='0.027UF',
 PACK_TYPE='0402',
 PART_NUMBER='A36096-129',
 LOCATION='C7B11',
 ROOM='PVPP_KLM_VR',
 SEC='1',
 CDS_LIB='mstr_discrete',
 CDS_PART_NAME='CAP_0402-0.027UF,16V,10%,X7R,AA',
 VOLTAGE='16V',
 PRIM_FILE='./archive_libs/mstr_discrete/cap/chips/chips.prt';

PART_NAME
 C7B12 'CAP_0402LF-1000PF,50V,10%,X7R,A':
 ROOM='PVPP_KLM_VR',
 REUSE_ID='26';

SECTION_NUMBER 1
 '@BASEBOARD_FAB2_LIB.BASEBOARD_FAB2(SCH_1):PAGE232_I209@MSTR_DISCRETE.CAP(CHIPS)':
 C_PATH='@baseboard_fab2_lib.baseboard_fab2(sch_1):page232_i209@mstr_discrete.ca~
p(chips)',
 P_PATH='@baseboard_fab2_lib.baseboard_fab2(sch_1):page232_i209@mstr_discrete.ca~
p(chips)',
 PATH='I209',
 DRAWING='@BASEBOARD_FAB2_LIB.BASEBOARD_FAB2(SCH_1):PAGE232',
 TOLERANCE='10%',
 MATERIAL='X7R',
 BOM_COST='PVPP_KLM_VR',
 PHYS_PAGE='232',
 REUSE_ID='26',
 XY='(-3975,725)',
 ROT='0',
 VER='1',
 VALUE='1000PF',
 PACK_TYPE='0402LF',
 PART_NUMBER='A36096-046',
 LOCATION='C7B12',
 ROOM='PVPP_KLM_VR',
 CDS_LIB='mstr_discrete',
 CDS_PART_NAME='CAP_0402LF-1000PF,50V,10%,X7R,A',
 VOLTAGE='50V',
 PRIM_FILE='./archive_libs/mstr_discrete/cap/chips/chips.prt';

PART_NAME
 C7B13 'CAP_0402LF-2200PF,50V,10%,X7R,A':
 ROOM='PVPP_KLM_VR',
 REUSE_ID='26';

SECTION_NUMBER 1
 '@BASEBOARD_FAB2_LIB.BASEBOARD_FAB2(SCH_1):PAGE232_I302@MSTR_DISCRETE.CAP(CHIPS)':
 C_PATH='@baseboard_fab2_lib.baseboard_fab2(sch_1):page232_i302@mstr_discrete.ca~
p(chips)',
 P_PATH='@baseboard_fab2_lib.baseboard_fab2(sch_1):page232_i302@mstr_discrete.ca~
p(chips)',
 PATH='I302',
 DRAWING='@BASEBOARD_FAB2_LIB.BASEBOARD_FAB2(SCH_1):PAGE232',
 SPOF='TRUE',
 TOLERANCE='10%',
 SEC_TYPE='0402LF',
 MATERIAL='X7R',
 BOM_COST='PVPP_KLM_VR',
 PHYS_PAGE='232',
 REUSE_ID='26',
 XY='(-1350,1775)',
 ROT='0',
 VER='1',
 VALUE='2200PF',
 PACK_TYPE='0402LF',
 PART_NUMBER='A36096-075',
 LOCATION='C7B13',
 ROOM='PVPP_KLM_VR',
 SEC='1',
 CDS_LIB='mstr_discrete',
 CDS_PART_NAME='CAP_0402LF-2200PF,50V,10%,X7R,A',
 VOLTAGE='50V',
 PRIM_FILE='./archive_libs/mstr_discrete/cap/chips/chips.prt';

PART_NAME
 C7B14 'CAP_0402LF-2200PF,50V,10%,X7R,A':
 ROOM='PVPP_KLM_VR',
 REUSE_ID='27';

SECTION_NUMBER 1
 '@BASEBOARD_FAB2_LIB.BASEBOARD_FAB2(SCH_1):PAGE232_I306@MSTR_DISCRETE.CAP(CHIPS)':
 C_PATH='@baseboard_fab2_lib.baseboard_fab2(sch_1):page232_i306@mstr_discrete.ca~
p(chips)',
 P_PATH='@baseboard_fab2_lib.baseboard_fab2(sch_1):page232_i306@mstr_discrete.ca~
p(chips)',
 PATH='I306',
 DRAWING='@BASEBOARD_FAB2_LIB.BASEBOARD_FAB2(SCH_1):PAGE232',
 TOLERANCE='10%',
 SEC_TYPE='0402LF',
 MATERIAL='X7R',
 BOM_COST='PVPP_KLM_VR',
 PHYS_PAGE='232',
 REUSE_ID='27',
 XY='(-3200,2450)',
 ROT='2',
 VER='2',
 VALUE='2200PF',
 PACK_TYPE='0402LF',
 PART_NUMBER='A36096-075',
 LOCATION='C7B14',
 ROOM='PVPP_KLM_VR',
 SEC='1',
 CDS_LIB='mstr_discrete',
 CDS_PART_NAME='CAP_0402LF-2200PF,50V,10%,X7R,A',
 VOLTAGE='50V',
 PRIM_FILE='./archive_libs/mstr_discrete/cap/chips/chips.prt';

PART_NAME
 C7B15 'CAP_A_0603V-22.0UF,4V,20%,X6S,A':
 ROOM='SB_DECOUPLING';

SECTION_NUMBER 1
 '@BASEBOARD_FAB2_LIB.BASEBOARD_FAB2(SCH_1):PAGE131_I1@DEV_DISCRETE.CAP_A(CHIPS)':
 C_PATH='@baseboard_fab2_lib.baseboard_fab2(sch_1):page131_i1@dev_discrete.cap_a~
(chips)',
 P_PATH='@baseboard_fab2_lib.baseboard_fab2(sch_1):page131_i1@dev_discrete.cap_a~
(chips)',
 PATH='I1',
 DRAWING='@BASEBOARD_FAB2_LIB.BASEBOARD_FAB2(SCH_1):PAGE131',
 TOLERANCE='20%',
 MATERIAL='X6S',
 BOM_COST='SB',
 PHYS_PAGE='131',
 XY='(975,4975)',
 ROT='0',
 VER='1',
 VALUE='22.0UF',
 PACK_TYPE='0603V',
 PART_NUMBER='E15431-004',
 LOCATION='C7B15',
 ROOM='SB_DECOUPLING',
 CDS_LIB='dev_discrete',
 CDS_PART_NAME='CAP_A_0603V-22.0UF,4V,20%,X6S,A',
 VOLTAGE='4V',
 PRIM_FILE='./archive_libs/discrete/cap_a/chips/chips.prt';

PART_NAME
 C7B16 'CAP_A_0603V-22.0UF,4V,20%,X6S,A':
 ROOM='SB_DECOUPLING';

SECTION_NUMBER 1
 '@BASEBOARD_FAB2_LIB.BASEBOARD_FAB2(SCH_1):PAGE131_I3@DEV_DISCRETE.CAP_A(CHIPS)':
 C_PATH='@baseboard_fab2_lib.baseboard_fab2(sch_1):page131_i3@dev_discrete.cap_a~
(chips)',
 P_PATH='@baseboard_fab2_lib.baseboard_fab2(sch_1):page131_i3@dev_discrete.cap_a~
(chips)',
 PATH='I3',
 DRAWING='@BASEBOARD_FAB2_LIB.BASEBOARD_FAB2(SCH_1):PAGE131',
 TOLERANCE='20%',
 MATERIAL='X6S',
 BOM_COST='SB',
 PHYS_PAGE='131',
 XY='(50,4975)',
 ROT='0',
 VER='1',
 VALUE='22.0UF',
 PACK_TYPE='0603V',
 PART_NUMBER='E15431-004',
 LOCATION='C7B16',
 ROOM='SB_DECOUPLING',
 CDS_LIB='dev_discrete',
 CDS_PART_NAME='CAP_A_0603V-22.0UF,4V,20%,X6S,A',
 VOLTAGE='4V',
 PRIM_FILE='./archive_libs/discrete/cap_a/chips/chips.prt';

PART_NAME
 C7B17 'CAP_A_0603V-22.0UF,4V,20%,X6S,A':
 ROOM='SB_DECOUPLING';

SECTION_NUMBER 1
 '@BASEBOARD_FAB2_LIB.BASEBOARD_FAB2(SCH_1):PAGE131_I18@DEV_DISCRETE.CAP_A(CHIPS)':
 C_PATH='@baseboard_fab2_lib.baseboard_fab2(sch_1):page131_i18@dev_discrete.cap_~
a(chips)',
 P_PATH='@baseboard_fab2_lib.baseboard_fab2(sch_1):page131_i18@dev_discrete.cap_~
a(chips)',
 PATH='I18',
 DRAWING='@BASEBOARD_FAB2_LIB.BASEBOARD_FAB2(SCH_1):PAGE131',
 TOLERANCE='20%',
 MATERIAL='X6S',
 BOM_COST='SB',
 PHYS_PAGE='131',
 XY='(-875,4025)',
 ROT='0',
 VER='1',
 VALUE='22.0UF',
 PACK_TYPE='0603V',
 PART_NUMBER='E15431-004',
 LOCATION='C7B17',
 ROOM='SB_DECOUPLING',
 CDS_LIB='dev_discrete',
 CDS_PART_NAME='CAP_A_0603V-22.0UF,4V,20%,X6S,A',
 VOLTAGE='4V',
 PRIM_FILE='./archive_libs/discrete/cap_a/chips/chips.prt';

PART_NAME
 C7B18 'CAP_A_0603V-22.0UF,4V,20%,X6S,A':
 ROOM='SB_DECOUPLING';

SECTION_NUMBER 1
 '@BASEBOARD_FAB2_LIB.BASEBOARD_FAB2(SCH_1):PAGE131_I12@DEV_DISCRETE.CAP_A(CHIPS)':
 C_PATH='@baseboard_fab2_lib.baseboard_fab2(sch_1):page131_i12@dev_discrete.cap_~
a(chips)',
 P_PATH='@baseboard_fab2_lib.baseboard_fab2(sch_1):page131_i12@dev_discrete.cap_~
a(chips)',
 PATH='I12',
 DRAWING='@BASEBOARD_FAB2_LIB.BASEBOARD_FAB2(SCH_1):PAGE131',
 TOLERANCE='20%',
 MATERIAL='X6S',
 BOM_COST='SB',
 PHYS_PAGE='131',
 XY='(-425,4025)',
 ROT='0',
 VER='1',
 VALUE='22.0UF',
 PACK_TYPE='0603V',
 PART_NUMBER='E15431-004',
 LOCATION='C7B18',
 ROOM='SB_DECOUPLING',
 CDS_LIB='dev_discrete',
 CDS_PART_NAME='CAP_A_0603V-22.0UF,4V,20%,X6S,A',
 VOLTAGE='4V',
 PRIM_FILE='./archive_libs/discrete/cap_a/chips/chips.prt';

PART_NAME
 C7B19 'CAP_A_0603V-22.0UF,4V,20%,X6S,A':
 ROOM='SB_DECOUPLING';

SECTION_NUMBER 1
 '@BASEBOARD_FAB2_LIB.BASEBOARD_FAB2(SCH_1):PAGE131_I2@DEV_DISCRETE.CAP_A(CHIPS)':
 C_PATH='@baseboard_fab2_lib.baseboard_fab2(sch_1):page131_i2@dev_discrete.cap_a~
(chips)',
 P_PATH='@baseboard_fab2_lib.baseboard_fab2(sch_1):page131_i2@dev_discrete.cap_a~
(chips)',
 PATH='I2',
 DRAWING='@BASEBOARD_FAB2_LIB.BASEBOARD_FAB2(SCH_1):PAGE131',
 TOLERANCE='20%',
 MATERIAL='X6S',
 BOM_COST='SB',
 PHYS_PAGE='131',
 XY='(500,4975)',
 ROT='0',
 VER='1',
 VALUE='22.0UF',
 PACK_TYPE='0603V',
 PART_NUMBER='E15431-004',
 LOCATION='C7B19',
 ROOM='SB_DECOUPLING',
 CDS_LIB='dev_discrete',
 CDS_PART_NAME='CAP_A_0603V-22.0UF,4V,20%,X6S,A',
 VOLTAGE='4V',
 PRIM_FILE='./archive_libs/discrete/cap_a/chips/chips.prt';

PART_NAME
 C7B20 'CAP_A_0603V-22.0UF,4V,20%,X6S,A':
 ROOM='SB_DECOUPLING';

SECTION_NUMBER 1
 '@BASEBOARD_FAB2_LIB.BASEBOARD_FAB2(SCH_1):PAGE131_I6@DEV_DISCRETE.CAP_A(CHIPS)':
 C_PATH='@baseboard_fab2_lib.baseboard_fab2(sch_1):page131_i6@dev_discrete.cap_a~
(chips)',
 P_PATH='@baseboard_fab2_lib.baseboard_fab2(sch_1):page131_i6@dev_discrete.cap_a~
(chips)',
 PATH='I6',
 DRAWING='@BASEBOARD_FAB2_LIB.BASEBOARD_FAB2(SCH_1):PAGE131',
 TOLERANCE='20%',
 MATERIAL='X6S',
 BOM_COST='SB',
 PHYS_PAGE='131',
 XY='(-875,4975)',
 ROT='0',
 VER='1',
 VALUE='22.0UF',
 PACK_TYPE='0603V',
 PART_NUMBER='E15431-004',
 LOCATION='C7B20',
 ROOM='SB_DECOUPLING',
 CDS_LIB='dev_discrete',
 CDS_PART_NAME='CAP_A_0603V-22.0UF,4V,20%,X6S,A',
 VOLTAGE='4V',
 PRIM_FILE='./archive_libs/discrete/cap_a/chips/chips.prt';

PART_NAME
 C7B21 'CAP_A_0603V-22.0UF,4V,20%,X6S,A':
 ROOM='SB_DECOUPLING';

SECTION_NUMBER 1
 '@BASEBOARD_FAB2_LIB.BASEBOARD_FAB2(SCH_1):PAGE131_I4@DEV_DISCRETE.CAP_A(CHIPS)':
 C_PATH='@baseboard_fab2_lib.baseboard_fab2(sch_1):page131_i4@dev_discrete.cap_a~
(chips)',
 P_PATH='@baseboard_fab2_lib.baseboard_fab2(sch_1):page131_i4@dev_discrete.cap_a~
(chips)',
 PATH='I4',
 DRAWING='@BASEBOARD_FAB2_LIB.BASEBOARD_FAB2(SCH_1):PAGE131',
 TOLERANCE='20%',
 MATERIAL='X6S',
 BOM_COST='SB',
 PHYS_PAGE='131',
 XY='(-425,4975)',
 ROT='0',
 VER='1',
 VALUE='22.0UF',
 PACK_TYPE='0603V',
 PART_NUMBER='E15431-004',
 LOCATION='C7B21',
 ROOM='SB_DECOUPLING',
 CDS_LIB='dev_discrete',
 CDS_PART_NAME='CAP_A_0603V-22.0UF,4V,20%,X6S,A',
 VOLTAGE='4V',
 PRIM_FILE='./archive_libs/discrete/cap_a/chips/chips.prt';

PART_NAME
 C7B22 'CAP_A_0603V-22.0UF,4V,20%,X6S,A':
 ROOM='SB_DECOUPLING';

SECTION_NUMBER 1
 '@BASEBOARD_FAB2_LIB.BASEBOARD_FAB2(SCH_1):PAGE131_I10@DEV_DISCRETE.CAP_A(CHIPS)':
 C_PATH='@baseboard_fab2_lib.baseboard_fab2(sch_1):page131_i10@dev_discrete.cap_~
a(chips)',
 P_PATH='@baseboard_fab2_lib.baseboard_fab2(sch_1):page131_i10@dev_discrete.cap_~
a(chips)',
 PATH='I10',
 DRAWING='@BASEBOARD_FAB2_LIB.BASEBOARD_FAB2(SCH_1):PAGE131',
 TOLERANCE='20%',
 MATERIAL='X6S',
 BOM_COST='SB',
 PHYS_PAGE='131',
 XY='(500,4025)',
 ROT='0',
 VER='1',
 VALUE='22.0UF',
 PACK_TYPE='0603V',
 PART_NUMBER='E15431-004',
 LOCATION='C7B22',
 ROOM='SB_DECOUPLING',
 CDS_LIB='dev_discrete',
 CDS_PART_NAME='CAP_A_0603V-22.0UF,4V,20%,X6S,A',
 VOLTAGE='4V',
 PRIM_FILE='./archive_libs/discrete/cap_a/chips/chips.prt';

PART_NAME
 C7B23 'CAP_A_0603V-22.0UF,4V,20%,X6S,A':
 ROOM='SB_DECOUPLING';

SECTION_NUMBER 1
 '@BASEBOARD_FAB2_LIB.BASEBOARD_FAB2(SCH_1):PAGE131_I7@DEV_DISCRETE.CAP_A(CHIPS)':
 C_PATH='@baseboard_fab2_lib.baseboard_fab2(sch_1):page131_i7@dev_discrete.cap_a~
(chips)',
 P_PATH='@baseboard_fab2_lib.baseboard_fab2(sch_1):page131_i7@dev_discrete.cap_a~
(chips)',
 PATH='I7',
 DRAWING='@BASEBOARD_FAB2_LIB.BASEBOARD_FAB2(SCH_1):PAGE131',
 TOLERANCE='20%',
 MATERIAL='X6S',
 BOM_COST='SB',
 PHYS_PAGE='131',
 XY='(975,4025)',
 ROT='0',
 VER='1',
 VALUE='22.0UF',
 PACK_TYPE='0603V',
 PART_NUMBER='E15431-004',
 LOCATION='C7B23',
 ROOM='SB_DECOUPLING',
 CDS_LIB='dev_discrete',
 CDS_PART_NAME='CAP_A_0603V-22.0UF,4V,20%,X6S,A',
 VOLTAGE='4V',
 PRIM_FILE='./archive_libs/discrete/cap_a/chips/chips.prt';

PART_NAME
 C7B24 'CAP_A_0603V-22.0UF,4V,20%,X6S,A':
 ROOM='SB_DECOUPLING';

SECTION_NUMBER 1
 '@BASEBOARD_FAB2_LIB.BASEBOARD_FAB2(SCH_1):PAGE131_I11@DEV_DISCRETE.CAP_A(CHIPS)':
 C_PATH='@baseboard_fab2_lib.baseboard_fab2(sch_1):page131_i11@dev_discrete.cap_~
a(chips)',
 P_PATH='@baseboard_fab2_lib.baseboard_fab2(sch_1):page131_i11@dev_discrete.cap_~
a(chips)',
 PATH='I11',
 DRAWING='@BASEBOARD_FAB2_LIB.BASEBOARD_FAB2(SCH_1):PAGE131',
 TOLERANCE='20%',
 MATERIAL='X6S',
 BOM_COST='SB',
 PHYS_PAGE='131',
 XY='(50,4025)',
 ROT='0',
 VER='1',
 VALUE='22.0UF',
 PACK_TYPE='0603V',
 PART_NUMBER='E15431-004',
 LOCATION='C7B24',
 ROOM='SB_DECOUPLING',
 CDS_LIB='dev_discrete',
 CDS_PART_NAME='CAP_A_0603V-22.0UF,4V,20%,X6S,A',
 VOLTAGE='4V',
 PRIM_FILE='./archive_libs/discrete/cap_a/chips/chips.prt';

PART_NAME
 C7B25 'CAP_0402-0.22UF,16V,10%,X7R,A3A':
 ROOM='DMI';

SECTION_NUMBER 1
 '@BASEBOARD_FAB2_LIB.BASEBOARD_FAB2(SCH_1):PAGE129_I35@MSTR_DISCRETE.CAP(CHIPS)':
 C_PATH='@baseboard_fab2_lib.baseboard_fab2(sch_1):page129_i35@mstr_discrete.cap~
(chips)',
 P_PATH='@baseboard_fab2_lib.baseboard_fab2(sch_1):page129_i35@mstr_discrete.cap~
(chips)',
 PATH='I35',
 DRAWING='@BASEBOARD_FAB2_LIB.BASEBOARD_FAB2(SCH_1):PAGE129',
 TOLERANCE='10%',
 MATERIAL='X7R',
 BOM_COST='SB',
 PHYS_PAGE='129',
 XY='(-3650,4925)',
 ROT='1',
 VER='1',
 VALUE='0.22UF',
 PACK_TYPE='0402',
 PART_NUMBER='A36096-155',
 LOCATION='C7B25',
 ROOM='DMI',
 CDS_LIB='mstr_discrete',
 CDS_PART_NAME='CAP_0402-0.22UF,16V,10%,X7R,A3A',
 VOLTAGE='16V',
 PRIM_FILE='./archive_libs/mstr_discrete/cap/chips/chips.prt';

PART_NAME
 C7B26 'CAP_0402-0.22UF,16V,10%,X7R,A3A':
 ROOM='DMI';

SECTION_NUMBER 1
 '@BASEBOARD_FAB2_LIB.BASEBOARD_FAB2(SCH_1):PAGE129_I79@MSTR_DISCRETE.CAP(CHIPS)':
 C_PATH='@baseboard_fab2_lib.baseboard_fab2(sch_1):page129_i79@mstr_discrete.cap~
(chips)',
 P_PATH='@baseboard_fab2_lib.baseboard_fab2(sch_1):page129_i79@mstr_discrete.cap~
(chips)',
 PATH='I79',
 DRAWING='@BASEBOARD_FAB2_LIB.BASEBOARD_FAB2(SCH_1):PAGE129',
 TOLERANCE='10%',
 MATERIAL='X7R',
 BOM_COST='SB',
 PHYS_PAGE='129',
 XY='(400,4925)',
 ROT='1',
 VER='1',
 VALUE='0.22UF',
 PACK_TYPE='0402',
 PART_NUMBER='A36096-155',
 LOCATION='C7B26',
 ROOM='DMI',
 CDS_LIB='mstr_discrete',
 CDS_PART_NAME='CAP_0402-0.22UF,16V,10%,X7R,A3A',
 VOLTAGE='16V',
 PRIM_FILE='./archive_libs/mstr_discrete/cap/chips/chips.prt';

PART_NAME
 C7B27 'CAP_0402-0.22UF,16V,10%,X7R,A3A':
 ROOM='DMI';

SECTION_NUMBER 1
 '@BASEBOARD_FAB2_LIB.BASEBOARD_FAB2(SCH_1):PAGE129_I69@MSTR_DISCRETE.CAP(CHIPS)':
 C_PATH='@baseboard_fab2_lib.baseboard_fab2(sch_1):page129_i69@mstr_discrete.cap~
(chips)',
 P_PATH='@baseboard_fab2_lib.baseboard_fab2(sch_1):page129_i69@mstr_discrete.cap~
(chips)',
 PATH='I69',
 DRAWING='@BASEBOARD_FAB2_LIB.BASEBOARD_FAB2(SCH_1):PAGE129',
 TOLERANCE='10%',
 MATERIAL='X7R',
 BOM_COST='SB',
 PHYS_PAGE='129',
 XY='(-3300,4725)',
 ROT='1',
 VER='1',
 VALUE='0.22UF',
 PACK_TYPE='0402',
 PART_NUMBER='A36096-155',
 LOCATION='C7B27',
 ROOM='DMI',
 CDS_LIB='mstr_discrete',
 CDS_PART_NAME='CAP_0402-0.22UF,16V,10%,X7R,A3A',
 VOLTAGE='16V',
 PRIM_FILE='./archive_libs/mstr_discrete/cap/chips/chips.prt';

PART_NAME
 C7B28 'CAP_0402-0.22UF,16V,10%,X7R,A3A':
 ROOM='DMI';

SECTION_NUMBER 1
 '@BASEBOARD_FAB2_LIB.BASEBOARD_FAB2(SCH_1):PAGE129_I70@MSTR_DISCRETE.CAP(CHIPS)':
 C_PATH='@baseboard_fab2_lib.baseboard_fab2(sch_1):page129_i70@mstr_discrete.cap~
(chips)',
 P_PATH='@baseboard_fab2_lib.baseboard_fab2(sch_1):page129_i70@mstr_discrete.cap~
(chips)',
 PATH='I70',
 DRAWING='@BASEBOARD_FAB2_LIB.BASEBOARD_FAB2(SCH_1):PAGE129',
 TOLERANCE='10%',
 MATERIAL='X7R',
 BOM_COST='SB',
 PHYS_PAGE='129',
 XY='(-3650,4525)',
 ROT='1',
 VER='1',
 VALUE='0.22UF',
 PACK_TYPE='0402',
 PART_NUMBER='A36096-155',
 LOCATION='C7B28',
 ROOM='DMI',
 CDS_LIB='mstr_discrete',
 CDS_PART_NAME='CAP_0402-0.22UF,16V,10%,X7R,A3A',
 VOLTAGE='16V',
 PRIM_FILE='./archive_libs/mstr_discrete/cap/chips/chips.prt';

PART_NAME
 C7B29 'CAP_0402-0.22UF,16V,10%,X7R,A3A':
 ROOM='DMI';

SECTION_NUMBER 1
 '@BASEBOARD_FAB2_LIB.BASEBOARD_FAB2(SCH_1):PAGE129_I78@MSTR_DISCRETE.CAP(CHIPS)':
 C_PATH='@baseboard_fab2_lib.baseboard_fab2(sch_1):page129_i78@mstr_discrete.cap~
(chips)',
 P_PATH='@baseboard_fab2_lib.baseboard_fab2(sch_1):page129_i78@mstr_discrete.cap~
(chips)',
 PATH='I78',
 DRAWING='@BASEBOARD_FAB2_LIB.BASEBOARD_FAB2(SCH_1):PAGE129',
 TOLERANCE='10%',
 MATERIAL='X7R',
 BOM_COST='SB',
 PHYS_PAGE='129',
 XY='(750,4725)',
 ROT='1',
 VER='1',
 VALUE='0.22UF',
 PACK_TYPE='0402',
 PART_NUMBER='A36096-155',
 LOCATION='C7B29',
 ROOM='DMI',
 CDS_LIB='mstr_discrete',
 CDS_PART_NAME='CAP_0402-0.22UF,16V,10%,X7R,A3A',
 VOLTAGE='16V',
 PRIM_FILE='./archive_libs/mstr_discrete/cap/chips/chips.prt';

PART_NAME
 C7B30 'CAP_0603LF-0.1UF,25V,10%,X7R,6A':
 ROOM='PVPP_KLM_VR',
 REUSE_ID='27';

SECTION_NUMBER 1
 '@BASEBOARD_FAB2_LIB.BASEBOARD_FAB2(SCH_1):PAGE232_I241@MSTR_DISCRETE.CAP(CHIPS)':
 C_PATH='@baseboard_fab2_lib.baseboard_fab2(sch_1):page232_i241@mstr_discrete.ca~
p(chips)',
 P_PATH='@baseboard_fab2_lib.baseboard_fab2(sch_1):page232_i241@mstr_discrete.ca~
p(chips)',
 PATH='I241',
 DRAWING='@BASEBOARD_FAB2_LIB.BASEBOARD_FAB2(SCH_1):PAGE232',
 SPOF='TRUE',
 TOLERANCE='10%',
 MATERIAL='X7R',
 BOM_COST='PVPP_KLM_VR',
 PHYS_PAGE='232',
 REUSE_ID='27',
 XY='(-3675,4200)',
 ROT='2',
 VER='2',
 VALUE='0.1UF',
 PACK_TYPE='0603LF',
 PART_NUMBER='602433-020',
 LOCATION='C7B30',
 ROOM='PVPP_KLM_VR',
 CDS_LIB='mstr_discrete',
 CDS_PART_NAME='CAP_0603LF-0.1UF,25V,10%,X7R,6A',
 VOLTAGE='25V',
 PRIM_FILE='./archive_libs/mstr_discrete/cap/chips/chips.prt';

PART_NAME
 C7C1 'CAP_0402-0.22UF,16V,10%,X7R,A3A':
 ROOM='DMI';

SECTION_NUMBER 1
 '@BASEBOARD_FAB2_LIB.BASEBOARD_FAB2(SCH_1):PAGE129_I77@MSTR_DISCRETE.CAP(CHIPS)':
 C_PATH='@baseboard_fab2_lib.baseboard_fab2(sch_1):page129_i77@mstr_discrete.cap~
(chips)',
 P_PATH='@baseboard_fab2_lib.baseboard_fab2(sch_1):page129_i77@mstr_discrete.cap~
(chips)',
 PATH='I77',
 DRAWING='@BASEBOARD_FAB2_LIB.BASEBOARD_FAB2(SCH_1):PAGE129',
 TOLERANCE='10%',
 MATERIAL='X7R',
 BOM_COST='SB',
 PHYS_PAGE='129',
 XY='(400,4525)',
 ROT='1',
 VER='1',
 VALUE='0.22UF',
 PACK_TYPE='0402',
 PART_NUMBER='A36096-155',
 LOCATION='C7C1',
 ROOM='DMI',
 CDS_LIB='mstr_discrete',
 CDS_PART_NAME='CAP_0402-0.22UF,16V,10%,X7R,A3A',
 VOLTAGE='16V',
 PRIM_FILE='./archive_libs/mstr_discrete/cap/chips/chips.prt';

PART_NAME
 C7C2 'CAP_0402-0.22UF,16V,10%,X7R,A3A':
 ROOM='DMI';

SECTION_NUMBER 1
 '@BASEBOARD_FAB2_LIB.BASEBOARD_FAB2(SCH_1):PAGE129_I71@MSTR_DISCRETE.CAP(CHIPS)':
 C_PATH='@baseboard_fab2_lib.baseboard_fab2(sch_1):page129_i71@mstr_discrete.cap~
(chips)',
 P_PATH='@baseboard_fab2_lib.baseboard_fab2(sch_1):page129_i71@mstr_discrete.cap~
(chips)',
 PATH='I71',
 DRAWING='@BASEBOARD_FAB2_LIB.BASEBOARD_FAB2(SCH_1):PAGE129',
 TOLERANCE='10%',
 MATERIAL='X7R',
 BOM_COST='SB',
 PHYS_PAGE='129',
 XY='(-3300,4325)',
 ROT='1',
 VER='1',
 VALUE='0.22UF',
 PACK_TYPE='0402',
 PART_NUMBER='A36096-155',
 LOCATION='C7C2',
 ROOM='DMI',
 CDS_LIB='mstr_discrete',
 CDS_PART_NAME='CAP_0402-0.22UF,16V,10%,X7R,A3A',
 VOLTAGE='16V',
 PRIM_FILE='./archive_libs/mstr_discrete/cap/chips/chips.prt';

PART_NAME
 C7C3 'CAP_0402-0.22UF,16V,10%,X7R,A3A':
 ROOM='DMI';

SECTION_NUMBER 1
 '@BASEBOARD_FAB2_LIB.BASEBOARD_FAB2(SCH_1):PAGE129_I76@MSTR_DISCRETE.CAP(CHIPS)':
 C_PATH='@baseboard_fab2_lib.baseboard_fab2(sch_1):page129_i76@mstr_discrete.cap~
(chips)',
 P_PATH='@baseboard_fab2_lib.baseboard_fab2(sch_1):page129_i76@mstr_discrete.cap~
(chips)',
 PATH='I76',
 DRAWING='@BASEBOARD_FAB2_LIB.BASEBOARD_FAB2(SCH_1):PAGE129',
 TOLERANCE='10%',
 MATERIAL='X7R',
 BOM_COST='SB',
 PHYS_PAGE='129',
 XY='(750,4325)',
 ROT='1',
 VER='1',
 VALUE='0.22UF',
 PACK_TYPE='0402',
 PART_NUMBER='A36096-155',
 LOCATION='C7C3',
 ROOM='DMI',
 CDS_LIB='mstr_discrete',
 CDS_PART_NAME='CAP_0402-0.22UF,16V,10%,X7R,A3A',
 VOLTAGE='16V',
 PRIM_FILE='./archive_libs/mstr_discrete/cap/chips/chips.prt';

PART_NAME
 C7C4 'CAP_0402LF-15.0PF,50V,5%,COG,AA':
 ROOM='SB';

SECTION_NUMBER 1
 '@BASEBOARD_FAB2_LIB.BASEBOARD_FAB2(SCH_1):PAGE114_I50@MSTR_DISCRETE.CAP(CHIPS)':
 C_PATH='@baseboard_fab2_lib.baseboard_fab2(sch_1):page114_i50@mstr_discrete.cap~
(chips)',
 P_PATH='@baseboard_fab2_lib.baseboard_fab2(sch_1):page114_i50@mstr_discrete.cap~
(chips)',
 PATH='I50',
 DRAWING='@BASEBOARD_FAB2_LIB.BASEBOARD_FAB2(SCH_1):PAGE114',
 NEW_VALUE='6.8PF',
 CONFIG='78.6R864.1FL',
 TOLERANCE='5%',
 SEC_TYPE='0402LF',
 MATERIAL='COG',
 BOM_COST='SYS_CLOCK',
 PHYS_PAGE='114',
 XY='(-2025,-200)',
 ROT='0',
 VER='1',
 VALUE='15.0PF',
 PACK_TYPE='0402LF',
 PART_NUMBER='A36095-047',
 LOCATION='C7C4',
 ROOM='SB',
 SEC='1',
 CDS_LIB='mstr_discrete',
 CDS_PART_NAME='CAP_0402LF-15.0PF,50V,5%,COG,AA',
 VOLTAGE='50V',
 PRIM_FILE='./archive_libs/mstr_discrete/cap/chips/chips.prt';

PART_NAME
 C7C5 'CAP_0402LF-15.0PF,50V,5%,COG,AA':
 ROOM='SB';

SECTION_NUMBER 1
 '@BASEBOARD_FAB2_LIB.BASEBOARD_FAB2(SCH_1):PAGE114_I47@MSTR_DISCRETE.CAP(CHIPS)':
 C_PATH='@baseboard_fab2_lib.baseboard_fab2(sch_1):page114_i47@mstr_discrete.cap~
(chips)',
 P_PATH='@baseboard_fab2_lib.baseboard_fab2(sch_1):page114_i47@mstr_discrete.cap~
(chips)',
 PATH='I47',
 DRAWING='@BASEBOARD_FAB2_LIB.BASEBOARD_FAB2(SCH_1):PAGE114',
 NEW_VALUE='6.8PF',
 CONFIG='78.6R864.1FL',
 TOLERANCE='5%',
 SEC_TYPE='0402LF',
 MATERIAL='COG',
 BOM_COST='SYS_CLOCK',
 PHYS_PAGE='114',
 XY='(-1525,-200)',
 ROT='0',
 VER='1',
 VALUE='15.0PF',
 PACK_TYPE='0402LF',
 PART_NUMBER='A36095-047',
 LOCATION='C7C5',
 ROOM='SB',
 SEC='1',
 CDS_LIB='mstr_discrete',
 CDS_PART_NAME='CAP_0402LF-15.0PF,50V,5%,COG,AA',
 VOLTAGE='50V',
 PRIM_FILE='./archive_libs/mstr_discrete/cap/chips/chips.prt';

PART_NAME
 C7C6 'CAP_A_0603V-22.0UF,4V,20%,X6S,A':
 GROUP='PWR_MLCC_CAP',
 ROOM='PVCCIO_CPU0';

SECTION_NUMBER 1
 '@BASEBOARD_FAB2_LIB.BASEBOARD_FAB2(SCH_1):PAGE212_I23@DEV_DISCRETE.CAP_A(CHIPS)':
 C_PATH='@baseboard_fab2_lib.baseboard_fab2(sch_1):page212_i23@dev_discrete.cap_~
a(chips)',
 P_PATH='@baseboard_fab2_lib.baseboard_fab2(sch_1):page212_i23@dev_discrete.cap_~
a(chips)',
 PATH='I23',
 DRAWING='@BASEBOARD_FAB2_LIB.BASEBOARD_FAB2(SCH_1):PAGE212',
 TOLERANCE='20%',
 SEC_TYPE='0603V',
 MATERIAL='X6S',
 BOM_COST='PROC_VRD_PVCCIO_CPU0',
 PHYS_PAGE='212',
 XY='(3350,3450)',
 ROT='0',
 VER='1',
 VALUE='22.0UF',
 PACK_TYPE='0603V',
 PART_NUMBER='E15431-004',
 LOCATION='C7C6',
 ROOM='PVCCIO_CPU0',
 GROUP='PWR_MLCC_CAP',
 SEC='1',
 CDS_LIB='dev_discrete',
 CDS_PART_NAME='CAP_A_0603V-22.0UF,4V,20%,X6S,A',
 VOLTAGE='4V',
 PRIM_FILE='./archive_libs/discrete/cap_a/chips/chips.prt';

PART_NAME
 C7C7 'SC22U16V5MX-4-GP_SMD-BCG5-SC22A':;

SECTION_NUMBER 1
 '@BASEBOARD_FAB2_LIB.BASEBOARD_FAB2(SCH_1):PAGE212_I138@W_HDL.SC22U16V5MX-4-GP(CHIPS)':
 C_PATH='@baseboard_fab2_lib.baseboard_fab2(sch_1):page212_i138@w_hdl.\sc22u16v5~
mx-4-gp\(chips)',
 P_PATH='@baseboard_fab2_lib.baseboard_fab2(sch_1):page212_i138@w_hdl.\sc22u16v5~
mx-4-gp\(chips)',
 PATH='I138',
 DRAWING='@BASEBOARD_FAB2_LIB.BASEBOARD_FAB2(SCH_1):PAGE212',
 TYPE='X6S',
 PACK_SIZE='0805',
 RATED='16V',
 ATTRIBUTE='22UF',
 TOLERANCE='20%',
 SEC_TYPE='SMD-BCG5',
 PHYS_PAGE='212',
 XY='(650,2175)',
 ROT='0',
 VER='1',
 VALUE='SC22U16V5MX-4-GP',
 PACK_TYPE='SMD-BCG5',
 PART_NUMBER='078.22611.0811',
 LOCATION='C7C7',
 SEC='1',
 CDS_LIB='w_hdl',
 CDS_PART_NAME='SC22U16V5MX-4-GP_SMD-BCG5-SC22A',
 PRIM_FILE='C:/<user>/w_hdl/sc22u16v5mx#2d4#2dgp/chips/chips.prt';

PART_NAME
 C7C8 'SC22U16V5MX-4-GP_SMD-BCG5-SC22A':;

SECTION_NUMBER 1
 '@BASEBOARD_FAB2_LIB.BASEBOARD_FAB2(SCH_1):PAGE212_I130@W_HDL.SC22U16V5MX-4-GP(CHIPS)':
 C_PATH='@baseboard_fab2_lib.baseboard_fab2(sch_1):page212_i130@w_hdl.\sc22u16v5~
mx-4-gp\(chips)',
 P_PATH='@baseboard_fab2_lib.baseboard_fab2(sch_1):page212_i130@w_hdl.\sc22u16v5~
mx-4-gp\(chips)',
 PATH='I130',
 DRAWING='@BASEBOARD_FAB2_LIB.BASEBOARD_FAB2(SCH_1):PAGE212',
 TYPE='X6S',
 PACK_SIZE='0805',
 RATED='16V',
 ATTRIBUTE='22UF',
 TOLERANCE='20%',
 SEC_TYPE='SMD-BCG5',
 PHYS_PAGE='212',
 XY='(2000,2175)',
 ROT='0',
 VER='1',
 VALUE='SC22U16V5MX-4-GP',
 PACK_TYPE='SMD-BCG5',
 PART_NUMBER='078.22611.0811',
 LOCATION='C7C8',
 SEC='1',
 CDS_LIB='w_hdl',
 CDS_PART_NAME='SC22U16V5MX-4-GP_SMD-BCG5-SC22A',
 PRIM_FILE='C:/<user>/w_hdl/sc22u16v5mx#2d4#2dgp/chips/chips.prt';

PART_NAME
 C7C9 'CAP_A_0603V-22.0UF,4V,20%,X6S,A':
 ROOM='SB_DECOUPLING';

SECTION_NUMBER 1
 '@BASEBOARD_FAB2_LIB.BASEBOARD_FAB2(SCH_1):PAGE132_I7@DEV_DISCRETE.CAP_A(CHIPS)':
 C_PATH='@baseboard_fab2_lib.baseboard_fab2(sch_1):page132_i7@dev_discrete.cap_a~
(chips)',
 P_PATH='@baseboard_fab2_lib.baseboard_fab2(sch_1):page132_i7@dev_discrete.cap_a~
(chips)',
 PATH='I7',
 DRAWING='@BASEBOARD_FAB2_LIB.BASEBOARD_FAB2(SCH_1):PAGE132',
 TOLERANCE='20%',
 MATERIAL='X6S',
 BOM_COST='SB',
 PHYS_PAGE='132',
 XY='(2550,3500)',
 ROT='0',
 VER='1',
 VALUE='22.0UF',
 PACK_TYPE='0603V',
 PART_NUMBER='E15431-004',
 LOCATION='C7C9',
 ROOM='SB_DECOUPLING',
 CDS_LIB='dev_discrete',
 CDS_PART_NAME='CAP_A_0603V-22.0UF,4V,20%,X6S,A',
 VOLTAGE='4V',
 PRIM_FILE='./archive_libs/discrete/cap_a/chips/chips.prt';

PART_NAME
 C7C10 'CAP_A_0603V-22.0UF,4V,20%,X6S,A':
 GROUP='PWR_MLCC_CAP';

SECTION_NUMBER 1
 '@BASEBOARD_FAB2_LIB.BASEBOARD_FAB2(SCH_1):PAGE212_I77@DEV_DISCRETE.CAP_A(CHIPS)':
 C_PATH='@baseboard_fab2_lib.baseboard_fab2(sch_1):page212_i77@dev_discrete.cap_~
a(chips)',
 P_PATH='@baseboard_fab2_lib.baseboard_fab2(sch_1):page212_i77@dev_discrete.cap_~
a(chips)',
 PATH='I77',
 DRAWING='@BASEBOARD_FAB2_LIB.BASEBOARD_FAB2(SCH_1):PAGE212',
 TOLERANCE='20%',
 SEC_TYPE='0603V',
 MATERIAL='X6S',
 PHYS_PAGE='212',
 XY='(3650,3450)',
 ROT='0',
 VER='1',
 VALUE='22.0UF',
 PACK_TYPE='0603V',
 PART_NUMBER='E15431-004',
 LOCATION='C7C10',
 GROUP='PWR_MLCC_CAP',
 SEC='1',
 CDS_LIB='dev_discrete',
 CDS_PART_NAME='CAP_A_0603V-22.0UF,4V,20%,X6S,A',
 VOLTAGE='4V',
 PRIM_FILE='./archive_libs/discrete/cap_a/chips/chips.prt';

PART_NAME
 C7C11 'CAP_A_0402V-0.1UF,16V,10%,X7R,A':
 ROOM='PVCCIO_CPU0';

SECTION_NUMBER 1
 '@BASEBOARD_FAB2_LIB.BASEBOARD_FAB2(SCH_1):PAGE212_I38@DEV_DISCRETE.CAP_A(CHIPS)':
 C_PATH='@baseboard_fab2_lib.baseboard_fab2(sch_1):page212_i38@dev_discrete.cap_~
a(chips)',
 P_PATH='@baseboard_fab2_lib.baseboard_fab2(sch_1):page212_i38@dev_discrete.cap_~
a(chips)',
 PATH='I38',
 DRAWING='@BASEBOARD_FAB2_LIB.BASEBOARD_FAB2(SCH_1):PAGE212',
 TOLERANCE='10%',
 SEC_TYPE='0402V',
 MATERIAL='X7R',
 PHYS_PAGE='212',
 XY='(-1650,4225)',
 ROT='0',
 VER='1',
 VALUE='0.1UF',
 PACK_TYPE='0402V',
 PART_NUMBER='A36096-030',
 LOCATION='C7C11',
 ROOM='PVCCIO_CPU0',
 SEC='1',
 CDS_LIB='dev_discrete',
 CDS_PART_NAME='CAP_A_0402V-0.1UF,16V,10%,X7R,A',
 VOLTAGE='16V',
 PRIM_FILE='./archive_libs/discrete/cap_a/chips/chips.prt';

PART_NAME
 C7C12 'CAP_0402-1.0UF,16V,10%,X6S,D97A':
 ROOM='PVCCIO_CPU0';

SECTION_NUMBER 1
 '@BASEBOARD_FAB2_LIB.BASEBOARD_FAB2(SCH_1):PAGE212_I39@MSTR_DISCRETE.CAP(CHIPS)':
 C_PATH='@baseboard_fab2_lib.baseboard_fab2(sch_1):page212_i39@mstr_discrete.cap~
(chips)',
 P_PATH='@baseboard_fab2_lib.baseboard_fab2(sch_1):page212_i39@mstr_discrete.cap~
(chips)',
 PATH='I39',
 DRAWING='@BASEBOARD_FAB2_LIB.BASEBOARD_FAB2(SCH_1):PAGE212',
 TOLERANCE='10%',
 SEC_TYPE='0402',
 MATERIAL='X6S',
 PHYS_PAGE='212',
 XY='(-1950,4225)',
 ROT='0',
 VER='1',
 VALUE='1.0UF',
 PACK_TYPE='0402',
 PART_NUMBER='D97712-011',
 LOCATION='C7C12',
 ROOM='PVCCIO_CPU0',
 SEC='1',
 CDS_LIB='mstr_discrete',
 CDS_PART_NAME='CAP_0402-1.0UF,16V,10%,X6S,D97A',
 VOLTAGE='16V',
 PRIM_FILE='./archive_libs/mstr_discrete/cap/chips/chips.prt';

PART_NAME
 C7C13 'CAP_0402LF-15.0PF,50V,5%,COG,AA':
 ROOM='SB';

SECTION_NUMBER 1
 '@BASEBOARD_FAB2_LIB.BASEBOARD_FAB2(SCH_1):PAGE114_I195@MSTR_DISCRETE.CAP(CHIPS)':
 C_PATH='@baseboard_fab2_lib.baseboard_fab2(sch_1):page114_i195@mstr_discrete.ca~
p(chips)',
 P_PATH='@baseboard_fab2_lib.baseboard_fab2(sch_1):page114_i195@mstr_discrete.ca~
p(chips)',
 PATH='I195',
 DRAWING='@BASEBOARD_FAB2_LIB.BASEBOARD_FAB2(SCH_1):PAGE114',
 TOLERANCE='5%',
 SEC_TYPE='0402LF',
 MATERIAL='COG',
 BOM_COST='SYS_CLOCK',
 PHYS_PAGE='114',
 XY='(-275,-225)',
 ROT='0',
 VER='1',
 VALUE='15.0PF',
 PACK_TYPE='0402LF',
 PART_NUMBER='A36095-047',
 LOCATION='C7C13',
 ROOM='SB',
 SEC='1',
 CDS_LIB='mstr_discrete',
 CDS_PART_NAME='CAP_0402LF-15.0PF,50V,5%,COG,AA',
 VOLTAGE='50V',
 PRIM_FILE='./archive_libs/mstr_discrete/cap/chips/chips.prt';

PART_NAME
 C7C14 'CAP_0402-0.220UF,16V,10%,X7R,AA':
 ROOM='PVCCIO_CPU0';

SECTION_NUMBER 1
 '@BASEBOARD_FAB2_LIB.BASEBOARD_FAB2(SCH_1):PAGE212_I37@MSTR_DISCRETE.CAP(CHIPS)':
 C_PATH='@baseboard_fab2_lib.baseboard_fab2(sch_1):page212_i37@mstr_discrete.cap~
(chips)',
 P_PATH='@baseboard_fab2_lib.baseboard_fab2(sch_1):page212_i37@mstr_discrete.cap~
(chips)',
 PATH='I37',
 DRAWING='@BASEBOARD_FAB2_LIB.BASEBOARD_FAB2(SCH_1):PAGE212',
 SPOF='TRUE',
 TOLERANCE='10%',
 SEC_TYPE='0402',
 MATERIAL='X7R',
 PHYS_PAGE='212',
 XY='(-1600,3600)',
 ROT='2',
 VER='1',
 VALUE='0.220UF',
 PACK_TYPE='0402',
 PART_NUMBER='A36096-104',
 LOCATION='C7C14',
 ROOM='PVCCIO_CPU0',
 SEC='1',
 CDS_LIB='mstr_discrete',
 CDS_PART_NAME='CAP_0402-0.220UF,16V,10%,X7R,AA',
 VOLTAGE='16V',
 PRIM_FILE='./archive_libs/mstr_discrete/cap/chips/chips.prt';

PART_NAME
 C7C15 'CAP_0402LF-15.0PF,50V,5%,COG,AA':
 ROOM='SB';

SECTION_NUMBER 1
 '@BASEBOARD_FAB2_LIB.BASEBOARD_FAB2(SCH_1):PAGE114_I196@MSTR_DISCRETE.CAP(CHIPS)':
 C_PATH='@baseboard_fab2_lib.baseboard_fab2(sch_1):page114_i196@mstr_discrete.ca~
p(chips)',
 P_PATH='@baseboard_fab2_lib.baseboard_fab2(sch_1):page114_i196@mstr_discrete.ca~
p(chips)',
 PATH='I196',
 DRAWING='@BASEBOARD_FAB2_LIB.BASEBOARD_FAB2(SCH_1):PAGE114',
 TOLERANCE='5%',
 SEC_TYPE='0402LF',
 MATERIAL='COG',
 BOM_COST='SYS_CLOCK',
 PHYS_PAGE='114',
 XY='(225,-225)',
 ROT='0',
 VER='1',
 VALUE='15.0PF',
 PACK_TYPE='0402LF',
 PART_NUMBER='A36095-047',
 LOCATION='C7C15',
 ROOM='SB',
 SEC='1',
 CDS_LIB='mstr_discrete',
 CDS_PART_NAME='CAP_0402LF-15.0PF,50V,5%,COG,AA',
 VOLTAGE='50V',
 PRIM_FILE='./archive_libs/mstr_discrete/cap/chips/chips.prt';

PART_NAME
 C7C17 'CAP_0402-1.0UF,16V,10%,X6S,D97A':
 ROOM='PVCCIO_CPU0';

SECTION_NUMBER 1
 '@BASEBOARD_FAB2_LIB.BASEBOARD_FAB2(SCH_1):PAGE212_I36@MSTR_DISCRETE.CAP(CHIPS)':
 C_PATH='@baseboard_fab2_lib.baseboard_fab2(sch_1):page212_i36@mstr_discrete.cap~
(chips)',
 P_PATH='@baseboard_fab2_lib.baseboard_fab2(sch_1):page212_i36@mstr_discrete.cap~
(chips)',
 PATH='I36',
 DRAWING='@BASEBOARD_FAB2_LIB.BASEBOARD_FAB2(SCH_1):PAGE212',
 TOLERANCE='10%',
 SEC_TYPE='0402',
 MATERIAL='X6S',
 PHYS_PAGE='212',
 XY='(-1350,4225)',
 ROT='0',
 VER='1',
 VALUE='1.0UF',
 PACK_TYPE='0402',
 PART_NUMBER='D97712-011',
 LOCATION='C7C17',
 ROOM='PVCCIO_CPU0',
 SEC='1',
 CDS_LIB='mstr_discrete',
 CDS_PART_NAME='CAP_0402-1.0UF,16V,10%,X6S,D97A',
 VOLTAGE='16V',
 PRIM_FILE='./archive_libs/mstr_discrete/cap/chips/chips.prt';

PART_NAME
 C7C18 'CAP_0402-0.22UF,16V,10%,X7R,A3A':
 ROOM='PVCCIO_CPU0';

SECTION_NUMBER 1
 '@BASEBOARD_FAB2_LIB.BASEBOARD_FAB2(SCH_1):PAGE212_I33@MSTR_DISCRETE.CAP(CHIPS)':
 C_PATH='@baseboard_fab2_lib.baseboard_fab2(sch_1):page212_i33@mstr_discrete.cap~
(chips)',
 P_PATH='@baseboard_fab2_lib.baseboard_fab2(sch_1):page212_i33@mstr_discrete.cap~
(chips)',
 PATH='I33',
 DRAWING='@BASEBOARD_FAB2_LIB.BASEBOARD_FAB2(SCH_1):PAGE212',
 TOLERANCE='10%',
 SEC_TYPE='0402',
 MATERIAL='X7R',
 PHYS_PAGE='212',
 XY='(-350,4225)',
 ROT='0',
 VER='1',
 VALUE='0.22UF',
 PACK_TYPE='0402',
 PART_NUMBER='A36096-155',
 LOCATION='C7C18',
 ROOM='PVCCIO_CPU0',
 SEC='1',
 CDS_LIB='mstr_discrete',
 CDS_PART_NAME='CAP_0402-0.22UF,16V,10%,X7R,A3A',
 VOLTAGE='16V',
 PRIM_FILE='./archive_libs/mstr_discrete/cap/chips/chips.prt';

PART_NAME
 C7C19 'CAP_A_0402V-1.0UF,6.3V,10%,X6SA':
 ROOM='SB';

SECTION_NUMBER 1
 '@BASEBOARD_FAB2_LIB.BASEBOARD_FAB2(SCH_1):PAGE137_I14@DEV_DISCRETE.CAP_A(CHIPS)':
 C_PATH='@baseboard_fab2_lib.baseboard_fab2(sch_1):page137_i14@dev_discrete.cap_~
a(chips)',
 P_PATH='@baseboard_fab2_lib.baseboard_fab2(sch_1):page137_i14@dev_discrete.cap_~
a(chips)',
 PATH='I14',
 DRAWING='@BASEBOARD_FAB2_LIB.BASEBOARD_FAB2(SCH_1):PAGE137',
 TOLERANCE='10%',
 SEC_TYPE='0402V',
 MATERIAL='X6S',
 BOM_COST='SB',
 PHYS_PAGE='137',
 XY='(-125,3450)',
 ROT='0',
 VER='1',
 VALUE='1.0UF',
 PACK_TYPE='0402V',
 PART_NUMBER='D97712-004',
 LOCATION='C7C19',
 ROOM='SB',
 SEC='1',
 CDS_LIB='dev_discrete',
 CDS_PART_NAME='CAP_A_0402V-1.0UF,6.3V,10%,X6SA',
 VOLTAGE='6.3V',
 PRIM_FILE='./archive_libs/discrete/cap_a/chips/chips.prt';

PART_NAME
 C7C20 'SC1U10V2KX-4-GP_SMD-BCG6-SC1U1A':;

SECTION_NUMBER 1
 '@BASEBOARD_FAB2_LIB.BASEBOARD_FAB2(SCH_1):PAGE212_I143@W_HDL.SC1U10V2KX-4-GP(CHIPS)':
 C_PATH='@baseboard_fab2_lib.baseboard_fab2(sch_1):page212_i143@w_hdl.\sc1u10v2k~
x-4-gp\(chips)',
 P_PATH='@baseboard_fab2_lib.baseboard_fab2(sch_1):page212_i143@w_hdl.\sc1u10v2k~
x-4-gp\(chips)',
 PATH='I143',
 DRAWING='@BASEBOARD_FAB2_LIB.BASEBOARD_FAB2(SCH_1):PAGE212',
 PACK_SIZE='0402',
 RATED='10V',
 ATTRIBUTE='1UF',
 TOLERANCE='10%',
 SEC_TYPE='SMD-BCG6',
 PHYS_PAGE='212',
 XY='(-825,4200)',
 ROT='0',
 VER='1',
 VALUE='SC1U10V2KX-4-GP',
 PACK_TYPE='SMD-BCG6',
 PART_NUMBER='78.10523.8FL',
 LOCATION='C7C20',
 SEC='1',
 CDS_LIB='w_hdl',
 CDS_PART_NAME='SC1U10V2KX-4-GP_SMD-BCG6-SC1U1A',
 PRIM_FILE='C:/<user>/w_hdl/sc1u10v2kx#2d4#2dgp/chips/chips.prt';

PART_NAME
 C7D1 'CAP_A_0402V-0.1UF,16V,10%,X7R,A':
 ROOM='SB';

SECTION_NUMBER 1
 '@BASEBOARD_FAB2_LIB.BASEBOARD_FAB2(SCH_1):PAGE118_I136@DEV_DISCRETE.CAP_A(CHIPS)':
 C_PATH='@baseboard_fab2_lib.baseboard_fab2(sch_1):page118_i136@dev_discrete.cap~
_a(chips)',
 P_PATH='@baseboard_fab2_lib.baseboard_fab2(sch_1):page118_i136@dev_discrete.cap~
_a(chips)',
 PATH='I136',
 DRAWING='@BASEBOARD_FAB2_LIB.BASEBOARD_FAB2(SCH_1):PAGE118',
 TOLERANCE='10%',
 SEC_TYPE='0402V',
 MATERIAL='X7R',
 BOM_COST='SB',
 PHYS_PAGE='118',
 XY='(-5200,375)',
 ROT='0',
 VER='1',
 VALUE='0.1UF',
 PACK_TYPE='0402V',
 PART_NUMBER='A36096-030',
 LOCATION='C7D1',
 ROOM='SB',
 SEC='1',
 CDS_LIB='dev_discrete',
 CDS_PART_NAME='CAP_A_0402V-0.1UF,16V,10%,X7R,A',
 VOLTAGE='16V',
 PRIM_FILE='./archive_libs/discrete/cap_a/chips/chips.prt';

PART_NAME
 C7D2 'CAP_0603-10UF,6.3V,20%,X6S,E15A':
 ROOM='SB_DECOUPLING';

SECTION_NUMBER 1
 '@BASEBOARD_FAB2_LIB.BASEBOARD_FAB2(SCH_1):PAGE130_I2@MSTR_DISCRETE.CAP(CHIPS)':
 C_PATH='@baseboard_fab2_lib.baseboard_fab2(sch_1):page130_i2@mstr_discrete.cap(~
chips)',
 P_PATH='@baseboard_fab2_lib.baseboard_fab2(sch_1):page130_i2@mstr_discrete.cap(~
chips)',
 PATH='I2',
 DRAWING='@BASEBOARD_FAB2_LIB.BASEBOARD_FAB2(SCH_1):PAGE130',
 TOLERANCE='20%',
 SEC_TYPE='0603',
 MATERIAL='X6S',
 BOM_COST='SB',
 PHYS_PAGE='130',
 XY='(1125,5003)',
 ROT='0',
 VER='1',
 VALUE='10UF',
 PACK_TYPE='0603',
 PART_NUMBER='E15431-002',
 LOCATION='C7D2',
 ROOM='SB_DECOUPLING',
 SEC='1',
 CDS_LIB='mstr_discrete',
 CDS_PART_NAME='CAP_0603-10UF,6.3V,20%,X6S,E15A',
 VOLTAGE='6.3V',
 PRIM_FILE='./archive_libs/mstr_discrete/cap/chips/chips.prt';

PART_NAME
 C7D3 'CAP_A_0603V-22.0UF,4V,20%,X6S,A':
 ROOM='SB_DECOUPLING';

SECTION_NUMBER 1
 '@BASEBOARD_FAB2_LIB.BASEBOARD_FAB2(SCH_1):PAGE130_I38@DEV_DISCRETE.CAP_A(CHIPS)':
 C_PATH='@baseboard_fab2_lib.baseboard_fab2(sch_1):page130_i38@dev_discrete.cap_~
a(chips)',
 P_PATH='@baseboard_fab2_lib.baseboard_fab2(sch_1):page130_i38@dev_discrete.cap_~
a(chips)',
 PATH='I38',
 DRAWING='@BASEBOARD_FAB2_LIB.BASEBOARD_FAB2(SCH_1):PAGE130',
 TOLERANCE='20%',
 MATERIAL='X6S',
 BOM_COST='SB',
 PHYS_PAGE='130',
 XY='(-3525,2750)',
 ROT='0',
 VER='1',
 VALUE='22.0UF',
 PACK_TYPE='0603V',
 PART_NUMBER='E15431-004',
 LOCATION='C7D3',
 ROOM='SB_DECOUPLING',
 CDS_LIB='dev_discrete',
 CDS_PART_NAME='CAP_A_0603V-22.0UF,4V,20%,X6S,A',
 VOLTAGE='4V',
 PRIM_FILE='./archive_libs/discrete/cap_a/chips/chips.prt';

PART_NAME
 C7D4 'CAP_0402-1.0UF,16V,10%,X6S,D97A':
 ROOM='PROC_SIDEBAND';

SECTION_NUMBER 1
 '@BASEBOARD_FAB2_LIB.BASEBOARD_FAB2(SCH_1):PAGE92_I79@MSTR_DISCRETE.CAP(CHIPS)':
 C_PATH='@baseboard_fab2_lib.baseboard_fab2(sch_1):page92_i79@mstr_discrete.cap(~
chips)',
 P_PATH='@baseboard_fab2_lib.baseboard_fab2(sch_1):page92_i79@mstr_discrete.cap(~
chips)',
 PATH='I79',
 DRAWING='@BASEBOARD_FAB2_LIB.BASEBOARD_FAB2(SCH_1):PAGE92',
 TOLERANCE='10%',
 SEC_TYPE='0402',
 MATERIAL='X6S',
 BOM_COST='PROC',
 PHYS_PAGE='92',
 XY='(-900,2525)',
 ROT='0',
 VER='1',
 VALUE='1.0UF',
 PACK_TYPE='0402',
 PART_NUMBER='D97712-011',
 LOCATION='C7D4',
 ROOM='PROC_SIDEBAND',
 SEC='1',
 CDS_LIB='mstr_discrete',
 CDS_PART_NAME='CAP_0402-1.0UF,16V,10%,X6S,D97A',
 VOLTAGE='16V',
 PRIM_FILE='./archive_libs/mstr_discrete/cap/chips/chips.prt';

PART_NAME
 C7D5 'CAP_A_0402V-0.1UF,16V,10%,X7R,A':
 ROOM='PROC_SIDEBAND';

SECTION_NUMBER 1
 '@BASEBOARD_FAB2_LIB.BASEBOARD_FAB2(SCH_1):PAGE92_I52@DEV_DISCRETE.CAP_A(CHIPS)':
 C_PATH='@baseboard_fab2_lib.baseboard_fab2(sch_1):page92_i52@dev_discrete.cap_a~
(chips)',
 P_PATH='@baseboard_fab2_lib.baseboard_fab2(sch_1):page92_i52@dev_discrete.cap_a~
(chips)',
 PATH='I52',
 DRAWING='@BASEBOARD_FAB2_LIB.BASEBOARD_FAB2(SCH_1):PAGE92',
 TOLERANCE='10%',
 SEC_TYPE='0402V',
 MATERIAL='X7R',
 BOM_COST='PROC_SIDEBAND',
 PHYS_PAGE='92',
 XY='(-100,2550)',
 ROT='0',
 VER='1',
 VALUE='0.1UF',
 PACK_TYPE='0402V',
 PART_NUMBER='A36096-030',
 LOCATION='C7D5',
 ROOM='PROC_SIDEBAND',
 SEC='1',
 CDS_LIB='dev_discrete',
 CDS_PART_NAME='CAP_A_0402V-0.1UF,16V,10%,X7R,A',
 VOLTAGE='16V',
 PRIM_FILE='./archive_libs/discrete/cap_a/chips/chips.prt';

PART_NAME
 C7E1 'CAP_A_0402V-0.1UF,16V,10%,X7R,A':
 ROOM='MEM',
 SIGNAL_MODEL='DEFAULT_CAPACITOR_100000pF_2_1';

SECTION_NUMBER 1
 '@BASEBOARD_FAB2_LIB.BASEBOARD_FAB2(SCH_1):PAGE99_I23@DEV_DISCRETE.CAP_A(CHIPS)':
 C_PATH='@baseboard_fab2_lib.baseboard_fab2(sch_1):page99_i23@dev_discrete.cap_a~
(chips)',
 P_PATH='@baseboard_fab2_lib.baseboard_fab2(sch_1):page99_i23@dev_discrete.cap_a~
(chips)',
 PATH='I23',
 DRAWING='@BASEBOARD_FAB2_LIB.BASEBOARD_FAB2(SCH_1):PAGE99',
 CD_SEC='1',
 TOLERANCE='10%',
 MATERIAL='X7R',
 BOM_COST='SM_CONTROLLER',
 PHYS_PAGE='99',
 XY='(2125,3775)',
 ROT='0',
 VER='1',
 VALUE='0.1UF',
 PACK_TYPE='0402V',
 PART_NUMBER='A36096-030',
 LOCATION='C7E1',
 SIGNAL_MODEL='DEFAULT_CAPACITOR_100000pF_2_1',
 ROOM='MEM',
 CDS_LIB='dev_discrete',
 CDS_PART_NAME='CAP_A_0402V-0.1UF,16V,10%,X7R,A',
 VOLTAGE='16V',
 PRIM_FILE='./archive_libs/discrete/cap_a/chips/chips.prt';

PART_NAME
 C7E2 'CAP_A_0402V-0.1UF,16V,10%,X7R,A':
 ROOM='MEM',
 SIGNAL_MODEL='DEFAULT_CAPACITOR_100000pF_2_1';

SECTION_NUMBER 1
 '@BASEBOARD_FAB2_LIB.BASEBOARD_FAB2(SCH_1):PAGE99_I32@DEV_DISCRETE.CAP_A(CHIPS)':
 C_PATH='@baseboard_fab2_lib.baseboard_fab2(sch_1):page99_i32@dev_discrete.cap_a~
(chips)',
 P_PATH='@baseboard_fab2_lib.baseboard_fab2(sch_1):page99_i32@dev_discrete.cap_a~
(chips)',
 PATH='I32',
 DRAWING='@BASEBOARD_FAB2_LIB.BASEBOARD_FAB2(SCH_1):PAGE99',
 CD_SEC='1',
 TOLERANCE='10%',
 MATERIAL='X7R',
 BOM_COST='SM_CONTROLLER',
 PHYS_PAGE='99',
 XY='(1625,3750)',
 ROT='0',
 VER='1',
 VALUE='0.1UF',
 PACK_TYPE='0402V',
 PART_NUMBER='A36096-030',
 LOCATION='C7E2',
 SIGNAL_MODEL='DEFAULT_CAPACITOR_100000pF_2_1',
 ROOM='MEM',
 CDS_LIB='dev_discrete',
 CDS_PART_NAME='CAP_A_0402V-0.1UF,16V,10%,X7R,A',
 VOLTAGE='16V',
 PRIM_FILE='./archive_libs/discrete/cap_a/chips/chips.prt';

PART_NAME
 C7E3 'CAP_A_0402V-0.1UF,16V,10%,X7R,A':
 ROOM='PROC_SIDEBAND';

SECTION_NUMBER 1
 '@BASEBOARD_FAB2_LIB.BASEBOARD_FAB2(SCH_1):PAGE95_I92@DEV_DISCRETE.CAP_A(CHIPS)':
 C_PATH='@baseboard_fab2_lib.baseboard_fab2(sch_1):page95_i92@dev_discrete.cap_a~
(chips)',
 P_PATH='@baseboard_fab2_lib.baseboard_fab2(sch_1):page95_i92@dev_discrete.cap_a~
(chips)',
 PATH='I92',
 DRAWING='@BASEBOARD_FAB2_LIB.BASEBOARD_FAB2(SCH_1):PAGE95',
 TOLERANCE='10%',
 SEC_TYPE='0402V',
 MATERIAL='X7R',
 BOM_COST='PROC_SIDEBAND',
 PHYS_PAGE='95',
 XY='(700,4775)',
 ROT='0',
 VER='1',
 VALUE='0.1UF',
 PACK_TYPE='0402V',
 PART_NUMBER='A36096-030',
 LOCATION='C7E3',
 ROOM='PROC_SIDEBAND',
 SEC='1',
 CDS_LIB='dev_discrete',
 CDS_PART_NAME='CAP_A_0402V-0.1UF,16V,10%,X7R,A',
 VOLTAGE='16V',
 PRIM_FILE='./archive_libs/discrete/cap_a/chips/chips.prt';

PART_NAME
 C7E4 'CAP_A_0402V-0.1UF,16V,10%,X7R,A':
 ROOM='PROC_SIDEBAND';

SECTION_NUMBER 1
 '@BASEBOARD_FAB2_LIB.BASEBOARD_FAB2(SCH_1):PAGE95_I115@DEV_DISCRETE.CAP_A(CHIPS)':
 C_PATH='@baseboard_fab2_lib.baseboard_fab2(sch_1):page95_i115@dev_discrete.cap_~
a(chips)',
 P_PATH='@baseboard_fab2_lib.baseboard_fab2(sch_1):page95_i115@dev_discrete.cap_~
a(chips)',
 PATH='I115',
 DRAWING='@BASEBOARD_FAB2_LIB.BASEBOARD_FAB2(SCH_1):PAGE95',
 TOLERANCE='10%',
 SEC_TYPE='0402V',
 MATERIAL='X7R',
 BOM_COST='PROC_SIDEBAND',
 PHYS_PAGE='95',
 XY='(1125,3450)',
 ROT='0',
 VER='1',
 VALUE='0.1UF',
 PACK_TYPE='0402V',
 PART_NUMBER='A36096-030',
 LOCATION='C7E4',
 ROOM='PROC_SIDEBAND',
 SEC='1',
 CDS_LIB='dev_discrete',
 CDS_PART_NAME='CAP_A_0402V-0.1UF,16V,10%,X7R,A',
 VOLTAGE='16V',
 PRIM_FILE='./archive_libs/discrete/cap_a/chips/chips.prt';

PART_NAME
 C7E5 'CAP_A_0402V-0.1UF,16V,10%,X7R,A':
 ROOM='P12V_PWR_SWITCH';

SECTION_NUMBER 1
 '@BASEBOARD_FAB2_LIB.BASEBOARD_FAB2(SCH_1):PAGE198_I52@DEV_DISCRETE.CAP_A(CHIPS)':
 C_PATH='@baseboard_fab2_lib.baseboard_fab2(sch_1):page198_i52@dev_discrete.cap_~
a(chips)',
 P_PATH='@baseboard_fab2_lib.baseboard_fab2(sch_1):page198_i52@dev_discrete.cap_~
a(chips)',
 PATH='I52',
 DRAWING='@BASEBOARD_FAB2_LIB.BASEBOARD_FAB2(SCH_1):PAGE198',
 TOLERANCE='10%',
 SEC_TYPE='0402V',
 MATERIAL='X7R',
 BOM_COST='PWR_SWITCH',
 PHYS_PAGE='198',
 XY='(-4775,2250)',
 ROT='0',
 VER='1',
 VALUE='0.1UF',
 PACK_TYPE='0402V',
 PART_NUMBER='A36096-030',
 LOCATION='C7E5',
 ROOM='P12V_PWR_SWITCH',
 SEC='1',
 CDS_LIB='dev_discrete',
 CDS_PART_NAME='CAP_A_0402V-0.1UF,16V,10%,X7R,A',
 VOLTAGE='16V',
 PRIM_FILE='./archive_libs/discrete/cap_a/chips/chips.prt';

PART_NAME
 C7E6 'CAP_0805-10UF,16V,10%,X6S,C953A':
 ROOM='P12V_PWR_SWITCH';

SECTION_NUMBER 1
 '@BASEBOARD_FAB2_LIB.BASEBOARD_FAB2(SCH_1):PAGE198_I53@MSTR_DISCRETE.CAP(CHIPS)':
 C_PATH='@baseboard_fab2_lib.baseboard_fab2(sch_1):page198_i53@mstr_discrete.cap~
(chips)',
 P_PATH='@baseboard_fab2_lib.baseboard_fab2(sch_1):page198_i53@mstr_discrete.cap~
(chips)',
 PATH='I53',
 DRAWING='@BASEBOARD_FAB2_LIB.BASEBOARD_FAB2(SCH_1):PAGE198',
 TOLERANCE='10%',
 SEC_TYPE='0805',
 MATERIAL='X6S',
 PHYS_PAGE='198',
 XY='(-5100,2250)',
 ROT='0',
 VER='1',
 VALUE='10UF',
 PACK_TYPE='0805',
 PART_NUMBER='C95333-007',
 LOCATION='C7E6',
 ROOM='P12V_PWR_SWITCH',
 SEC='1',
 CDS_LIB='mstr_discrete',
 CDS_PART_NAME='CAP_0805-10UF,16V,10%,X6S,C953A',
 VOLTAGE='16V',
 PRIM_FILE='./archive_libs/mstr_discrete/cap/chips/chips.prt';

PART_NAME
 C7E8 'CAP_0805-10UF,16V,10%,X6S,C953A':
 ROOM='P12V_PWR_SWITCH';

SECTION_NUMBER 1
 '@BASEBOARD_FAB2_LIB.BASEBOARD_FAB2(SCH_1):PAGE198_I50@MSTR_DISCRETE.CAP(CHIPS)':
 C_PATH='@baseboard_fab2_lib.baseboard_fab2(sch_1):page198_i50@mstr_discrete.cap~
(chips)',
 P_PATH='@baseboard_fab2_lib.baseboard_fab2(sch_1):page198_i50@mstr_discrete.cap~
(chips)',
 PATH='I50',
 DRAWING='@BASEBOARD_FAB2_LIB.BASEBOARD_FAB2(SCH_1):PAGE198',
 TOLERANCE='10%',
 SEC_TYPE='0805',
 MATERIAL='X6S',
 PHYS_PAGE='198',
 XY='(-5125,1250)',
 ROT='0',
 VER='1',
 VALUE='10UF',
 PACK_TYPE='0805',
 PART_NUMBER='C95333-007',
 LOCATION='C7E8',
 ROOM='P12V_PWR_SWITCH',
 SEC='1',
 CDS_LIB='mstr_discrete',
 CDS_PART_NAME='CAP_0805-10UF,16V,10%,X6S,C953A',
 VOLTAGE='16V',
 PRIM_FILE='./archive_libs/mstr_discrete/cap/chips/chips.prt';

PART_NAME
 C7E9 'CAP_A_0402V-0.1UF,16V,10%,X7R,A':
 ROOM='P12V_PWR_SWITCH';

SECTION_NUMBER 1
 '@BASEBOARD_FAB2_LIB.BASEBOARD_FAB2(SCH_1):PAGE198_I49@DEV_DISCRETE.CAP_A(CHIPS)':
 C_PATH='@baseboard_fab2_lib.baseboard_fab2(sch_1):page198_i49@dev_discrete.cap_~
a(chips)',
 P_PATH='@baseboard_fab2_lib.baseboard_fab2(sch_1):page198_i49@dev_discrete.cap_~
a(chips)',
 PATH='I49',
 DRAWING='@BASEBOARD_FAB2_LIB.BASEBOARD_FAB2(SCH_1):PAGE198',
 TOLERANCE='10%',
 SEC_TYPE='0402V',
 MATERIAL='X7R',
 BOM_COST='PWR_SWITCH',
 PHYS_PAGE='198',
 XY='(-4675,1200)',
 ROT='0',
 VER='1',
 VALUE='0.1UF',
 PACK_TYPE='0402V',
 PART_NUMBER='A36096-030',
 LOCATION='C7E9',
 ROOM='P12V_PWR_SWITCH',
 SEC='1',
 CDS_LIB='dev_discrete',
 CDS_PART_NAME='CAP_A_0402V-0.1UF,16V,10%,X7R,A',
 VOLTAGE='16V',
 PRIM_FILE='./archive_libs/discrete/cap_a/chips/chips.prt';

PART_NAME
 C7E10 'CAP_0402LF-1000PF,50V,10%,X7R,A':
 ROOM='P5V_STBY_VR',
 REUSE_ID='17';

SECTION_NUMBER 1
 '@BASEBOARD_FAB2_LIB.BASEBOARD_FAB2(SCH_1):PAGE241_I14@MSTR_DISCRETE.CAP(CHIPS)':
 C_PATH='@baseboard_fab2_lib.baseboard_fab2(sch_1):page241_i14@mstr_discrete.cap~
(chips)',
 P_PATH='@baseboard_fab2_lib.baseboard_fab2(sch_1):page241_i14@mstr_discrete.cap~
(chips)',
 PATH='I14',
 DRAWING='@BASEBOARD_FAB2_LIB.BASEBOARD_FAB2(SCH_1):PAGE241',
 TOLERANCE='10%',
 SEC_TYPE='0402LF',
 MATERIAL='X7R',
 BOM_COST='P5V_STBY_VR',
 PHYS_PAGE='241',
 REUSE_ID='17',
 XY='(1500,4400)',
 ROT='0',
 VER='1',
 VALUE='1000PF',
 PACK_TYPE='0402LF',
 PART_NUMBER='A36096-046',
 LOCATION='C7E10',
 ROOM='P5V_STBY_VR',
 SEC='1',
 CDS_LIB='mstr_discrete',
 CDS_PART_NAME='CAP_0402LF-1000PF,50V,10%,X7R,A',
 VOLTAGE='50V',
 PRIM_FILE='./archive_libs/mstr_discrete/cap/chips/chips.prt';

PART_NAME
 C7E11 'CAP_1206LF-22UF,16V,10%,X6S,D3A':
 ROOM='P5V_STBY_VR';

SECTION_NUMBER 1
 '@BASEBOARD_FAB2_LIB.BASEBOARD_FAB2(SCH_1):PAGE241_I39@MSTR_DISCRETE.CAP(CHIPS)':
 C_PATH='@baseboard_fab2_lib.baseboard_fab2(sch_1):page241_i39@mstr_discrete.cap~
(chips)',
 P_PATH='@baseboard_fab2_lib.baseboard_fab2(sch_1):page241_i39@mstr_discrete.cap~
(chips)',
 PATH='I39',
 DRAWING='@BASEBOARD_FAB2_LIB.BASEBOARD_FAB2(SCH_1):PAGE241',
 TOLERANCE='10%',
 SEC_TYPE='1206LF',
 MATERIAL='X6S',
 BOM_COST='P5V_STBY_VR',
 PHYS_PAGE='241',
 XY='(-1750,4275)',
 ROT='0',
 VER='1',
 VALUE='22UF',
 PACK_TYPE='1206LF',
 PART_NUMBER='D38464-005',
 LOCATION='C7E11',
 ROOM='P5V_STBY_VR',
 SEC='1',
 CDS_LIB='mstr_discrete',
 CDS_PART_NAME='CAP_1206LF-22UF,16V,10%,X6S,D3A',
 VOLTAGE='16V',
 PRIM_FILE='./archive_libs/mstr_discrete/cap/chips/chips.prt';

PART_NAME
 C7E12 'SC22U16V5MX-4-GP_SMD-BCG5-SC22A':;

SECTION_NUMBER 1
 '@BASEBOARD_FAB2_LIB.BASEBOARD_FAB2(SCH_1):PAGE241_I98@W_HDL.SC22U16V5MX-4-GP(CHIPS)':
 C_PATH='@baseboard_fab2_lib.baseboard_fab2(sch_1):page241_i98@w_hdl.\sc22u16v5m~
x-4-gp\(chips)',
 P_PATH='@baseboard_fab2_lib.baseboard_fab2(sch_1):page241_i98@w_hdl.\sc22u16v5m~
x-4-gp\(chips)',
 PATH='I98',
 DRAWING='@BASEBOARD_FAB2_LIB.BASEBOARD_FAB2(SCH_1):PAGE241',
 TYPE='X6S',
 PACK_SIZE='0805',
 RATED='16V',
 ATTRIBUTE='22UF',
 TOLERANCE='20%',
 SEC_TYPE='SMD-BCG5',
 PHYS_PAGE='241',
 XY='(-3050,4325)',
 ROT='0',
 VER='1',
 VALUE='SC22U16V5MX-4-GP',
 PACK_TYPE='SMD-BCG5',
 PART_NUMBER='078.22611.0811',
 LOCATION='C7E12',
 SEC='1',
 CDS_LIB='w_hdl',
 CDS_PART_NAME='SC22U16V5MX-4-GP_SMD-BCG5-SC22A',
 PRIM_FILE='C:/<user>/w_hdl/sc22u16v5mx#2d4#2dgp/chips/chips.prt';

PART_NAME
 C7E13 'SC22U16V5MX-4-GP_SMD-BCG5-SC22A':;

SECTION_NUMBER 1
 '@BASEBOARD_FAB2_LIB.BASEBOARD_FAB2(SCH_1):PAGE241_I92@W_HDL.SC22U16V5MX-4-GP(CHIPS)':
 C_PATH='@baseboard_fab2_lib.baseboard_fab2(sch_1):page241_i92@w_hdl.\sc22u16v5m~
x-4-gp\(chips)',
 P_PATH='@baseboard_fab2_lib.baseboard_fab2(sch_1):page241_i92@w_hdl.\sc22u16v5m~
x-4-gp\(chips)',
 PATH='I92',
 DRAWING='@BASEBOARD_FAB2_LIB.BASEBOARD_FAB2(SCH_1):PAGE241',
 TYPE='X6S',
 PACK_SIZE='0805',
 RATED='16V',
 ATTRIBUTE='22UF',
 TOLERANCE='20%',
 SEC_TYPE='SMD-BCG5',
 PHYS_PAGE='241',
 XY='(-2400,4325)',
 ROT='0',
 VER='1',
 VALUE='SC22U16V5MX-4-GP',
 PACK_TYPE='SMD-BCG5',
 PART_NUMBER='078.22611.0811',
 LOCATION='C7E13',
 SEC='1',
 CDS_LIB='w_hdl',
 CDS_PART_NAME='SC22U16V5MX-4-GP_SMD-BCG5-SC22A',
 PRIM_FILE='C:/<user>/w_hdl/sc22u16v5mx#2d4#2dgp/chips/chips.prt';

PART_NAME
 C7E14 'CAP_0402-1.0UF,16V,10%,X6S,D97A':
 ROOM='P5V_STBY_VR',
 REUSE_ID='1';

SECTION_NUMBER 1
 '@BASEBOARD_FAB2_LIB.BASEBOARD_FAB2(SCH_1):PAGE241_I30@MSTR_DISCRETE.CAP(CHIPS)':
 C_PATH='@baseboard_fab2_lib.baseboard_fab2(sch_1):page241_i30@mstr_discrete.cap~
(chips)',
 P_PATH='@baseboard_fab2_lib.baseboard_fab2(sch_1):page241_i30@mstr_discrete.cap~
(chips)',
 PATH='I30',
 DRAWING='@BASEBOARD_FAB2_LIB.BASEBOARD_FAB2(SCH_1):PAGE241',
 FIN='VR_1P2',
 TOLERANCE='10%',
 SEC_TYPE='0402',
 MATERIAL='X6S',
 BOM_COST='P5V_STBY_VR',
 PHYS_PAGE='241',
 REUSE_ID='1',
 XY='(-1400,3850)',
 ROT='0',
 VER='1',
 VALUE='1.0UF',
 PACK_TYPE='0402',
 PART_NUMBER='D97712-011',
 LOCATION='C7E14',
 ROOM='P5V_STBY_VR',
 SEC='1',
 CDS_LIB='mstr_discrete',
 CDS_PART_NAME='CAP_0402-1.0UF,16V,10%,X6S,D97A',
 VOLTAGE='16V',
 PRIM_FILE='./archive_libs/mstr_discrete/cap/chips/chips.prt';

PART_NAME
 C7F1 'CAP_A_0402V-0.01UF,25V,10%,X7RA':
 ROOM='SB_SPI',
 NO_XNET_CONNECTION='1';

SECTION_NUMBER 1
 '@BASEBOARD_FAB2_LIB.BASEBOARD_FAB2(SCH_1):PAGE153_I131@DEV_DISCRETE.CAP_A(CHIPS)':
 C_PATH='@baseboard_fab2_lib.baseboard_fab2(sch_1):page153_i131@dev_discrete.cap~
_a(chips)',
 P_PATH='@baseboard_fab2_lib.baseboard_fab2(sch_1):page153_i131@dev_discrete.cap~
_a(chips)',
 PATH='I131',
 DRAWING='@BASEBOARD_FAB2_LIB.BASEBOARD_FAB2(SCH_1):PAGE153',
 TOLERANCE='10%',
 SEC_TYPE='0402V',
 MATERIAL='X7R',
 BOM_COST='MIO_BIOS_MEM',
 NO_XNET_CONNECTION='1',
 PHYS_PAGE='153',
 XY='(-3625,4500)',
 ROT='0',
 VER='1',
 VALUE='0.01UF',
 PACK_TYPE='0402V',
 PART_NUMBER='A36096-045',
 LOCATION='C7F1',
 ROOM='SB_SPI',
 SEC='1',
 CDS_LIB='dev_discrete',
 CDS_PART_NAME='CAP_A_0402V-0.01UF,25V,10%,X7RA',
 VOLTAGE='25V',
 PRIM_FILE='./archive_libs/discrete/cap_a/chips/chips.prt';

PART_NAME
 C7F2 'CAP_A_0402V-1.0UF,6.3V,10%,X6SA':
 ROOM='SB_SPI',
 NO_XNET_CONNECTION='1';

SECTION_NUMBER 1
 '@BASEBOARD_FAB2_LIB.BASEBOARD_FAB2(SCH_1):PAGE153_I130@DEV_DISCRETE.CAP_A(CHIPS)':
 C_PATH='@baseboard_fab2_lib.baseboard_fab2(sch_1):page153_i130@dev_discrete.cap~
_a(chips)',
 P_PATH='@baseboard_fab2_lib.baseboard_fab2(sch_1):page153_i130@dev_discrete.cap~
_a(chips)',
 PATH='I130',
 DRAWING='@BASEBOARD_FAB2_LIB.BASEBOARD_FAB2(SCH_1):PAGE153',
 TOLERANCE='10%',
 SEC_TYPE='0402V',
 MATERIAL='X6S',
 BOM_COST='MIO_BIOS_MEM',
 NO_XNET_CONNECTION='1',
 PHYS_PAGE='153',
 XY='(-3925,4500)',
 ROT='0',
 VER='1',
 VALUE='1.0UF',
 PACK_TYPE='0402V',
 PART_NUMBER='D97712-004',
 LOCATION='C7F2',
 ROOM='SB_SPI',
 SEC='1',
 CDS_LIB='dev_discrete',
 CDS_PART_NAME='CAP_A_0402V-1.0UF,6.3V,10%,X6SA',
 VOLTAGE='6.3V',
 PRIM_FILE='./archive_libs/discrete/cap_a/chips/chips.prt';

PART_NAME
 C7F3 'CAP_0402LF-3300PF,50V,10%,EMPTA':
 ROOM='PVPP_KLM_VR',
 REUSE_ID='26';

SECTION_NUMBER 1
 '@BASEBOARD_FAB2_LIB.BASEBOARD_FAB2(SCH_1):PAGE231_I175@MSTR_DISCRETE.CAP(CHIPS)':
 C_PATH='@baseboard_fab2_lib.baseboard_fab2(sch_1):page231_i175@mstr_discrete.ca~
p(chips)',
 P_PATH='@baseboard_fab2_lib.baseboard_fab2(sch_1):page231_i175@mstr_discrete.ca~
p(chips)',
 PATH='I175',
 DRAWING='@BASEBOARD_FAB2_LIB.BASEBOARD_FAB2(SCH_1):PAGE231',
 TOLERANCE='10%',
 MATERIAL='EMPTY',
 BOM_COST='PVPP_KLM_VR',
 PHYS_PAGE='231',
 REUSE_ID='26',
 XY='(-2300,3950)',
 ROT='0',
 VER='1',
 VALUE='3300PF',
 PACK_TYPE='0402LF',
 PART_NUMBER='A36096-091',
 LOCATION='C7F3',
 ROOM='PVPP_KLM_VR',
 CDS_LIB='mstr_discrete',
 CDS_PART_NAME='CAP_0402LF-3300PF,50V,10%,EMPTA',
 VOLTAGE='50V',
 PRIM_FILE='./archive_libs/mstr_discrete/cap/chips/chips.prt';

PART_NAME
 C7F4 'CAP_0603LF-0.1UF,25V,10%,X7R,6A':
 ROOM='PVPP_KLM_VR',
 REUSE_ID='27';

SECTION_NUMBER 1
 '@BASEBOARD_FAB2_LIB.BASEBOARD_FAB2(SCH_1):PAGE231_I159@MSTR_DISCRETE.CAP(CHIPS)':
 C_PATH='@baseboard_fab2_lib.baseboard_fab2(sch_1):page231_i159@mstr_discrete.ca~
p(chips)',
 P_PATH='@baseboard_fab2_lib.baseboard_fab2(sch_1):page231_i159@mstr_discrete.ca~
p(chips)',
 PATH='I159',
 DRAWING='@BASEBOARD_FAB2_LIB.BASEBOARD_FAB2(SCH_1):PAGE231',
 SPOF='TRUE',
 TOLERANCE='10%',
 MATERIAL='X7R',
 BOM_COST='PVPP_KLM_VR',
 PHYS_PAGE='231',
 REUSE_ID='27',
 XY='(-3025,4450)',
 ROT='2',
 VER='2',
 VALUE='0.1UF',
 PACK_TYPE='0603LF',
 PART_NUMBER='602433-020',
 LOCATION='C7F4',
 ROOM='PVPP_KLM_VR',
 CDS_LIB='mstr_discrete',
 CDS_PART_NAME='CAP_0603LF-0.1UF,25V,10%,X7R,6A',
 VOLTAGE='25V',
 PRIM_FILE='./archive_libs/mstr_discrete/cap/chips/chips.prt';

PART_NAME
 C7F5 'CAP_0805-10UF,16V,10%,X6S,C953A':
 REUSE_ID='17';

SECTION_NUMBER 1
 '@BASEBOARD_FAB2_LIB.BASEBOARD_FAB2(SCH_1):PAGE231_I209@MSTR_DISCRETE.CAP(CHIPS)':
 C_PATH='@baseboard_fab2_lib.baseboard_fab2(sch_1):page231_i209@mstr_discrete.ca~
p(chips)',
 P_PATH='@baseboard_fab2_lib.baseboard_fab2(sch_1):page231_i209@mstr_discrete.ca~
p(chips)',
 PATH='I209',
 DRAWING='@BASEBOARD_FAB2_LIB.BASEBOARD_FAB2(SCH_1):PAGE231',
 TOLERANCE='10%',
 SEC_TYPE='0805',
 MATERIAL='X6S',
 PHYS_PAGE='231',
 XY='(-6225,4375)',
 ROT='0',
 VER='1',
 VALUE='10UF',
 PACK_TYPE='0805',
 PART_NUMBER='C95333-007',
 LOCATION='C7F5',
 SEC='1',
 CDS_LIB='mstr_discrete',
 CDS_PART_NAME='CAP_0805-10UF,16V,10%,X6S,C953A',
 VOLTAGE='16V',
 PRIM_FILE='./archive_libs/mstr_discrete/cap/chips/chips.prt',
 REUSE_ID='17';

PART_NAME
 C7F6 'CAP_A_0402V-0.1UF,16V,10%,X7R,A':;

SECTION_NUMBER 1
 '@BASEBOARD_FAB2_LIB.BASEBOARD_FAB2(SCH_1):PAGE231_I205@DEV_DISCRETE.CAP_A(CHIPS)':
 C_PATH='@baseboard_fab2_lib.baseboard_fab2(sch_1):page231_i205@dev_discrete.cap~
_a(chips)',
 P_PATH='@baseboard_fab2_lib.baseboard_fab2(sch_1):page231_i205@dev_discrete.cap~
_a(chips)',
 PATH='I205',
 DRAWING='@BASEBOARD_FAB2_LIB.BASEBOARD_FAB2(SCH_1):PAGE231',
 TOLERANCE='10%',
 SEC_TYPE='0402V',
 MATERIAL='X7R',
 PHYS_PAGE='231',
 XY='(-4775,3750)',
 ROT='0',
 VER='1',
 VALUE='0.1UF',
 PACK_TYPE='0402V',
 PART_NUMBER='A36096-030',
 LOCATION='C7F6',
 SEC='1',
 CDS_LIB='dev_discrete',
 CDS_PART_NAME='CAP_A_0402V-0.1UF,16V,10%,X7R,A',
 VOLTAGE='16V',
 PRIM_FILE='./archive_libs/discrete/cap_a/chips/chips.prt';

PART_NAME
 C7F7 'SC22U16V5MX-4-GP_SMD-BCG5-SC22A':;

SECTION_NUMBER 1
 '@BASEBOARD_FAB2_LIB.BASEBOARD_FAB2(SCH_1):PAGE231_I226@W_HDL.SC22U16V5MX-4-GP(CHIPS)':
 C_PATH='@baseboard_fab2_lib.baseboard_fab2(sch_1):page231_i226@w_hdl.\sc22u16v5~
mx-4-gp\(chips)',
 P_PATH='@baseboard_fab2_lib.baseboard_fab2(sch_1):page231_i226@w_hdl.\sc22u16v5~
mx-4-gp\(chips)',
 PATH='I226',
 DRAWING='@BASEBOARD_FAB2_LIB.BASEBOARD_FAB2(SCH_1):PAGE231',
 TYPE='X6S',
 PACK_SIZE='0805',
 RATED='16V',
 ATTRIBUTE='22UF',
 TOLERANCE='20%',
 SEC_TYPE='SMD-BCG5',
 PHYS_PAGE='231',
 XY='(-6950,4325)',
 ROT='0',
 VER='1',
 VALUE='SC22U16V5MX-4-GP',
 PACK_TYPE='SMD-BCG5',
 PART_NUMBER='078.22611.0811',
 LOCATION='C7F7',
 SEC='1',
 CDS_LIB='w_hdl',
 CDS_PART_NAME='SC22U16V5MX-4-GP_SMD-BCG5-SC22A',
 PRIM_FILE='C:/<user>/w_hdl/sc22u16v5mx#2d4#2dgp/chips/chips.prt';

PART_NAME
 C7F8 'CAP_0402LF-1000PF,50V,10%,EMPTA':
 ROOM='PVPP_KLM_VR',
 REUSE_ID='1';

SECTION_NUMBER 1
 '@BASEBOARD_FAB2_LIB.BASEBOARD_FAB2(SCH_1):PAGE231_I140@MSTR_DISCRETE.CAP(CHIPS)':
 C_PATH='@baseboard_fab2_lib.baseboard_fab2(sch_1):page231_i140@mstr_discrete.ca~
p(chips)',
 P_PATH='@baseboard_fab2_lib.baseboard_fab2(sch_1):page231_i140@mstr_discrete.ca~
p(chips)',
 PATH='I140',
 DRAWING='@BASEBOARD_FAB2_LIB.BASEBOARD_FAB2(SCH_1):PAGE231',
 FIN='VR_1P2',
 TOLERANCE='10%',
 MATERIAL='EMPTY',
 BOM_COST='PVPP_KLM_VR',
 PHYS_PAGE='231',
 REUSE_ID='1',
 XY='(-6175,2650)',
 ROT='2',
 VER='1',
 VALUE='1000PF',
 PACK_TYPE='0402LF',
 PART_NUMBER='A36096-046',
 LOCATION='C7F8',
 ROOM='PVPP_KLM_VR',
 CDS_LIB='mstr_discrete',
 CDS_PART_NAME='CAP_0402LF-1000PF,50V,10%,EMPTA',
 VOLTAGE='50V',
 PRIM_FILE='./archive_libs/mstr_discrete/cap/chips/chips.prt';

PART_NAME
 C7F9 'CAP_0402LF-100.0PF,50V,5%,COG,A':
 ROOM='PVPP_KLM_VR',
 REUSE_ID='27';

SECTION_NUMBER 1
 '@BASEBOARD_FAB2_LIB.BASEBOARD_FAB2(SCH_1):PAGE231_I199@MSTR_DISCRETE.CAP(CHIPS)':
 C_PATH='@baseboard_fab2_lib.baseboard_fab2(sch_1):page231_i199@mstr_discrete.ca~
p(chips)',
 P_PATH='@baseboard_fab2_lib.baseboard_fab2(sch_1):page231_i199@mstr_discrete.ca~
p(chips)',
 PATH='I199',
 DRAWING='@BASEBOARD_FAB2_LIB.BASEBOARD_FAB2(SCH_1):PAGE231',
 TOLERANCE='5%',
 SEC_TYPE='0402LF',
 MATERIAL='COG',
 BOM_COST='PVPP_KLM_VR',
 PHYS_PAGE='231',
 REUSE_ID='27',
 XY='(-1875,3075)',
 ROT='2',
 VER='2',
 VALUE='100.0PF',
 PACK_TYPE='0402LF',
 PART_NUMBER='A36095-026',
 LOCATION='C7F9',
 ROOM='PVPP_KLM_VR',
 SEC='1',
 CDS_LIB='mstr_discrete',
 CDS_PART_NAME='CAP_0402LF-100.0PF,50V,5%,COG,A',
 VOLTAGE='50V',
 PRIM_FILE='./archive_libs/mstr_discrete/cap/chips/chips.prt';

PART_NAME
 C7F10 'CAP_0402-0.027UF,16V,10%,X7R,AA':
 ROOM='PVPP_KLM_VR',
 REUSE_ID='26';

SECTION_NUMBER 1
 '@BASEBOARD_FAB2_LIB.BASEBOARD_FAB2(SCH_1):PAGE231_I194@MSTR_DISCRETE.CAP(CHIPS)':
 C_PATH='@baseboard_fab2_lib.baseboard_fab2(sch_1):page231_i194@mstr_discrete.ca~
p(chips)',
 P_PATH='@baseboard_fab2_lib.baseboard_fab2(sch_1):page231_i194@mstr_discrete.ca~
p(chips)',
 PATH='I194',
 DRAWING='@BASEBOARD_FAB2_LIB.BASEBOARD_FAB2(SCH_1):PAGE231',
 TOLERANCE='10%',
 SEC_TYPE='0402',
 MATERIAL='X7R',
 BOM_COST='PVPP_KLM_VR',
 PHYS_PAGE='231',
 REUSE_ID='26',
 XY='(-4725,2425)',
 ROT='0',
 VER='1',
 VALUE='0.027UF',
 PACK_TYPE='0402',
 PART_NUMBER='A36096-129',
 LOCATION='C7F10',
 ROOM='PVPP_KLM_VR',
 SEC='1',
 CDS_LIB='mstr_discrete',
 CDS_PART_NAME='CAP_0402-0.027UF,16V,10%,X7R,AA',
 VOLTAGE='16V',
 PRIM_FILE='./archive_libs/mstr_discrete/cap/chips/chips.prt';

PART_NAME
 C7F11 'CAP_0402LF-1000PF,50V,10%,X7R,A':
 ROOM='PVPP_KLM_VR',
 REUSE_ID='17';

SECTION_NUMBER 1
 '@BASEBOARD_FAB2_LIB.BASEBOARD_FAB2(SCH_1):PAGE231_I142@MSTR_DISCRETE.CAP(CHIPS)':
 C_PATH='@baseboard_fab2_lib.baseboard_fab2(sch_1):page231_i142@mstr_discrete.ca~
p(chips)',
 P_PATH='@baseboard_fab2_lib.baseboard_fab2(sch_1):page231_i142@mstr_discrete.ca~
p(chips)',
 PATH='I142',
 DRAWING='@BASEBOARD_FAB2_LIB.BASEBOARD_FAB2(SCH_1):PAGE231',
 TOLERANCE='10%',
 MATERIAL='X7R',
 BOM_COST='PVPP_KLM_VR',
 PHYS_PAGE='231',
 REUSE_ID='17',
 XY='(-3700,1050)',
 ROT='0',
 VER='1',
 VALUE='1000PF',
 PACK_TYPE='0402LF',
 PART_NUMBER='A36096-046',
 LOCATION='C7F11',
 ROOM='PVPP_KLM_VR',
 CDS_LIB='mstr_discrete',
 CDS_PART_NAME='CAP_0402LF-1000PF,50V,10%,X7R,A',
 VOLTAGE='50V',
 PRIM_FILE='./archive_libs/mstr_discrete/cap/chips/chips.prt';

PART_NAME
 C7F12 'CAP_0402LF-2200PF,50V,10%,X7R,A':
 ROOM='PVPP_KLM_VR',
 REUSE_ID='27';

SECTION_NUMBER 1
 '@BASEBOARD_FAB2_LIB.BASEBOARD_FAB2(SCH_1):PAGE231_I200@MSTR_DISCRETE.CAP(CHIPS)':
 C_PATH='@baseboard_fab2_lib.baseboard_fab2(sch_1):page231_i200@mstr_discrete.ca~
p(chips)',
 P_PATH='@baseboard_fab2_lib.baseboard_fab2(sch_1):page231_i200@mstr_discrete.ca~
p(chips)',
 PATH='I200',
 DRAWING='@BASEBOARD_FAB2_LIB.BASEBOARD_FAB2(SCH_1):PAGE231',
 TOLERANCE='10%',
 SEC_TYPE='0402LF',
 MATERIAL='X7R',
 BOM_COST='PVPP_KLM_VR',
 PHYS_PAGE='231',
 REUSE_ID='27',
 XY='(-2500,2700)',
 ROT='2',
 VER='2',
 VALUE='2200PF',
 PACK_TYPE='0402LF',
 PART_NUMBER='A36096-075',
 LOCATION='C7F12',
 ROOM='PVPP_KLM_VR',
 SEC='1',
 CDS_LIB='mstr_discrete',
 CDS_PART_NAME='CAP_0402LF-2200PF,50V,10%,X7R,A',
 VOLTAGE='50V',
 PRIM_FILE='./archive_libs/mstr_discrete/cap/chips/chips.prt';

PART_NAME
 C7F13 'CAP_0402LF-2200PF,50V,10%,X7R,A':
 ROOM='PVPP_KLM_VR',
 REUSE_ID='26';

SECTION_NUMBER 1
 '@BASEBOARD_FAB2_LIB.BASEBOARD_FAB2(SCH_1):PAGE231_I219@MSTR_DISCRETE.CAP(CHIPS)':
 C_PATH='@baseboard_fab2_lib.baseboard_fab2(sch_1):page231_i219@mstr_discrete.ca~
p(chips)',
 P_PATH='@baseboard_fab2_lib.baseboard_fab2(sch_1):page231_i219@mstr_discrete.ca~
p(chips)',
 PATH='I219',
 DRAWING='@BASEBOARD_FAB2_LIB.BASEBOARD_FAB2(SCH_1):PAGE231',
 SPOF='TRUE',
 TOLERANCE='10%',
 SEC_TYPE='0402LF',
 MATERIAL='X7R',
 BOM_COST='PVPP_KLM_VR',
 PHYS_PAGE='231',
 REUSE_ID='26',
 XY='(-675,2000)',
 ROT='0',
 VER='1',
 VALUE='2200PF',
 PACK_TYPE='0402LF',
 PART_NUMBER='A36096-075',
 LOCATION='C7F13',
 ROOM='PVPP_KLM_VR',
 SEC='1',
 CDS_LIB='mstr_discrete',
 CDS_PART_NAME='CAP_0402LF-2200PF,50V,10%,X7R,A',
 VOLTAGE='50V',
 PRIM_FILE='./archive_libs/mstr_discrete/cap/chips/chips.prt';

PART_NAME
 C7F14 'CAP_0402LF-1000PF,50V,10%,X7R,A':
 ROOM='VDDQ_ABC_PWR_VR';

SECTION_NUMBER 1
 '@BASEBOARD_FAB2_LIB.BASEBOARD_FAB2(SCH_1):PAGE215_I44@MSTR_DISCRETE.CAP(CHIPS)':
 C_PATH='@baseboard_fab2_lib.baseboard_fab2(sch_1):page215_i44@mstr_discrete.cap~
(chips)',
 P_PATH='@baseboard_fab2_lib.baseboard_fab2(sch_1):page215_i44@mstr_discrete.cap~
(chips)',
 PATH='I44',
 DRAWING='@BASEBOARD_FAB2_LIB.BASEBOARD_FAB2(SCH_1):PAGE215',
 TOLERANCE='10%',
 SEC_TYPE='0402LF',
 MATERIAL='X7R',
 PHYS_PAGE='215',
 XY='(3800,1050)',
 ROT='0',
 VER='1',
 VALUE='1000PF',
 PACK_TYPE='0402LF',
 PART_NUMBER='A36096-046',
 LOCATION='C7F14',
 ROOM='VDDQ_ABC_PWR_VR',
 SEC='1',
 CDS_LIB='mstr_discrete',
 CDS_PART_NAME='CAP_0402LF-1000PF,50V,10%,X7R,A',
 VOLTAGE='50V',
 PRIM_FILE='./archive_libs/mstr_discrete/cap/chips/chips.prt';

PART_NAME
 C7F15 'CAP_A_0402V-0.1UF,16V,10%,X7R,A':
 ROOM='VDDQ_ABC_PWR_VR';

SECTION_NUMBER 1
 '@BASEBOARD_FAB2_LIB.BASEBOARD_FAB2(SCH_1):PAGE215_I38@DEV_DISCRETE.CAP_A(CHIPS)':
 C_PATH='@baseboard_fab2_lib.baseboard_fab2(sch_1):page215_i38@dev_discrete.cap_~
a(chips)',
 P_PATH='@baseboard_fab2_lib.baseboard_fab2(sch_1):page215_i38@dev_discrete.cap_~
a(chips)',
 PATH='I38',
 DRAWING='@BASEBOARD_FAB2_LIB.BASEBOARD_FAB2(SCH_1):PAGE215',
 TOLERANCE='10%',
 SEC_TYPE='0402V',
 MATERIAL='X7R',
 PHYS_PAGE='215',
 XY='(3150,200)',
 ROT='0',
 VER='1',
 VALUE='0.1UF',
 PACK_TYPE='0402V',
 PART_NUMBER='A36096-030',
 LOCATION='C7F15',
 ROOM='VDDQ_ABC_PWR_VR',
 SEC='1',
 CDS_LIB='dev_discrete',
 CDS_PART_NAME='CAP_A_0402V-0.1UF,16V,10%,X7R,A',
 VOLTAGE='16V',
 PRIM_FILE='./archive_libs/discrete/cap_a/chips/chips.prt';

PART_NAME
 C7F16 'CAP_A_0402V-1.0UF,6.3V,10%,X6SA':
 ROOM='VDDQ_ABC_PWR_VR';

SECTION_NUMBER 1
 '@BASEBOARD_FAB2_LIB.BASEBOARD_FAB2(SCH_1):PAGE215_I40@DEV_DISCRETE.CAP_A(CHIPS)':
 C_PATH='@baseboard_fab2_lib.baseboard_fab2(sch_1):page215_i40@dev_discrete.cap_~
a(chips)',
 P_PATH='@baseboard_fab2_lib.baseboard_fab2(sch_1):page215_i40@dev_discrete.cap_~
a(chips)',
 PATH='I40',
 DRAWING='@BASEBOARD_FAB2_LIB.BASEBOARD_FAB2(SCH_1):PAGE215',
 TOLERANCE='10%',
 SEC_TYPE='0402V',
 MATERIAL='X6S',
 PHYS_PAGE='215',
 XY='(3550,200)',
 ROT='0',
 VER='1',
 VALUE='1.0UF',
 PACK_TYPE='0402V',
 PART_NUMBER='D97712-004',
 LOCATION='C7F16',
 ROOM='VDDQ_ABC_PWR_VR',
 SEC='1',
 CDS_LIB='dev_discrete',
 CDS_PART_NAME='CAP_A_0402V-1.0UF,6.3V,10%,X6SA',
 VOLTAGE='6.3V',
 PRIM_FILE='./archive_libs/discrete/cap_a/chips/chips.prt';

PART_NAME
 C7F17 'CAP_A_0402V-0.1UF,16V,10%,X7R,A':
 ROOM='VDDQ_ABC_PWR_VR';

SECTION_NUMBER 1
 '@BASEBOARD_FAB2_LIB.BASEBOARD_FAB2(SCH_1):PAGE215_I34@DEV_DISCRETE.CAP_A(CHIPS)':
 C_PATH='@baseboard_fab2_lib.baseboard_fab2(sch_1):page215_i34@dev_discrete.cap_~
a(chips)',
 P_PATH='@baseboard_fab2_lib.baseboard_fab2(sch_1):page215_i34@dev_discrete.cap_~
a(chips)',
 PATH='I34',
 DRAWING='@BASEBOARD_FAB2_LIB.BASEBOARD_FAB2(SCH_1):PAGE215',
 TOLERANCE='10%',
 SEC_TYPE='0402V',
 MATERIAL='X7R',
 PHYS_PAGE='215',
 XY='(1975,2900)',
 ROT='0',
 VER='1',
 VALUE='0.1UF',
 PACK_TYPE='0402V',
 PART_NUMBER='A36096-030',
 LOCATION='C7F17',
 ROOM='VDDQ_ABC_PWR_VR',
 SEC='1',
 CDS_LIB='dev_discrete',
 CDS_PART_NAME='CAP_A_0402V-0.1UF,16V,10%,X7R,A',
 VOLTAGE='16V',
 PRIM_FILE='./archive_libs/discrete/cap_a/chips/chips.prt';

PART_NAME
 C7F18 'CAP_A_0402V-1.0UF,6.3V,10%,X6SA':
 ROOM='VDDQ_ABC_PWR_VR';

SECTION_NUMBER 1
 '@BASEBOARD_FAB2_LIB.BASEBOARD_FAB2(SCH_1):PAGE215_I35@DEV_DISCRETE.CAP_A(CHIPS)':
 C_PATH='@baseboard_fab2_lib.baseboard_fab2(sch_1):page215_i35@dev_discrete.cap_~
a(chips)',
 P_PATH='@baseboard_fab2_lib.baseboard_fab2(sch_1):page215_i35@dev_discrete.cap_~
a(chips)',
 PATH='I35',
 DRAWING='@BASEBOARD_FAB2_LIB.BASEBOARD_FAB2(SCH_1):PAGE215',
 TOLERANCE='10%',
 SEC_TYPE='0402V',
 MATERIAL='X6S',
 PHYS_PAGE='215',
 XY='(2375,2900)',
 ROT='0',
 VER='1',
 VALUE='1.0UF',
 PACK_TYPE='0402V',
 PART_NUMBER='D97712-004',
 LOCATION='C7F18',
 ROOM='VDDQ_ABC_PWR_VR',
 SEC='1',
 CDS_LIB='dev_discrete',
 CDS_PART_NAME='CAP_A_0402V-1.0UF,6.3V,10%,X6SA',
 VOLTAGE='6.3V',
 PRIM_FILE='./archive_libs/discrete/cap_a/chips/chips.prt';

PART_NAME
 C7G2 'CAPP_2626-270UF,16V,20%,OSCON,A':
 ROOM='VDDQ_ABC_PWR_VR';

SECTION_NUMBER 1
 '@BASEBOARD_FAB2_LIB.BASEBOARD_FAB2(SCH_1):PAGE217_I175@MSTR_DISCRETE.CAPP(CHIPS)':
 C_PATH='@baseboard_fab2_lib.baseboard_fab2(sch_1):page217_i175@mstr_discrete.ca~
pp(chips)',
 P_PATH='@baseboard_fab2_lib.baseboard_fab2(sch_1):page217_i175@mstr_discrete.ca~
pp(chips)',
 PATH='I175',
 DRAWING='@BASEBOARD_FAB2_LIB.BASEBOARD_FAB2(SCH_1):PAGE217',
 TOLERANCE='20%',
 SEC_TYPE='2626',
 MATERIAL='OSCON',
 PHYS_PAGE='217',
 XY='(200,700)',
 ROT='0',
 VER='1',
 VALUE='270UF',
 PACK_TYPE='2626',
 PART_NUMBER='A31228-047',
 LOCATION='C7G2',
 ROOM='VDDQ_ABC_PWR_VR',
 SEC='1',
 CDS_LIB='mstr_discrete',
 CDS_PART_NAME='CAPP_2626-270UF,16V,20%,OSCON,A',
 VOLTAGE='16V',
 PRIM_FILE='./archive_libs/mstr_discrete/capp/chips/chips.prt';

PART_NAME
 C7G3 'CAP_0402LF-220PF,50V,10%,X7R,AA':
 ROOM='VDDQ_ABC_PWR_VR';

SECTION_NUMBER 1
 '@BASEBOARD_FAB2_LIB.BASEBOARD_FAB2(SCH_1):PAGE215_I22@MSTR_DISCRETE.CAP(CHIPS)':
 C_PATH='@baseboard_fab2_lib.baseboard_fab2(sch_1):page215_i22@mstr_discrete.cap~
(chips)',
 P_PATH='@baseboard_fab2_lib.baseboard_fab2(sch_1):page215_i22@mstr_discrete.cap~
(chips)',
 PATH='I22',
 DRAWING='@BASEBOARD_FAB2_LIB.BASEBOARD_FAB2(SCH_1):PAGE215',
 TOLERANCE='10%',
 SEC_TYPE='0402LF',
 MATERIAL='X7R',
 PHYS_PAGE='215',
 XY='(875,550)',
 ROT='2',
 VER='1',
 VALUE='220PF',
 PACK_TYPE='0402LF',
 PART_NUMBER='A36096-050',
 LOCATION='C7G3',
 ROOM='VDDQ_ABC_PWR_VR',
 SEC='1',
 CDS_LIB='mstr_discrete',
 CDS_PART_NAME='CAP_0402LF-220PF,50V,10%,X7R,AA',
 VOLTAGE='50V',
 PRIM_FILE='./archive_libs/mstr_discrete/cap/chips/chips.prt';

PART_NAME
 C7G4 'CAP_0402LF-220PF,50V,10%,X7R,AA':
 ROOM='VDDQ_ABC_PWR_VR',
 NO_XNET_CONNECTION='1';

SECTION_NUMBER 1
 '@BASEBOARD_FAB2_LIB.BASEBOARD_FAB2(SCH_1):PAGE215_I14@MSTR_DISCRETE.CAP(CHIPS)':
 C_PATH='@baseboard_fab2_lib.baseboard_fab2(sch_1):page215_i14@mstr_discrete.cap~
(chips)',
 P_PATH='@baseboard_fab2_lib.baseboard_fab2(sch_1):page215_i14@mstr_discrete.cap~
(chips)',
 PATH='I14',
 DRAWING='@BASEBOARD_FAB2_LIB.BASEBOARD_FAB2(SCH_1):PAGE215',
 TOLERANCE='10%',
 SEC_TYPE='0402LF',
 MATERIAL='X7R',
 NO_XNET_CONNECTION='1',
 PHYS_PAGE='215',
 XY='(-300,850)',
 ROT='0',
 VER='1',
 VALUE='220PF',
 PACK_TYPE='0402LF',
 PART_NUMBER='A36096-050',
 LOCATION='C7G4',
 ROOM='VDDQ_ABC_PWR_VR',
 SEC='1',
 CDS_LIB='mstr_discrete',
 CDS_PART_NAME='CAP_0402LF-220PF,50V,10%,X7R,AA',
 VOLTAGE='50V',
 PRIM_FILE='./archive_libs/mstr_discrete/cap/chips/chips.prt';

PART_NAME
 C7G5 'CAP_0402-0.22UF,16V,10%,X7R,A3A':
 ROOM='OCP_STEERING';

SECTION_NUMBER 1
 '@BASEBOARD_FAB2_LIB.BASEBOARD_FAB2(SCH_1):PAGE105_I20@MSTR_DISCRETE.CAP(CHIPS)':
 C_PATH='@baseboard_fab2_lib.baseboard_fab2(sch_1):page105_i20@mstr_discrete.cap~
(chips)',
 P_PATH='@baseboard_fab2_lib.baseboard_fab2(sch_1):page105_i20@mstr_discrete.cap~
(chips)',
 PATH='I20',
 DRAWING='@BASEBOARD_FAB2_LIB.BASEBOARD_FAB2(SCH_1):PAGE105',
 TOLERANCE='10%',
 SEC_TYPE='0402',
 MATERIAL='X7R',
 PHYS_PAGE='105',
 XY='(-750,4350)',
 ROT='2',
 VER='1',
 VALUE='0.22UF',
 PACK_TYPE='0402',
 PART_NUMBER='A36096-155',
 LOCATION='C7G5',
 ROOM='OCP_STEERING',
 SEC='1',
 CDS_LIB='mstr_discrete',
 CDS_PART_NAME='CAP_0402-0.22UF,16V,10%,X7R,A3A',
 VOLTAGE='16V',
 PRIM_FILE='./archive_libs/mstr_discrete/cap/chips/chips.prt';

PART_NAME
 C7G6 'CAP_0402-0.22UF,16V,10%,X7R,A3A':
 ROOM='OCP_STEERING';

SECTION_NUMBER 1
 '@BASEBOARD_FAB2_LIB.BASEBOARD_FAB2(SCH_1):PAGE105_I6@MSTR_DISCRETE.CAP(CHIPS)':
 C_PATH='@baseboard_fab2_lib.baseboard_fab2(sch_1):page105_i6@mstr_discrete.cap(~
chips)',
 P_PATH='@baseboard_fab2_lib.baseboard_fab2(sch_1):page105_i6@mstr_discrete.cap(~
chips)',
 PATH='I6',
 DRAWING='@BASEBOARD_FAB2_LIB.BASEBOARD_FAB2(SCH_1):PAGE105',
 TOLERANCE='10%',
 MATERIAL='X7R',
 PHYS_PAGE='105',
 XY='(-700,3350)',
 ROT='2',
 VER='1',
 VALUE='0.22UF',
 PACK_TYPE='0402',
 PART_NUMBER='A36096-155',
 LOCATION='C7G6',
 ROOM='OCP_STEERING',
 CDS_LIB='mstr_discrete',
 CDS_PART_NAME='CAP_0402-0.22UF,16V,10%,X7R,A3A',
 VOLTAGE='16V',
 PRIM_FILE='./archive_libs/mstr_discrete/cap/chips/chips.prt';

PART_NAME
 C7G7 'CAP_0402-0.22UF,16V,10%,X7R,A3A':
 ROOM='OCP_STEERING';

SECTION_NUMBER 1
 '@BASEBOARD_FAB2_LIB.BASEBOARD_FAB2(SCH_1):PAGE105_I7@MSTR_DISCRETE.CAP(CHIPS)':
 C_PATH='@baseboard_fab2_lib.baseboard_fab2(sch_1):page105_i7@mstr_discrete.cap(~
chips)',
 P_PATH='@baseboard_fab2_lib.baseboard_fab2(sch_1):page105_i7@mstr_discrete.cap(~
chips)',
 PATH='I7',
 DRAWING='@BASEBOARD_FAB2_LIB.BASEBOARD_FAB2(SCH_1):PAGE105',
 TOLERANCE='10%',
 SEC_TYPE='0402',
 MATERIAL='X7R',
 PHYS_PAGE='105',
 XY='(-500,3650)',
 ROT='2',
 VER='1',
 VALUE='0.22UF',
 PACK_TYPE='0402',
 PART_NUMBER='A36096-155',
 LOCATION='C7G7',
 ROOM='OCP_STEERING',
 SEC='1',
 CDS_LIB='mstr_discrete',
 CDS_PART_NAME='CAP_0402-0.22UF,16V,10%,X7R,A3A',
 VOLTAGE='16V',
 PRIM_FILE='./archive_libs/mstr_discrete/cap/chips/chips.prt';

PART_NAME
 C7G8 'CAP_0402-0.22UF,16V,10%,X7R,A3A':
 ROOM='OCP_STEERING';

SECTION_NUMBER 1
 '@BASEBOARD_FAB2_LIB.BASEBOARD_FAB2(SCH_1):PAGE105_I22@MSTR_DISCRETE.CAP(CHIPS)':
 C_PATH='@baseboard_fab2_lib.baseboard_fab2(sch_1):page105_i22@mstr_discrete.cap~
(chips)',
 P_PATH='@baseboard_fab2_lib.baseboard_fab2(sch_1):page105_i22@mstr_discrete.cap~
(chips)',
 PATH='I22',
 DRAWING='@BASEBOARD_FAB2_LIB.BASEBOARD_FAB2(SCH_1):PAGE105',
 TOLERANCE='10%',
 SEC_TYPE='0402',
 MATERIAL='X7R',
 PHYS_PAGE='105',
 XY='(-550,4650)',
 ROT='2',
 VER='1',
 VALUE='0.22UF',
 PACK_TYPE='0402',
 PART_NUMBER='A36096-155',
 LOCATION='C7G8',
 ROOM='OCP_STEERING',
 SEC='1',
 CDS_LIB='mstr_discrete',
 CDS_PART_NAME='CAP_0402-0.22UF,16V,10%,X7R,A3A',
 VOLTAGE='16V',
 PRIM_FILE='./archive_libs/mstr_discrete/cap/chips/chips.prt';

PART_NAME
 C7G9 'CAP_0402-0.22UF,16V,10%,X7R,A3A':
 ROOM='OCP_STEERING';

SECTION_NUMBER 1
 '@BASEBOARD_FAB2_LIB.BASEBOARD_FAB2(SCH_1):PAGE105_I21@MSTR_DISCRETE.CAP(CHIPS)':
 C_PATH='@baseboard_fab2_lib.baseboard_fab2(sch_1):page105_i21@mstr_discrete.cap~
(chips)',
 P_PATH='@baseboard_fab2_lib.baseboard_fab2(sch_1):page105_i21@mstr_discrete.cap~
(chips)',
 PATH='I21',
 DRAWING='@BASEBOARD_FAB2_LIB.BASEBOARD_FAB2(SCH_1):PAGE105',
 TOLERANCE='10%',
 SEC_TYPE='0402',
 MATERIAL='X7R',
 PHYS_PAGE='105',
 XY='(-350,4350)',
 ROT='2',
 VER='1',
 VALUE='0.22UF',
 PACK_TYPE='0402',
 PART_NUMBER='A36096-155',
 LOCATION='C7G9',
 ROOM='OCP_STEERING',
 SEC='1',
 CDS_LIB='mstr_discrete',
 CDS_PART_NAME='CAP_0402-0.22UF,16V,10%,X7R,A3A',
 VOLTAGE='16V',
 PRIM_FILE='./archive_libs/mstr_discrete/cap/chips/chips.prt';

PART_NAME
 C7G10 'CAP_0402-0.22UF,16V,10%,X7R,A3A':
 ROOM='OCP_STEERING';

SECTION_NUMBER 1
 '@BASEBOARD_FAB2_LIB.BASEBOARD_FAB2(SCH_1):PAGE105_I8@MSTR_DISCRETE.CAP(CHIPS)':
 C_PATH='@baseboard_fab2_lib.baseboard_fab2(sch_1):page105_i8@mstr_discrete.cap(~
chips)',
 P_PATH='@baseboard_fab2_lib.baseboard_fab2(sch_1):page105_i8@mstr_discrete.cap(~
chips)',
 PATH='I8',
 DRAWING='@BASEBOARD_FAB2_LIB.BASEBOARD_FAB2(SCH_1):PAGE105',
 TOLERANCE='10%',
 SEC_TYPE='0402',
 MATERIAL='X7R',
 PHYS_PAGE='105',
 XY='(-300,3350)',
 ROT='2',
 VER='1',
 VALUE='0.22UF',
 PACK_TYPE='0402',
 PART_NUMBER='A36096-155',
 LOCATION='C7G10',
 ROOM='OCP_STEERING',
 SEC='1',
 CDS_LIB='mstr_discrete',
 CDS_PART_NAME='CAP_0402-0.22UF,16V,10%,X7R,A3A',
 VOLTAGE='16V',
 PRIM_FILE='./archive_libs/mstr_discrete/cap/chips/chips.prt';

PART_NAME
 C7G11 'CAP_0402-0.22UF,16V,10%,X7R,A3A':
 ROOM='OCP_STEERING';

SECTION_NUMBER 1
 '@BASEBOARD_FAB2_LIB.BASEBOARD_FAB2(SCH_1):PAGE105_I27@MSTR_DISCRETE.CAP(CHIPS)':
 C_PATH='@baseboard_fab2_lib.baseboard_fab2(sch_1):page105_i27@mstr_discrete.cap~
(chips)',
 P_PATH='@baseboard_fab2_lib.baseboard_fab2(sch_1):page105_i27@mstr_discrete.cap~
(chips)',
 PATH='I27',
 DRAWING='@BASEBOARD_FAB2_LIB.BASEBOARD_FAB2(SCH_1):PAGE105',
 TOLERANCE='10%',
 SEC_TYPE='0402',
 MATERIAL='X7R',
 PHYS_PAGE='105',
 XY='(-150,4650)',
 ROT='2',
 VER='1',
 VALUE='0.22UF',
 PACK_TYPE='0402',
 PART_NUMBER='A36096-155',
 LOCATION='C7G11',
 ROOM='OCP_STEERING',
 SEC='1',
 CDS_LIB='mstr_discrete',
 CDS_PART_NAME='CAP_0402-0.22UF,16V,10%,X7R,A3A',
 VOLTAGE='16V',
 PRIM_FILE='./archive_libs/mstr_discrete/cap/chips/chips.prt';

PART_NAME
 C7G12 'CAP_0402-0.22UF,16V,10%,X7R,A3A':
 ROOM='OCP_STEERING';

SECTION_NUMBER 1
 '@BASEBOARD_FAB2_LIB.BASEBOARD_FAB2(SCH_1):PAGE105_I12@MSTR_DISCRETE.CAP(CHIPS)':
 C_PATH='@baseboard_fab2_lib.baseboard_fab2(sch_1):page105_i12@mstr_discrete.cap~
(chips)',
 P_PATH='@baseboard_fab2_lib.baseboard_fab2(sch_1):page105_i12@mstr_discrete.cap~
(chips)',
 PATH='I12',
 DRAWING='@BASEBOARD_FAB2_LIB.BASEBOARD_FAB2(SCH_1):PAGE105',
 TOLERANCE='10%',
 SEC_TYPE='0402',
 MATERIAL='X7R',
 PHYS_PAGE='105',
 XY='(-100,3650)',
 ROT='2',
 VER='1',
 VALUE='0.22UF',
 PACK_TYPE='0402',
 PART_NUMBER='A36096-155',
 LOCATION='C7G12',
 ROOM='OCP_STEERING',
 SEC='1',
 CDS_LIB='mstr_discrete',
 CDS_PART_NAME='CAP_0402-0.22UF,16V,10%,X7R,A3A',
 VOLTAGE='16V',
 PRIM_FILE='./archive_libs/mstr_discrete/cap/chips/chips.prt';

PART_NAME
 C7G13 'CAP_0402-0.22UF,16V,10%,X7R,A3A':
 ROOM='OCP_STEERING';

SECTION_NUMBER 1
 '@BASEBOARD_FAB2_LIB.BASEBOARD_FAB2(SCH_1):PAGE105_I13@MSTR_DISCRETE.CAP(CHIPS)':
 C_PATH='@baseboard_fab2_lib.baseboard_fab2(sch_1):page105_i13@mstr_discrete.cap~
(chips)',
 P_PATH='@baseboard_fab2_lib.baseboard_fab2(sch_1):page105_i13@mstr_discrete.cap~
(chips)',
 PATH='I13',
 DRAWING='@BASEBOARD_FAB2_LIB.BASEBOARD_FAB2(SCH_1):PAGE105',
 TOLERANCE='10%',
 SEC_TYPE='0402',
 MATERIAL='X7R',
 PHYS_PAGE='105',
 XY='(100,3350)',
 ROT='2',
 VER='1',
 VALUE='0.22UF',
 PACK_TYPE='0402',
 PART_NUMBER='A36096-155',
 LOCATION='C7G13',
 ROOM='OCP_STEERING',
 SEC='1',
 CDS_LIB='mstr_discrete',
 CDS_PART_NAME='CAP_0402-0.22UF,16V,10%,X7R,A3A',
 VOLTAGE='16V',
 PRIM_FILE='./archive_libs/mstr_discrete/cap/chips/chips.prt';

PART_NAME
 C7G14 'CAP_0402-0.22UF,16V,10%,X7R,A3A':
 ROOM='OCP_STEERING';

SECTION_NUMBER 1
 '@BASEBOARD_FAB2_LIB.BASEBOARD_FAB2(SCH_1):PAGE105_I28@MSTR_DISCRETE.CAP(CHIPS)':
 C_PATH='@baseboard_fab2_lib.baseboard_fab2(sch_1):page105_i28@mstr_discrete.cap~
(chips)',
 P_PATH='@baseboard_fab2_lib.baseboard_fab2(sch_1):page105_i28@mstr_discrete.cap~
(chips)',
 PATH='I28',
 DRAWING='@BASEBOARD_FAB2_LIB.BASEBOARD_FAB2(SCH_1):PAGE105',
 TOLERANCE='10%',
 SEC_TYPE='0402',
 MATERIAL='X7R',
 PHYS_PAGE='105',
 XY='(50,4350)',
 ROT='2',
 VER='1',
 VALUE='0.22UF',
 PACK_TYPE='0402',
 PART_NUMBER='A36096-155',
 LOCATION='C7G14',
 ROOM='OCP_STEERING',
 SEC='1',
 CDS_LIB='mstr_discrete',
 CDS_PART_NAME='CAP_0402-0.22UF,16V,10%,X7R,A3A',
 VOLTAGE='16V',
 PRIM_FILE='./archive_libs/mstr_discrete/cap/chips/chips.prt';

PART_NAME
 C7G15 'CAP_0402-0.22UF,16V,10%,X7R,A3A':
 ROOM='OCP_STEERING';

SECTION_NUMBER 1
 '@BASEBOARD_FAB2_LIB.BASEBOARD_FAB2(SCH_1):PAGE105_I45@MSTR_DISCRETE.CAP(CHIPS)':
 C_PATH='@baseboard_fab2_lib.baseboard_fab2(sch_1):page105_i45@mstr_discrete.cap~
(chips)',
 P_PATH='@baseboard_fab2_lib.baseboard_fab2(sch_1):page105_i45@mstr_discrete.cap~
(chips)',
 PATH='I45',
 DRAWING='@BASEBOARD_FAB2_LIB.BASEBOARD_FAB2(SCH_1):PAGE105',
 TOLERANCE='10%',
 SEC_TYPE='0402',
 MATERIAL='X7R',
 PHYS_PAGE='105',
 XY='(250,4650)',
 ROT='2',
 VER='1',
 VALUE='0.22UF',
 PACK_TYPE='0402',
 PART_NUMBER='A36096-155',
 LOCATION='C7G15',
 ROOM='OCP_STEERING',
 SEC='1',
 CDS_LIB='mstr_discrete',
 CDS_PART_NAME='CAP_0402-0.22UF,16V,10%,X7R,A3A',
 VOLTAGE='16V',
 PRIM_FILE='./archive_libs/mstr_discrete/cap/chips/chips.prt';

PART_NAME
 C7G16 'CAP_0402-0.22UF,16V,10%,X7R,A3A':
 ROOM='OCP_STEERING';

SECTION_NUMBER 1
 '@BASEBOARD_FAB2_LIB.BASEBOARD_FAB2(SCH_1):PAGE105_I31@MSTR_DISCRETE.CAP(CHIPS)':
 C_PATH='@baseboard_fab2_lib.baseboard_fab2(sch_1):page105_i31@mstr_discrete.cap~
(chips)',
 P_PATH='@baseboard_fab2_lib.baseboard_fab2(sch_1):page105_i31@mstr_discrete.cap~
(chips)',
 PATH='I31',
 DRAWING='@BASEBOARD_FAB2_LIB.BASEBOARD_FAB2(SCH_1):PAGE105',
 TOLERANCE='10%',
 SEC_TYPE='0402',
 MATERIAL='X7R',
 PHYS_PAGE='105',
 XY='(300,3650)',
 ROT='2',
 VER='1',
 VALUE='0.22UF',
 PACK_TYPE='0402',
 PART_NUMBER='A36096-155',
 LOCATION='C7G16',
 ROOM='OCP_STEERING',
 SEC='1',
 CDS_LIB='mstr_discrete',
 CDS_PART_NAME='CAP_0402-0.22UF,16V,10%,X7R,A3A',
 VOLTAGE='16V',
 PRIM_FILE='./archive_libs/mstr_discrete/cap/chips/chips.prt';

PART_NAME
 C7G17 'CAP_0402-0.22UF,16V,10%,X7R,A3A':
 ROOM='OCP_STEERING';

SECTION_NUMBER 1
 '@BASEBOARD_FAB2_LIB.BASEBOARD_FAB2(SCH_1):PAGE105_I44@MSTR_DISCRETE.CAP(CHIPS)':
 C_PATH='@baseboard_fab2_lib.baseboard_fab2(sch_1):page105_i44@mstr_discrete.cap~
(chips)',
 P_PATH='@baseboard_fab2_lib.baseboard_fab2(sch_1):page105_i44@mstr_discrete.cap~
(chips)',
 PATH='I44',
 DRAWING='@BASEBOARD_FAB2_LIB.BASEBOARD_FAB2(SCH_1):PAGE105',
 TOLERANCE='10%',
 SEC_TYPE='0402',
 MATERIAL='X7R',
 PHYS_PAGE='105',
 XY='(450,4350)',
 ROT='2',
 VER='1',
 VALUE='0.22UF',
 PACK_TYPE='0402',
 PART_NUMBER='A36096-155',
 LOCATION='C7G17',
 ROOM='OCP_STEERING',
 SEC='1',
 CDS_LIB='mstr_discrete',
 CDS_PART_NAME='CAP_0402-0.22UF,16V,10%,X7R,A3A',
 VOLTAGE='16V',
 PRIM_FILE='./archive_libs/mstr_discrete/cap/chips/chips.prt';

PART_NAME
 C7G18 'CAP_0402-0.22UF,16V,10%,X7R,A3A':
 ROOM='OCP_STEERING';

SECTION_NUMBER 1
 '@BASEBOARD_FAB2_LIB.BASEBOARD_FAB2(SCH_1):PAGE105_I32@MSTR_DISCRETE.CAP(CHIPS)':
 C_PATH='@baseboard_fab2_lib.baseboard_fab2(sch_1):page105_i32@mstr_discrete.cap~
(chips)',
 P_PATH='@baseboard_fab2_lib.baseboard_fab2(sch_1):page105_i32@mstr_discrete.cap~
(chips)',
 PATH='I32',
 DRAWING='@BASEBOARD_FAB2_LIB.BASEBOARD_FAB2(SCH_1):PAGE105',
 TOLERANCE='10%',
 SEC_TYPE='0402',
 MATERIAL='X7R',
 PHYS_PAGE='105',
 XY='(500,3350)',
 ROT='2',
 VER='1',
 VALUE='0.22UF',
 PACK_TYPE='0402',
 PART_NUMBER='A36096-155',
 LOCATION='C7G18',
 ROOM='OCP_STEERING',
 SEC='1',
 CDS_LIB='mstr_discrete',
 CDS_PART_NAME='CAP_0402-0.22UF,16V,10%,X7R,A3A',
 VOLTAGE='16V',
 PRIM_FILE='./archive_libs/mstr_discrete/cap/chips/chips.prt';

PART_NAME
 C7G19 'CAP_0402-0.22UF,16V,10%,X7R,A3A':
 ROOM='OCP_STEERING';

SECTION_NUMBER 1
 '@BASEBOARD_FAB2_LIB.BASEBOARD_FAB2(SCH_1):PAGE105_I257@MSTR_DISCRETE.CAP(CHIPS)':
 C_PATH='@baseboard_fab2_lib.baseboard_fab2(sch_1):page105_i257@mstr_discrete.ca~
p(chips)',
 P_PATH='@baseboard_fab2_lib.baseboard_fab2(sch_1):page105_i257@mstr_discrete.ca~
p(chips)',
 PATH='I257',
 DRAWING='@BASEBOARD_FAB2_LIB.BASEBOARD_FAB2(SCH_1):PAGE105',
 TOLERANCE='10%',
 SEC_TYPE='0402',
 MATERIAL='X7R',
 PHYS_PAGE='105',
 XY='(700,3650)',
 ROT='2',
 VER='1',
 VALUE='0.22UF',
 PACK_TYPE='0402',
 PART_NUMBER='A36096-155',
 LOCATION='C7G19',
 ROOM='OCP_STEERING',
 SEC='1',
 CDS_LIB='mstr_discrete',
 CDS_PART_NAME='CAP_0402-0.22UF,16V,10%,X7R,A3A',
 VOLTAGE='16V',
 PRIM_FILE='./archive_libs/mstr_discrete/cap/chips/chips.prt';

PART_NAME
 C7G20 'CAP_0402-0.22UF,16V,10%,X7R,A3A':
 ROOM='OCP_STEERING';

SECTION_NUMBER 1
 '@BASEBOARD_FAB2_LIB.BASEBOARD_FAB2(SCH_1):PAGE105_I258@MSTR_DISCRETE.CAP(CHIPS)':
 C_PATH='@baseboard_fab2_lib.baseboard_fab2(sch_1):page105_i258@mstr_discrete.ca~
p(chips)',
 P_PATH='@baseboard_fab2_lib.baseboard_fab2(sch_1):page105_i258@mstr_discrete.ca~
p(chips)',
 PATH='I258',
 DRAWING='@BASEBOARD_FAB2_LIB.BASEBOARD_FAB2(SCH_1):PAGE105',
 TOLERANCE='10%',
 SEC_TYPE='0402',
 MATERIAL='X7R',
 PHYS_PAGE='105',
 XY='(650,4650)',
 ROT='2',
 VER='1',
 VALUE='0.22UF',
 PACK_TYPE='0402',
 PART_NUMBER='A36096-155',
 LOCATION='C7G20',
 ROOM='OCP_STEERING',
 SEC='1',
 CDS_LIB='mstr_discrete',
 CDS_PART_NAME='CAP_0402-0.22UF,16V,10%,X7R,A3A',
 VOLTAGE='16V',
 PRIM_FILE='./archive_libs/mstr_discrete/cap/chips/chips.prt';

PART_NAME
 C7G21 'CAP_0402-0.22UF,16V,10%,X7R,A3A':
 ROOM='OCP_STEERING';

SECTION_NUMBER 1
 '@BASEBOARD_FAB2_LIB.BASEBOARD_FAB2(SCH_1):PAGE105_I51@MSTR_DISCRETE.CAP(CHIPS)':
 C_PATH='@baseboard_fab2_lib.baseboard_fab2(sch_1):page105_i51@mstr_discrete.cap~
(chips)',
 P_PATH='@baseboard_fab2_lib.baseboard_fab2(sch_1):page105_i51@mstr_discrete.cap~
(chips)',
 PATH='I51',
 DRAWING='@BASEBOARD_FAB2_LIB.BASEBOARD_FAB2(SCH_1):PAGE105',
 TOLERANCE='10%',
 SEC_TYPE='0402',
 MATERIAL='X7R',
 PHYS_PAGE='105',
 XY='(875,4350)',
 ROT='2',
 VER='1',
 VALUE='0.22UF',
 PACK_TYPE='0402',
 PART_NUMBER='A36096-155',
 LOCATION='C7G21',
 ROOM='OCP_STEERING',
 SEC='1',
 CDS_LIB='mstr_discrete',
 CDS_PART_NAME='CAP_0402-0.22UF,16V,10%,X7R,A3A',
 VOLTAGE='16V',
 PRIM_FILE='./archive_libs/mstr_discrete/cap/chips/chips.prt';

PART_NAME
 C7G22 'CAP_0402-0.22UF,16V,10%,X7R,A3A':
 ROOM='OCP_STEERING';

SECTION_NUMBER 1
 '@BASEBOARD_FAB2_LIB.BASEBOARD_FAB2(SCH_1):PAGE105_I37@MSTR_DISCRETE.CAP(CHIPS)':
 C_PATH='@baseboard_fab2_lib.baseboard_fab2(sch_1):page105_i37@mstr_discrete.cap~
(chips)',
 P_PATH='@baseboard_fab2_lib.baseboard_fab2(sch_1):page105_i37@mstr_discrete.cap~
(chips)',
 PATH='I37',
 DRAWING='@BASEBOARD_FAB2_LIB.BASEBOARD_FAB2(SCH_1):PAGE105',
 TOLERANCE='10%',
 SEC_TYPE='0402',
 MATERIAL='X7R',
 PHYS_PAGE='105',
 XY='(925,3350)',
 ROT='2',
 VER='1',
 VALUE='0.22UF',
 PACK_TYPE='0402',
 PART_NUMBER='A36096-155',
 LOCATION='C7G22',
 ROOM='OCP_STEERING',
 SEC='1',
 CDS_LIB='mstr_discrete',
 CDS_PART_NAME='CAP_0402-0.22UF,16V,10%,X7R,A3A',
 VOLTAGE='16V',
 PRIM_FILE='./archive_libs/mstr_discrete/cap/chips/chips.prt';

PART_NAME
 C7G23 'CAP_0402-0.22UF,16V,10%,X7R,A3A':
 ROOM='OCP_STEERING';

SECTION_NUMBER 1
 '@BASEBOARD_FAB2_LIB.BASEBOARD_FAB2(SCH_1):PAGE105_I52@MSTR_DISCRETE.CAP(CHIPS)':
 C_PATH='@baseboard_fab2_lib.baseboard_fab2(sch_1):page105_i52@mstr_discrete.cap~
(chips)',
 P_PATH='@baseboard_fab2_lib.baseboard_fab2(sch_1):page105_i52@mstr_discrete.cap~
(chips)',
 PATH='I52',
 DRAWING='@BASEBOARD_FAB2_LIB.BASEBOARD_FAB2(SCH_1):PAGE105',
 TOLERANCE='10%',
 SEC_TYPE='0402',
 MATERIAL='X7R',
 PHYS_PAGE='105',
 XY='(1075,4650)',
 ROT='2',
 VER='1',
 VALUE='0.22UF',
 PACK_TYPE='0402',
 PART_NUMBER='A36096-155',
 LOCATION='C7G23',
 ROOM='OCP_STEERING',
 SEC='1',
 CDS_LIB='mstr_discrete',
 CDS_PART_NAME='CAP_0402-0.22UF,16V,10%,X7R,A3A',
 VOLTAGE='16V',
 PRIM_FILE='./archive_libs/mstr_discrete/cap/chips/chips.prt';

PART_NAME
 C7G24 'CAP_0402-0.22UF,16V,10%,X7R,A3A':
 ROOM='OCP_STEERING';

SECTION_NUMBER 1
 '@BASEBOARD_FAB2_LIB.BASEBOARD_FAB2(SCH_1):PAGE105_I1@MSTR_DISCRETE.CAP(CHIPS)':
 C_PATH='@baseboard_fab2_lib.baseboard_fab2(sch_1):page105_i1@mstr_discrete.cap(~
chips)',
 P_PATH='@baseboard_fab2_lib.baseboard_fab2(sch_1):page105_i1@mstr_discrete.cap(~
chips)',
 PATH='I1',
 DRAWING='@BASEBOARD_FAB2_LIB.BASEBOARD_FAB2(SCH_1):PAGE105',
 TOLERANCE='10%',
 SEC_TYPE='0402',
 MATERIAL='X7R',
 PHYS_PAGE='105',
 XY='(1125,3650)',
 ROT='2',
 VER='1',
 VALUE='0.22UF',
 PACK_TYPE='0402',
 PART_NUMBER='A36096-155',
 LOCATION='C7G24',
 ROOM='OCP_STEERING',
 SEC='1',
 CDS_LIB='mstr_discrete',
 CDS_PART_NAME='CAP_0402-0.22UF,16V,10%,X7R,A3A',
 VOLTAGE='16V',
 PRIM_FILE='./archive_libs/mstr_discrete/cap/chips/chips.prt';

PART_NAME
 C7G25 'CAP_0402-0.22UF,16V,10%,X7R,A3A':
 ROOM='OCP_STEERING';

SECTION_NUMBER 1
 '@BASEBOARD_FAB2_LIB.BASEBOARD_FAB2(SCH_1):PAGE105_I69@MSTR_DISCRETE.CAP(CHIPS)':
 C_PATH='@baseboard_fab2_lib.baseboard_fab2(sch_1):page105_i69@mstr_discrete.cap~
(chips)',
 P_PATH='@baseboard_fab2_lib.baseboard_fab2(sch_1):page105_i69@mstr_discrete.cap~
(chips)',
 PATH='I69',
 DRAWING='@BASEBOARD_FAB2_LIB.BASEBOARD_FAB2(SCH_1):PAGE105',
 TOLERANCE='10%',
 SEC_TYPE='0402',
 MATERIAL='X7R',
 PHYS_PAGE='105',
 XY='(1275,4350)',
 ROT='2',
 VER='1',
 VALUE='0.22UF',
 PACK_TYPE='0402',
 PART_NUMBER='A36096-155',
 LOCATION='C7G25',
 ROOM='OCP_STEERING',
 SEC='1',
 CDS_LIB='mstr_discrete',
 CDS_PART_NAME='CAP_0402-0.22UF,16V,10%,X7R,A3A',
 VOLTAGE='16V',
 PRIM_FILE='./archive_libs/mstr_discrete/cap/chips/chips.prt';

PART_NAME
 C7G26 'CAP_0402-0.22UF,16V,10%,X7R,A3A':
 ROOM='OCP_STEERING';

SECTION_NUMBER 1
 '@BASEBOARD_FAB2_LIB.BASEBOARD_FAB2(SCH_1):PAGE105_I55@MSTR_DISCRETE.CAP(CHIPS)':
 C_PATH='@baseboard_fab2_lib.baseboard_fab2(sch_1):page105_i55@mstr_discrete.cap~
(chips)',
 P_PATH='@baseboard_fab2_lib.baseboard_fab2(sch_1):page105_i55@mstr_discrete.cap~
(chips)',
 PATH='I55',
 DRAWING='@BASEBOARD_FAB2_LIB.BASEBOARD_FAB2(SCH_1):PAGE105',
 TOLERANCE='10%',
 SEC_TYPE='0402',
 MATERIAL='X7R',
 PHYS_PAGE='105',
 XY='(1325,3350)',
 ROT='2',
 VER='1',
 VALUE='0.22UF',
 PACK_TYPE='0402',
 PART_NUMBER='A36096-155',
 LOCATION='C7G26',
 ROOM='OCP_STEERING',
 SEC='1',
 CDS_LIB='mstr_discrete',
 CDS_PART_NAME='CAP_0402-0.22UF,16V,10%,X7R,A3A',
 VOLTAGE='16V',
 PRIM_FILE='./archive_libs/mstr_discrete/cap/chips/chips.prt';

PART_NAME
 C7G27 'CAP_0805LF-22UF,4V,20%,X6S,C95A':
 GROUP='PWR_MLCC_CAP',
 ROOM='VDDQ_ABC_PWR_VR';

SECTION_NUMBER 1
 '@BASEBOARD_FAB2_LIB.BASEBOARD_FAB2(SCH_1):PAGE216_I68@MSTR_DISCRETE.CAP(CHIPS)':
 C_PATH='@baseboard_fab2_lib.baseboard_fab2(sch_1):page216_i68@mstr_discrete.cap~
(chips)',
 P_PATH='@baseboard_fab2_lib.baseboard_fab2(sch_1):page216_i68@mstr_discrete.cap~
(chips)',
 PATH='I68',
 DRAWING='@BASEBOARD_FAB2_LIB.BASEBOARD_FAB2(SCH_1):PAGE216',
 BOM_SS='NOPOP',
 TOLERANCE='20%',
 SEC_TYPE='0805LF',
 MATERIAL='X6S',
 BOM_COST='PROC_VRD_VCCIN_CPU0',
 PHYS_PAGE='216',
 XY='(4400,-550)',
 ROT='0',
 VER='1',
 VALUE='22UF',
 PACK_TYPE='0805LF',
 PART_NUMBER='C95333-002',
 LOCATION='C7G27',
 ROOM='VDDQ_ABC_PWR_VR',
 GROUP='PWR_MLCC_CAP',
 SEC='1',
 CDS_LIB='mstr_discrete',
 CDS_PART_NAME='CAP_0805LF-22UF,4V,20%,X6S,C95A',
 VOLTAGE='4V',
 PRIM_FILE='./archive_libs/mstr_discrete/cap/chips/chips.prt';

PART_NAME
 C7G28 'CAPP_3018-470UF,2.5V,20%,ALUM,A':
 GROUP='PWR_BULK_CAP',
 ROOM='VDDQ_ABC_PWR_VR';

SECTION_NUMBER 1
 '@BASEBOARD_FAB2_LIB.BASEBOARD_FAB2(SCH_1):PAGE217_I75@MSTR_DISCRETE.CAPP(CHIPS)':
 C_PATH='@baseboard_fab2_lib.baseboard_fab2(sch_1):page217_i75@mstr_discrete.cap~
p(chips)',
 P_PATH='@baseboard_fab2_lib.baseboard_fab2(sch_1):page217_i75@mstr_discrete.cap~
p(chips)',
 PATH='I75',
 DRAWING='@BASEBOARD_FAB2_LIB.BASEBOARD_FAB2(SCH_1):PAGE217',
 TOLERANCE='20%',
 SEC_TYPE='3018',
 MATERIAL='ALUM',
 PHYS_PAGE='217',
 XY='(3350,-400)',
 ROT='0',
 VER='1',
 VALUE='470UF',
 PACK_TYPE='3018',
 PART_NUMBER='699013-049',
 LOCATION='C7G28',
 ROOM='VDDQ_ABC_PWR_VR',
 GROUP='PWR_BULK_CAP',
 SEC='1',
 CDS_LIB='mstr_discrete',
 CDS_PART_NAME='CAPP_3018-470UF,2.5V,20%,ALUM,A',
 VOLTAGE='2.5V',
 PRIM_FILE='./archive_libs/mstr_discrete/capp/chips/chips.prt';

PART_NAME
 C7G29 'CAP_A_0402V-0.1UF,16V,10%,X7R,A':
 ROOM='VDDQ_ABC_PWR_VR';

SECTION_NUMBER 1
 '@BASEBOARD_FAB2_LIB.BASEBOARD_FAB2(SCH_1):PAGE216_I51@DEV_DISCRETE.CAP_A(CHIPS)':
 C_PATH='@baseboard_fab2_lib.baseboard_fab2(sch_1):page216_i51@dev_discrete.cap_~
a(chips)',
 P_PATH='@baseboard_fab2_lib.baseboard_fab2(sch_1):page216_i51@dev_discrete.cap_~
a(chips)',
 PATH='I51',
 DRAWING='@BASEBOARD_FAB2_LIB.BASEBOARD_FAB2(SCH_1):PAGE216',
 TOLERANCE='10%',
 SEC_TYPE='0402V',
 MATERIAL='X7R',
 PHYS_PAGE='216',
 XY='(-1000,2525)',
 ROT='0',
 VER='1',
 VALUE='0.1UF',
 PACK_TYPE='0402V',
 PART_NUMBER='A36096-030',
 LOCATION='C7G29',
 ROOM='VDDQ_ABC_PWR_VR',
 SEC='1',
 CDS_LIB='dev_discrete',
 CDS_PART_NAME='CAP_A_0402V-0.1UF,16V,10%,X7R,A',
 VOLTAGE='16V',
 PRIM_FILE='./archive_libs/discrete/cap_a/chips/chips.prt';

PART_NAME
 C7G30 'CAP_0402-1.0UF,16V,10%,X6S,D97A':
 ROOM='VDDQ_ABC_PWR_VR';

SECTION_NUMBER 1
 '@BASEBOARD_FAB2_LIB.BASEBOARD_FAB2(SCH_1):PAGE216_I79@MSTR_DISCRETE.CAP(CHIPS)':
 C_PATH='@baseboard_fab2_lib.baseboard_fab2(sch_1):page216_i79@mstr_discrete.cap~
(chips)',
 P_PATH='@baseboard_fab2_lib.baseboard_fab2(sch_1):page216_i79@mstr_discrete.cap~
(chips)',
 PATH='I79',
 DRAWING='@BASEBOARD_FAB2_LIB.BASEBOARD_FAB2(SCH_1):PAGE216',
 TOLERANCE='10%',
 SEC_TYPE='0402',
 MATERIAL='X6S',
 PHYS_PAGE='216',
 XY='(-1325,175)',
 ROT='0',
 VER='1',
 VALUE='1.0UF',
 PACK_TYPE='0402',
 PART_NUMBER='D97712-011',
 LOCATION='C7G30',
 ROOM='VDDQ_ABC_PWR_VR',
 SEC='1',
 CDS_LIB='mstr_discrete',
 CDS_PART_NAME='CAP_0402-1.0UF,16V,10%,X6S,D97A',
 VOLTAGE='16V',
 PRIM_FILE='./archive_libs/mstr_discrete/cap/chips/chips.prt';

PART_NAME
 C7G31 'CAP_0402-0.220UF,16V,10%,X7R,AA':
 ROOM='VDDQ_ABC_PWR_VR';

SECTION_NUMBER 1
 '@BASEBOARD_FAB2_LIB.BASEBOARD_FAB2(SCH_1):PAGE216_I44@MSTR_DISCRETE.CAP(CHIPS)':
 C_PATH='@baseboard_fab2_lib.baseboard_fab2(sch_1):page216_i44@mstr_discrete.cap~
(chips)',
 P_PATH='@baseboard_fab2_lib.baseboard_fab2(sch_1):page216_i44@mstr_discrete.cap~
(chips)',
 PATH='I44',
 DRAWING='@BASEBOARD_FAB2_LIB.BASEBOARD_FAB2(SCH_1):PAGE216',
 SPOF='TRUE',
 TOLERANCE='10%',
 SEC_TYPE='0402',
 MATERIAL='X7R',
 PHYS_PAGE='216',
 XY='(-675,1925)',
 ROT='2',
 VER='1',
 VALUE='0.220UF',
 PACK_TYPE='0402',
 PART_NUMBER='A36096-104',
 LOCATION='C7G31',
 ROOM='VDDQ_ABC_PWR_VR',
 SEC='1',
 CDS_LIB='mstr_discrete',
 CDS_PART_NAME='CAP_0402-0.220UF,16V,10%,X7R,AA',
 VOLTAGE='16V',
 PRIM_FILE='./archive_libs/mstr_discrete/cap/chips/chips.prt';

PART_NAME
 C7G33 'CAP_0402-1.0UF,16V,10%,X6S,D97A':
 ROOM='VDDQ_ABC_PWR_VR';

SECTION_NUMBER 1
 '@BASEBOARD_FAB2_LIB.BASEBOARD_FAB2(SCH_1):PAGE216_I50@MSTR_DISCRETE.CAP(CHIPS)':
 C_PATH='@baseboard_fab2_lib.baseboard_fab2(sch_1):page216_i50@mstr_discrete.cap~
(chips)',
 P_PATH='@baseboard_fab2_lib.baseboard_fab2(sch_1):page216_i50@mstr_discrete.cap~
(chips)',
 PATH='I50',
 DRAWING='@BASEBOARD_FAB2_LIB.BASEBOARD_FAB2(SCH_1):PAGE216',
 TOLERANCE='10%',
 SEC_TYPE='0402',
 MATERIAL='X6S',
 PHYS_PAGE='216',
 XY='(-725,2525)',
 ROT='0',
 VER='1',
 VALUE='1.0UF',
 PACK_TYPE='0402',
 PART_NUMBER='D97712-011',
 LOCATION='C7G33',
 ROOM='VDDQ_ABC_PWR_VR',
 SEC='1',
 CDS_LIB='mstr_discrete',
 CDS_PART_NAME='CAP_0402-1.0UF,16V,10%,X6S,D97A',
 VOLTAGE='16V',
 PRIM_FILE='./archive_libs/mstr_discrete/cap/chips/chips.prt';

PART_NAME
 C7G34 'CAP_0402-0.22UF,16V,10%,X7R,A3A':
 ROOM='VDDQ_ABC_PWR_VR';

SECTION_NUMBER 1
 '@BASEBOARD_FAB2_LIB.BASEBOARD_FAB2(SCH_1):PAGE216_I54@MSTR_DISCRETE.CAP(CHIPS)':
 C_PATH='@baseboard_fab2_lib.baseboard_fab2(sch_1):page216_i54@mstr_discrete.cap~
(chips)',
 P_PATH='@baseboard_fab2_lib.baseboard_fab2(sch_1):page216_i54@mstr_discrete.cap~
(chips)',
 PATH='I54',
 DRAWING='@BASEBOARD_FAB2_LIB.BASEBOARD_FAB2(SCH_1):PAGE216',
 TOLERANCE='10%',
 SEC_TYPE='0402',
 MATERIAL='X7R',
 PHYS_PAGE='216',
 XY='(100,2550)',
 ROT='0',
 VER='1',
 VALUE='0.22UF',
 PACK_TYPE='0402',
 PART_NUMBER='A36096-155',
 LOCATION='C7G34',
 ROOM='VDDQ_ABC_PWR_VR',
 SEC='1',
 CDS_LIB='mstr_discrete',
 CDS_PART_NAME='CAP_0402-0.22UF,16V,10%,X7R,A3A',
 VOLTAGE='16V',
 PRIM_FILE='./archive_libs/mstr_discrete/cap/chips/chips.prt';

PART_NAME
 C7G35 'SC1U10V2KX-4-GP_SMD-BCG6-SC1U1A':;

SECTION_NUMBER 1
 '@BASEBOARD_FAB2_LIB.BASEBOARD_FAB2(SCH_1):PAGE216_I149@W_HDL.SC1U10V2KX-4-GP(CHIPS)':
 C_PATH='@baseboard_fab2_lib.baseboard_fab2(sch_1):page216_i149@w_hdl.\sc1u10v2k~
x-4-gp\(chips)',
 P_PATH='@baseboard_fab2_lib.baseboard_fab2(sch_1):page216_i149@w_hdl.\sc1u10v2k~
x-4-gp\(chips)',
 PATH='I149',
 DRAWING='@BASEBOARD_FAB2_LIB.BASEBOARD_FAB2(SCH_1):PAGE216',
 PACK_SIZE='0402',
 RATED='10V',
 ATTRIBUTE='1UF',
 TOLERANCE='10%',
 SEC_TYPE='SMD-BCG6',
 PHYS_PAGE='216',
 XY='(-250,2525)',
 ROT='0',
 VER='1',
 VALUE='SC1U10V2KX-4-GP',
 PACK_TYPE='SMD-BCG6',
 PART_NUMBER='78.10523.8FL',
 LOCATION='C7G35',
 SEC='1',
 CDS_LIB='w_hdl',
 CDS_PART_NAME='SC1U10V2KX-4-GP_SMD-BCG6-SC1U1A',
 PRIM_FILE='C:/<user>/w_hdl/sc1u10v2kx#2d4#2dgp/chips/chips.prt';

PART_NAME
 C7G36 'CAP_A_0402V-0.1UF,16V,10%,X7R,A':
 ROOM='VDDQ_ABC_PWR_VR';

SECTION_NUMBER 1
 '@BASEBOARD_FAB2_LIB.BASEBOARD_FAB2(SCH_1):PAGE216_I78@DEV_DISCRETE.CAP_A(CHIPS)':
 C_PATH='@baseboard_fab2_lib.baseboard_fab2(sch_1):page216_i78@dev_discrete.cap_~
a(chips)',
 P_PATH='@baseboard_fab2_lib.baseboard_fab2(sch_1):page216_i78@dev_discrete.cap_~
a(chips)',
 PATH='I78',
 DRAWING='@BASEBOARD_FAB2_LIB.BASEBOARD_FAB2(SCH_1):PAGE216',
 TOLERANCE='10%',
 SEC_TYPE='0402V',
 MATERIAL='X7R',
 PHYS_PAGE='216',
 XY='(-1075,175)',
 ROT='0',
 VER='1',
 VALUE='0.1UF',
 PACK_TYPE='0402V',
 PART_NUMBER='A36096-030',
 LOCATION='C7G36',
 ROOM='VDDQ_ABC_PWR_VR',
 SEC='1',
 CDS_LIB='dev_discrete',
 CDS_PART_NAME='CAP_A_0402V-0.1UF,16V,10%,X7R,A',
 VOLTAGE='16V',
 PRIM_FILE='./archive_libs/discrete/cap_a/chips/chips.prt';

PART_NAME
 C7G37 'CAP_0402-1.0UF,16V,10%,X6S,D97A':
 ROOM='VDDQ_ABC_PWR_VR';

SECTION_NUMBER 1
 '@BASEBOARD_FAB2_LIB.BASEBOARD_FAB2(SCH_1):PAGE216_I48@MSTR_DISCRETE.CAP(CHIPS)':
 C_PATH='@baseboard_fab2_lib.baseboard_fab2(sch_1):page216_i48@mstr_discrete.cap~
(chips)',
 P_PATH='@baseboard_fab2_lib.baseboard_fab2(sch_1):page216_i48@mstr_discrete.cap~
(chips)',
 PATH='I48',
 DRAWING='@BASEBOARD_FAB2_LIB.BASEBOARD_FAB2(SCH_1):PAGE216',
 TOLERANCE='10%',
 SEC_TYPE='0402',
 MATERIAL='X6S',
 PHYS_PAGE='216',
 XY='(-1275,2525)',
 ROT='0',
 VER='1',
 VALUE='1.0UF',
 PACK_TYPE='0402',
 PART_NUMBER='D97712-011',
 LOCATION='C7G37',
 ROOM='VDDQ_ABC_PWR_VR',
 SEC='1',
 CDS_LIB='mstr_discrete',
 CDS_PART_NAME='CAP_0402-1.0UF,16V,10%,X6S,D97A',
 VOLTAGE='16V',
 PRIM_FILE='./archive_libs/mstr_discrete/cap/chips/chips.prt';

PART_NAME
 C7G38 'CAP_0402-0.220UF,16V,10%,X7R,AA':
 ROOM='VDDQ_ABC_PWR_VR';

SECTION_NUMBER 1
 '@BASEBOARD_FAB2_LIB.BASEBOARD_FAB2(SCH_1):PAGE216_I128@MSTR_DISCRETE.CAP(CHIPS)':
 C_PATH='@baseboard_fab2_lib.baseboard_fab2(sch_1):page216_i128@mstr_discrete.ca~
p(chips)',
 P_PATH='@baseboard_fab2_lib.baseboard_fab2(sch_1):page216_i128@mstr_discrete.ca~
p(chips)',
 PATH='I128',
 DRAWING='@BASEBOARD_FAB2_LIB.BASEBOARD_FAB2(SCH_1):PAGE216',
 BOM_SS='NOPOP',
 SPOF='TRUE',
 TOLERANCE='10%',
 SEC_TYPE='0402',
 MATERIAL='X7R',
 PHYS_PAGE='216',
 XY='(-800,-425)',
 ROT='2',
 VER='1',
 VALUE='0.220UF',
 PACK_TYPE='0402',
 PART_NUMBER='A36096-104',
 LOCATION='C7G38',
 ROOM='VDDQ_ABC_PWR_VR',
 SEC='1',
 CDS_LIB='mstr_discrete',
 CDS_PART_NAME='CAP_0402-0.220UF,16V,10%,X7R,AA',
 VOLTAGE='16V',
 PRIM_FILE='./archive_libs/mstr_discrete/cap/chips/chips.prt';

PART_NAME
 C7G40 'CAP_0402-1.0UF,16V,10%,X6S,D97A':
 ROOM='VDDQ_ABC_PWR_VR';

SECTION_NUMBER 1
 '@BASEBOARD_FAB2_LIB.BASEBOARD_FAB2(SCH_1):PAGE216_I77@MSTR_DISCRETE.CAP(CHIPS)':
 C_PATH='@baseboard_fab2_lib.baseboard_fab2(sch_1):page216_i77@mstr_discrete.cap~
(chips)',
 P_PATH='@baseboard_fab2_lib.baseboard_fab2(sch_1):page216_i77@mstr_discrete.cap~
(chips)',
 PATH='I77',
 DRAWING='@BASEBOARD_FAB2_LIB.BASEBOARD_FAB2(SCH_1):PAGE216',
 BOM_SS='NOPOP',
 TOLERANCE='10%',
 SEC_TYPE='0402',
 MATERIAL='X6S',
 PHYS_PAGE='216',
 XY='(-825,175)',
 ROT='0',
 VER='1',
 VALUE='1.0UF',
 PACK_TYPE='0402',
 PART_NUMBER='D97712-011',
 LOCATION='C7G40',
 ROOM='VDDQ_ABC_PWR_VR',
 SEC='1',
 CDS_LIB='mstr_discrete',
 CDS_PART_NAME='CAP_0402-1.0UF,16V,10%,X6S,D97A',
 VOLTAGE='16V',
 PRIM_FILE='./archive_libs/mstr_discrete/cap/chips/chips.prt';

PART_NAME
 C7G41 'CAP_0402-0.22UF,16V,10%,X7R,A3A':
 ROOM='VDDQ_ABC_PWR_VR';

SECTION_NUMBER 1
 '@BASEBOARD_FAB2_LIB.BASEBOARD_FAB2(SCH_1):PAGE216_I72@MSTR_DISCRETE.CAP(CHIPS)':
 C_PATH='@baseboard_fab2_lib.baseboard_fab2(sch_1):page216_i72@mstr_discrete.cap~
(chips)',
 P_PATH='@baseboard_fab2_lib.baseboard_fab2(sch_1):page216_i72@mstr_discrete.cap~
(chips)',
 PATH='I72',
 DRAWING='@BASEBOARD_FAB2_LIB.BASEBOARD_FAB2(SCH_1):PAGE216',
 BOM_SS='NOPOP',
 TOLERANCE='10%',
 SEC_TYPE='0402',
 MATERIAL='X7R',
 PHYS_PAGE='216',
 XY='(50,200)',
 ROT='0',
 VER='1',
 VALUE='0.22UF',
 PACK_TYPE='0402',
 PART_NUMBER='A36096-155',
 LOCATION='C7G41',
 ROOM='VDDQ_ABC_PWR_VR',
 SEC='1',
 CDS_LIB='mstr_discrete',
 CDS_PART_NAME='CAP_0402-0.22UF,16V,10%,X7R,A3A',
 VOLTAGE='16V',
 PRIM_FILE='./archive_libs/mstr_discrete/cap/chips/chips.prt';

PART_NAME
 C7G42 'SC1U10V2KX-4-GP_SMD-BCG6-SC1U1A':;

SECTION_NUMBER 1
 '@BASEBOARD_FAB2_LIB.BASEBOARD_FAB2(SCH_1):PAGE216_I150@W_HDL.SC1U10V2KX-4-GP(CHIPS)':
 C_PATH='@baseboard_fab2_lib.baseboard_fab2(sch_1):page216_i150@w_hdl.\sc1u10v2k~
x-4-gp\(chips)',
 P_PATH='@baseboard_fab2_lib.baseboard_fab2(sch_1):page216_i150@w_hdl.\sc1u10v2k~
x-4-gp\(chips)',
 PATH='I150',
 DRAWING='@BASEBOARD_FAB2_LIB.BASEBOARD_FAB2(SCH_1):PAGE216',
 PACK_SIZE='0402',
 RATED='10V',
 ATTRIBUTE='1UF',
 BOM_SS='NOPOP',
 TOLERANCE='10%',
 SEC_TYPE='SMD-BCG6',
 PHYS_PAGE='216',
 XY='(-325,175)',
 ROT='0',
 VER='1',
 VALUE='SC1U10V2KX-4-GP',
 PACK_TYPE='SMD-BCG6',
 PART_NUMBER='78.10523.8FL',
 LOCATION='C7G42',
 SEC='1',
 CDS_LIB='w_hdl',
 CDS_PART_NAME='SC1U10V2KX-4-GP_SMD-BCG6-SC1U1A',
 PRIM_FILE='C:/<user>/w_hdl/sc1u10v2kx#2d4#2dgp/chips/chips.prt';

PART_NAME
 C7L1 'CAP_0805-100UF,4V,20%,X5R,6024A':
 GROUP='PWR_MLCC_CAP',
 ROOM='VDDQ_ABC_PWR_VR';

SECTION_NUMBER 1
 '@BASEBOARD_FAB2_LIB.BASEBOARD_FAB2(SCH_1):PAGE228_I314@MSTR_DISCRETE.CAP(CHIPS)':
 C_PATH='@baseboard_fab2_lib.baseboard_fab2(sch_1):page228_i314@mstr_discrete.ca~
p(chips)',
 P_PATH='@baseboard_fab2_lib.baseboard_fab2(sch_1):page228_i314@mstr_discrete.ca~
p(chips)',
 PATH='I314',
 DRAWING='@BASEBOARD_FAB2_LIB.BASEBOARD_FAB2(SCH_1):PAGE228',
 NEW_PN='078.1071T.M002',
 NEW_MATERIAL='X6S',
 BOM_SS='NOPOP',
 TOLERANCE='20%',
 SEC_TYPE='0805',
 MATERIAL='X5R',
 BOM_COST='MEM_VRD_PVDDQ_CD',
 PHYS_PAGE='228',
 XY='(2750,2825)',
 ROT='0',
 VER='1',
 VALUE='100UF',
 PACK_TYPE='0805',
 PART_NUMBER='602433-112',
 LOCATION='C7L1',
 ROOM='VDDQ_ABC_PWR_VR',
 GROUP='PWR_MLCC_CAP',
 SEC='1',
 CDS_LIB='mstr_discrete',
 CDS_PART_NAME='CAP_0805-100UF,4V,20%,X5R,6024A',
 VOLTAGE='4V',
 PRIM_FILE='./archive_libs/mstr_discrete/cap/chips/chips.prt';

PART_NAME
 C7L2 'CAP_0603LF-10UF,4V,20%,X6S,E15A':
 GROUP='PWR_MLCC_CAP',
 ROOM='PVPP_KLM_VR';

SECTION_NUMBER 1
 '@BASEBOARD_FAB2_LIB.BASEBOARD_FAB2(SCH_1):PAGE234_I88@MSTR_DISCRETE.CAP(CHIPS)':
 C_PATH='@baseboard_fab2_lib.baseboard_fab2(sch_1):page234_i88@mstr_discrete.cap~
(chips)',
 P_PATH='@baseboard_fab2_lib.baseboard_fab2(sch_1):page234_i88@mstr_discrete.cap~
(chips)',
 PATH='I88',
 DRAWING='@BASEBOARD_FAB2_LIB.BASEBOARD_FAB2(SCH_1):PAGE234',
 TOLERANCE='20%',
 MATERIAL='X6S',
 BOM_COST='MEM_VRD_PVPP_AB',
 PHYS_PAGE='234',
 XY='(-5950,725)',
 ROT='0',
 VER='1',
 VALUE='10UF',
 PACK_TYPE='0603LF',
 PART_NUMBER='E15431-001',
 LOCATION='C7L2',
 ROOM='PVPP_KLM_VR',
 GROUP='PWR_MLCC_CAP',
 CDS_LIB='mstr_discrete',
 CDS_PART_NAME='CAP_0603LF-10UF,4V,20%,X6S,E15A',
 VOLTAGE='4V',
 PRIM_FILE='./archive_libs/mstr_discrete/cap/chips/chips.prt';

PART_NAME
 C7L3 'CAP_0603LF-10UF,4V,20%,X6S,E15A':
 GROUP='PWR_MLCC_CAP',
 ROOM='PVPP_KLM_VR';

SECTION_NUMBER 1
 '@BASEBOARD_FAB2_LIB.BASEBOARD_FAB2(SCH_1):PAGE234_I87@MSTR_DISCRETE.CAP(CHIPS)':
 C_PATH='@baseboard_fab2_lib.baseboard_fab2(sch_1):page234_i87@mstr_discrete.cap~
(chips)',
 P_PATH='@baseboard_fab2_lib.baseboard_fab2(sch_1):page234_i87@mstr_discrete.cap~
(chips)',
 PATH='I87',
 DRAWING='@BASEBOARD_FAB2_LIB.BASEBOARD_FAB2(SCH_1):PAGE234',
 TOLERANCE='20%',
 MATERIAL='X6S',
 BOM_COST='MEM_VRD_PVPP_AB',
 PHYS_PAGE='234',
 XY='(-5675,700)',
 ROT='0',
 VER='1',
 VALUE='10UF',
 PACK_TYPE='0603LF',
 PART_NUMBER='E15431-001',
 LOCATION='C7L3',
 ROOM='PVPP_KLM_VR',
 GROUP='PWR_MLCC_CAP',
 CDS_LIB='mstr_discrete',
 CDS_PART_NAME='CAP_0603LF-10UF,4V,20%,X6S,E15A',
 VOLTAGE='4V',
 PRIM_FILE='./archive_libs/mstr_discrete/cap/chips/chips.prt';

PART_NAME
 C7L4 'CAP_A_0603V-47UF,4V,20%,X5R,60A':
 GROUP='PWR_MLCC_CAP';

SECTION_NUMBER 1
 '@BASEBOARD_FAB2_LIB.BASEBOARD_FAB2(SCH_1):PAGE228_I288@DEV_DISCRETE.CAP_A(CHIPS)':
 C_PATH='@baseboard_fab2_lib.baseboard_fab2(sch_1):page228_i288@dev_discrete.cap~
_a(chips)',
 P_PATH='@baseboard_fab2_lib.baseboard_fab2(sch_1):page228_i288@dev_discrete.cap~
_a(chips)',
 PATH='I288',
 DRAWING='@BASEBOARD_FAB2_LIB.BASEBOARD_FAB2(SCH_1):PAGE228',
 BOM_SS='E15431-004',
 TOLERANCE='20%',
 SEC_TYPE='0603V',
 MATERIAL='X5R',
 PHYS_PAGE='228',
 XY='(-1075,-775)',
 ROT='0',
 VER='1',
 VALUE='47UF',
 PACK_TYPE='0603V',
 PART_NUMBER='602433-106',
 LOCATION='C7L4',
 GROUP='PWR_MLCC_CAP',
 SEC='1',
 CDS_LIB='dev_discrete',
 CDS_PART_NAME='CAP_A_0603V-47UF,4V,20%,X5R,60A',
 VOLTAGE='4V',
 PRIM_FILE='./archive_libs/discrete/cap_a/chips/chips.prt';

PART_NAME
 C7L5 'CAP_A_0603V-47UF,4V,20%,X5R,60A':
 GROUP='PWR_MLCC_CAP';

SECTION_NUMBER 1
 '@BASEBOARD_FAB2_LIB.BASEBOARD_FAB2(SCH_1):PAGE228_I268@DEV_DISCRETE.CAP_A(CHIPS)':
 C_PATH='@baseboard_fab2_lib.baseboard_fab2(sch_1):page228_i268@dev_discrete.cap~
_a(chips)',
 P_PATH='@baseboard_fab2_lib.baseboard_fab2(sch_1):page228_i268@dev_discrete.cap~
_a(chips)',
 PATH='I268',
 DRAWING='@BASEBOARD_FAB2_LIB.BASEBOARD_FAB2(SCH_1):PAGE228',
 BOM_SS='E15431-004',
 TOLERANCE='20%',
 SEC_TYPE='0603V',
 MATERIAL='X5R',
 PHYS_PAGE='228',
 XY='(-2250,-75)',
 ROT='0',
 VER='1',
 VALUE='47UF',
 PACK_TYPE='0603V',
 PART_NUMBER='602433-106',
 LOCATION='C7L5',
 GROUP='PWR_MLCC_CAP',
 SEC='1',
 CDS_LIB='dev_discrete',
 CDS_PART_NAME='CAP_A_0603V-47UF,4V,20%,X5R,60A',
 VOLTAGE='4V',
 PRIM_FILE='./archive_libs/discrete/cap_a/chips/chips.prt';

PART_NAME
 C7L6 'CAP_0603LF-10UF,4V,20%,X6S,E15A':
 GROUP='PWR_MLCC_CAP',
 ROOM='PVPP_KLM_VR';

SECTION_NUMBER 1
 '@BASEBOARD_FAB2_LIB.BASEBOARD_FAB2(SCH_1):PAGE234_I90@MSTR_DISCRETE.CAP(CHIPS)':
 C_PATH='@baseboard_fab2_lib.baseboard_fab2(sch_1):page234_i90@mstr_discrete.cap~
(chips)',
 P_PATH='@baseboard_fab2_lib.baseboard_fab2(sch_1):page234_i90@mstr_discrete.cap~
(chips)',
 PATH='I90',
 DRAWING='@BASEBOARD_FAB2_LIB.BASEBOARD_FAB2(SCH_1):PAGE234',
 TOLERANCE='20%',
 MATERIAL='X6S',
 BOM_COST='MEM_VRD_PVPP_AB',
 PHYS_PAGE='234',
 XY='(-6550,725)',
 ROT='0',
 VER='1',
 VALUE='10UF',
 PACK_TYPE='0603LF',
 PART_NUMBER='E15431-001',
 LOCATION='C7L6',
 ROOM='PVPP_KLM_VR',
 GROUP='PWR_MLCC_CAP',
 CDS_LIB='mstr_discrete',
 CDS_PART_NAME='CAP_0603LF-10UF,4V,20%,X6S,E15A',
 VOLTAGE='4V',
 PRIM_FILE='./archive_libs/mstr_discrete/cap/chips/chips.prt';

PART_NAME
 C7L7 'CAP_0603LF-10UF,4V,20%,X6S,E15A':
 GROUP='PWR_MLCC_CAP',
 ROOM='PVPP_KLM_VR';

SECTION_NUMBER 1
 '@BASEBOARD_FAB2_LIB.BASEBOARD_FAB2(SCH_1):PAGE234_I89@MSTR_DISCRETE.CAP(CHIPS)':
 C_PATH='@baseboard_fab2_lib.baseboard_fab2(sch_1):page234_i89@mstr_discrete.cap~
(chips)',
 P_PATH='@baseboard_fab2_lib.baseboard_fab2(sch_1):page234_i89@mstr_discrete.cap~
(chips)',
 PATH='I89',
 DRAWING='@BASEBOARD_FAB2_LIB.BASEBOARD_FAB2(SCH_1):PAGE234',
 TOLERANCE='20%',
 MATERIAL='X6S',
 BOM_COST='MEM_VRD_PVPP_AB',
 PHYS_PAGE='234',
 XY='(-6250,725)',
 ROT='0',
 VER='1',
 VALUE='10UF',
 PACK_TYPE='0603LF',
 PART_NUMBER='E15431-001',
 LOCATION='C7L7',
 ROOM='PVPP_KLM_VR',
 GROUP='PWR_MLCC_CAP',
 CDS_LIB='mstr_discrete',
 CDS_PART_NAME='CAP_0603LF-10UF,4V,20%,X6S,E15A',
 VOLTAGE='4V',
 PRIM_FILE='./archive_libs/mstr_discrete/cap/chips/chips.prt';

PART_NAME
 C7M1 'CAP_A_0603V-47UF,4V,20%,X5R,60A':
 GROUP='PWR_MLCC_CAP';

SECTION_NUMBER 1
 '@BASEBOARD_FAB2_LIB.BASEBOARD_FAB2(SCH_1):PAGE228_I295@DEV_DISCRETE.CAP_A(CHIPS)':
 C_PATH='@baseboard_fab2_lib.baseboard_fab2(sch_1):page228_i295@dev_discrete.cap~
_a(chips)',
 P_PATH='@baseboard_fab2_lib.baseboard_fab2(sch_1):page228_i295@dev_discrete.cap~
_a(chips)',
 PATH='I295',
 DRAWING='@BASEBOARD_FAB2_LIB.BASEBOARD_FAB2(SCH_1):PAGE228',
 BOM_SS='E15431-004',
 TOLERANCE='20%',
 SEC_TYPE='0603V',
 MATERIAL='X5R',
 PHYS_PAGE='228',
 XY='(1000,-775)',
 ROT='0',
 VER='1',
 VALUE='47UF',
 PACK_TYPE='0603V',
 PART_NUMBER='602433-106',
 LOCATION='C7M1',
 GROUP='PWR_MLCC_CAP',
 SEC='1',
 CDS_LIB='dev_discrete',
 CDS_PART_NAME='CAP_A_0603V-47UF,4V,20%,X5R,60A',
 VOLTAGE='4V',
 PRIM_FILE='./archive_libs/discrete/cap_a/chips/chips.prt';

PART_NAME
 C7M2 'CAP_A_0603V-47UF,4V,20%,X5R,60A':
 GROUP='PWR_MLCC_CAP';

SECTION_NUMBER 1
 '@BASEBOARD_FAB2_LIB.BASEBOARD_FAB2(SCH_1):PAGE228_I294@DEV_DISCRETE.CAP_A(CHIPS)':
 C_PATH='@baseboard_fab2_lib.baseboard_fab2(sch_1):page228_i294@dev_discrete.cap~
_a(chips)',
 P_PATH='@baseboard_fab2_lib.baseboard_fab2(sch_1):page228_i294@dev_discrete.cap~
_a(chips)',
 PATH='I294',
 DRAWING='@BASEBOARD_FAB2_LIB.BASEBOARD_FAB2(SCH_1):PAGE228',
 BOM_SS='E15431-004',
 TOLERANCE='20%',
 SEC_TYPE='0603V',
 MATERIAL='X5R',
 PHYS_PAGE='228',
 XY='(725,-775)',
 ROT='0',
 VER='1',
 VALUE='47UF',
 PACK_TYPE='0603V',
 PART_NUMBER='602433-106',
 LOCATION='C7M2',
 GROUP='PWR_MLCC_CAP',
 SEC='1',
 CDS_LIB='dev_discrete',
 CDS_PART_NAME='CAP_A_0603V-47UF,4V,20%,X5R,60A',
 VOLTAGE='4V',
 PRIM_FILE='./archive_libs/discrete/cap_a/chips/chips.prt';

PART_NAME
 C7M3 'CAP_0603LF-10UF,4V,20%,X6S,E15A':
 GROUP='PWR_MLCC_CAP',
 ROOM='PVPP_KLM_VR';

SECTION_NUMBER 1
 '@BASEBOARD_FAB2_LIB.BASEBOARD_FAB2(SCH_1):PAGE234_I92@MSTR_DISCRETE.CAP(CHIPS)':
 C_PATH='@baseboard_fab2_lib.baseboard_fab2(sch_1):page234_i92@mstr_discrete.cap~
(chips)',
 P_PATH='@baseboard_fab2_lib.baseboard_fab2(sch_1):page234_i92@mstr_discrete.cap~
(chips)',
 PATH='I92',
 DRAWING='@BASEBOARD_FAB2_LIB.BASEBOARD_FAB2(SCH_1):PAGE234',
 TOLERANCE='20%',
 MATERIAL='X6S',
 BOM_COST='MEM_VRD_PVPP_AB',
 PHYS_PAGE='234',
 XY='(-7125,725)',
 ROT='0',
 VER='1',
 VALUE='10UF',
 PACK_TYPE='0603LF',
 PART_NUMBER='E15431-001',
 LOCATION='C7M3',
 ROOM='PVPP_KLM_VR',
 GROUP='PWR_MLCC_CAP',
 CDS_LIB='mstr_discrete',
 CDS_PART_NAME='CAP_0603LF-10UF,4V,20%,X6S,E15A',
 VOLTAGE='4V',
 PRIM_FILE='./archive_libs/mstr_discrete/cap/chips/chips.prt';

PART_NAME
 C7M4 'CAP_0603LF-10UF,4V,20%,X6S,E15A':
 GROUP='PWR_MLCC_CAP',
 ROOM='PVPP_KLM_VR';

SECTION_NUMBER 1
 '@BASEBOARD_FAB2_LIB.BASEBOARD_FAB2(SCH_1):PAGE234_I91@MSTR_DISCRETE.CAP(CHIPS)':
 C_PATH='@baseboard_fab2_lib.baseboard_fab2(sch_1):page234_i91@mstr_discrete.cap~
(chips)',
 P_PATH='@baseboard_fab2_lib.baseboard_fab2(sch_1):page234_i91@mstr_discrete.cap~
(chips)',
 PATH='I91',
 DRAWING='@BASEBOARD_FAB2_LIB.BASEBOARD_FAB2(SCH_1):PAGE234',
 TOLERANCE='20%',
 MATERIAL='X6S',
 BOM_COST='MEM_VRD_PVPP_AB',
 PHYS_PAGE='234',
 XY='(-6825,725)',
 ROT='0',
 VER='1',
 VALUE='10UF',
 PACK_TYPE='0603LF',
 PART_NUMBER='E15431-001',
 LOCATION='C7M4',
 ROOM='PVPP_KLM_VR',
 GROUP='PWR_MLCC_CAP',
 CDS_LIB='mstr_discrete',
 CDS_PART_NAME='CAP_0603LF-10UF,4V,20%,X6S,E15A',
 VOLTAGE='4V',
 PRIM_FILE='./archive_libs/mstr_discrete/cap/chips/chips.prt';

PART_NAME
 C7M5 'CAP_A_0603V-47UF,4V,20%,X5R,60A':
 GROUP='PWR_MLCC_CAP';

SECTION_NUMBER 1
 '@BASEBOARD_FAB2_LIB.BASEBOARD_FAB2(SCH_1):PAGE228_I202@DEV_DISCRETE.CAP_A(CHIPS)':
 C_PATH='@baseboard_fab2_lib.baseboard_fab2(sch_1):page228_i202@dev_discrete.cap~
_a(chips)',
 P_PATH='@baseboard_fab2_lib.baseboard_fab2(sch_1):page228_i202@dev_discrete.cap~
_a(chips)',
 PATH='I202',
 DRAWING='@BASEBOARD_FAB2_LIB.BASEBOARD_FAB2(SCH_1):PAGE228',
 BOM_SS='NOPOP',
 TOLERANCE='20%',
 SEC_TYPE='0603V',
 MATERIAL='X5R',
 PHYS_PAGE='228',
 XY='(2875,1425)',
 ROT='0',
 VER='1',
 VALUE='47UF',
 PACK_TYPE='0603V',
 PART_NUMBER='602433-106',
 LOCATION='C7M5',
 GROUP='PWR_MLCC_CAP',
 SEC='1',
 CDS_LIB='dev_discrete',
 CDS_PART_NAME='CAP_A_0603V-47UF,4V,20%,X5R,60A',
 VOLTAGE='4V',
 PRIM_FILE='./archive_libs/discrete/cap_a/chips/chips.prt';

PART_NAME
 C7M6 'CAPP_3018-68UF,16V,20%,TANT,72A':;

SECTION_NUMBER 1
 '@BASEBOARD_FAB2_LIB.BASEBOARD_FAB2(SCH_1):PAGE195_I108@MSTR_DISCRETE.CAPP(CHIPS)':
 C_PATH='@baseboard_fab2_lib.baseboard_fab2(sch_1):page195_i108@mstr_discrete.ca~
pp(chips)',
 P_PATH='@baseboard_fab2_lib.baseboard_fab2(sch_1):page195_i108@mstr_discrete.ca~
pp(chips)',
 PATH='I108',
 DRAWING='@BASEBOARD_FAB2_LIB.BASEBOARD_FAB2(SCH_1):PAGE195',
 TOLERANCE='20%',
 SEC_TYPE='3018',
 MATERIAL='TANT',
 PHYS_PAGE='195',
 XY='(-6150,1950)',
 ROT='0',
 VER='1',
 VALUE='68UF',
 PACK_TYPE='3018',
 PART_NUMBER='724613-112',
 LOCATION='C7M6',
 SEC='1',
 CDS_LIB='mstr_discrete',
 CDS_PART_NAME='CAPP_3018-68UF,16V,20%,TANT,72A',
 VOLTAGE='16V',
 PRIM_FILE='./archive_libs/mstr_discrete/capp/chips/chips.prt';

PART_NAME
 C7P1 'CAP_0805-100UF,4V,20%,X5R,6024A':
 GROUP='PWR_MLCC_CAP',
 ROOM='VDDQ_ABC_PWR_VR';

SECTION_NUMBER 1
 '@BASEBOARD_FAB2_LIB.BASEBOARD_FAB2(SCH_1):PAGE228_I308@MSTR_DISCRETE.CAP(CHIPS)':
 C_PATH='@baseboard_fab2_lib.baseboard_fab2(sch_1):page228_i308@mstr_discrete.ca~
p(chips)',
 P_PATH='@baseboard_fab2_lib.baseboard_fab2(sch_1):page228_i308@mstr_discrete.ca~
p(chips)',
 PATH='I308',
 DRAWING='@BASEBOARD_FAB2_LIB.BASEBOARD_FAB2(SCH_1):PAGE228',
 NEW_PN='078.1071T.M002',
 NEW_MATERIAL='X6S',
 BOM_SS='NOPOP',
 TOLERANCE='20%',
 SEC_TYPE='0805',
 MATERIAL='X5R',
 BOM_COST='MEM_VRD_PVDDQ_CD',
 PHYS_PAGE='228',
 XY='(525,725)',
 ROT='0',
 VER='1',
 VALUE='100UF',
 PACK_TYPE='0805',
 PART_NUMBER='602433-112',
 LOCATION='C7P1',
 ROOM='VDDQ_ABC_PWR_VR',
 GROUP='PWR_MLCC_CAP',
 SEC='1',
 CDS_LIB='mstr_discrete',
 CDS_PART_NAME='CAP_0805-100UF,4V,20%,X5R,6024A',
 VOLTAGE='4V',
 PRIM_FILE='./archive_libs/mstr_discrete/cap/chips/chips.prt';

PART_NAME
 C7P2 'CAP_0805-100UF,4V,20%,X5R,6024A':
 GROUP='PWR_MLCC_CAP',
 ROOM='VDDQ_ABC_PWR_VR';

SECTION_NUMBER 1
 '@BASEBOARD_FAB2_LIB.BASEBOARD_FAB2(SCH_1):PAGE228_I305@MSTR_DISCRETE.CAP(CHIPS)':
 C_PATH='@baseboard_fab2_lib.baseboard_fab2(sch_1):page228_i305@mstr_discrete.ca~
p(chips)',
 P_PATH='@baseboard_fab2_lib.baseboard_fab2(sch_1):page228_i305@mstr_discrete.ca~
p(chips)',
 PATH='I305',
 DRAWING='@BASEBOARD_FAB2_LIB.BASEBOARD_FAB2(SCH_1):PAGE228',
 NEW_PN='078.1071T.M002',
 NEW_MATERIAL='X6S',
 BOM_SS='NOPOP',
 TOLERANCE='20%',
 SEC_TYPE='0805',
 MATERIAL='X5R',
 BOM_COST='MEM_VRD_PVDDQ_CD',
 PHYS_PAGE='228',
 XY='(1625,2775)',
 ROT='0',
 VER='1',
 VALUE='100UF',
 PACK_TYPE='0805',
 PART_NUMBER='602433-112',
 LOCATION='C7P2',
 ROOM='VDDQ_ABC_PWR_VR',
 GROUP='PWR_MLCC_CAP',
 SEC='1',
 CDS_LIB='mstr_discrete',
 CDS_PART_NAME='CAP_0805-100UF,4V,20%,X5R,6024A',
 VOLTAGE='4V',
 PRIM_FILE='./archive_libs/mstr_discrete/cap/chips/chips.prt';

PART_NAME
 C7P3 'CAP_0805-47UF,4V,20%,X6S,C9533A':
 GROUP='PWR_MLCC_CAP',
 ROOM='PVCCIN_CPU1_DECAP_VR';

SECTION_NUMBER 1
 '@BASEBOARD_FAB2_LIB.BASEBOARD_FAB2(SCH_1):PAGE76_I52@MSTR_DISCRETE.CAP(CHIPS)':
 C_PATH='@baseboard_fab2_lib.baseboard_fab2(sch_1):page76_i52@mstr_discrete.cap(~
chips)',
 P_PATH='@baseboard_fab2_lib.baseboard_fab2(sch_1):page76_i52@mstr_discrete.cap(~
chips)',
 PATH='I52',
 DRAWING='@BASEBOARD_FAB2_LIB.BASEBOARD_FAB2(SCH_1):PAGE76',
 TOLERANCE='20%',
 MATERIAL='X6S',
 BOM_COST='PROC',
 PHYS_PAGE='76',
 XY='(-3300,1150)',
 ROT='0',
 VER='1',
 VALUE='47UF',
 PACK_TYPE='0805',
 PART_NUMBER='C95333-006',
 LOCATION='C7P3',
 ROOM='PVCCIN_CPU1_DECAP_VR',
 GROUP='PWR_MLCC_CAP',
 CDS_LIB='mstr_discrete',
 CDS_PART_NAME='CAP_0805-47UF,4V,20%,X6S,C9533A',
 VOLTAGE='4V',
 PRIM_FILE='./archive_libs/mstr_discrete/cap/chips/chips.prt';

PART_NAME
 C7P4 'CAP_0805-100UF,4V,20%,X5R,6024A':
 GROUP='PWR_MCP_CAP',
 ROOM='VDDQ_ABC_PWR_VR';

SECTION_NUMBER 1
 '@BASEBOARD_FAB2_LIB.BASEBOARD_FAB2(SCH_1):PAGE76_I271@MSTR_DISCRETE.CAP(CHIPS)':
 C_PATH='@baseboard_fab2_lib.baseboard_fab2(sch_1):page76_i271@mstr_discrete.cap~
(chips)',
 P_PATH='@baseboard_fab2_lib.baseboard_fab2(sch_1):page76_i271@mstr_discrete.cap~
(chips)',
 PATH='I271',
 DRAWING='@BASEBOARD_FAB2_LIB.BASEBOARD_FAB2(SCH_1):PAGE76',
 NEW_PN='078.1071T.M002',
 NEW_MATERIAL='X6S',
 TOLERANCE='20%',
 SEC_TYPE='0805',
 MATERIAL='X5R',
 BOM_COST='MEM_VRD_PVDDQ_CD',
 PHYS_PAGE='76',
 XY='(-1600,2200)',
 ROT='0',
 VER='1',
 VALUE='100UF',
 PACK_TYPE='0805',
 PART_NUMBER='602433-112',
 LOCATION='C7P4',
 ROOM='VDDQ_ABC_PWR_VR',
 GROUP='PWR_MCP_CAP',
 SEC='1',
 CDS_LIB='mstr_discrete',
 CDS_PART_NAME='CAP_0805-100UF,4V,20%,X5R,6024A',
 VOLTAGE='4V',
 PRIM_FILE='./archive_libs/mstr_discrete/cap/chips/chips.prt';

PART_NAME
 C7P5 'CAP_0805-100UF,4V,20%,X5R,6024A':
 GROUP='PWR_MCP_CAP',
 ROOM='VDDQ_ABC_PWR_VR';

SECTION_NUMBER 1
 '@BASEBOARD_FAB2_LIB.BASEBOARD_FAB2(SCH_1):PAGE76_I259@MSTR_DISCRETE.CAP(CHIPS)':
 C_PATH='@baseboard_fab2_lib.baseboard_fab2(sch_1):page76_i259@mstr_discrete.cap~
(chips)',
 P_PATH='@baseboard_fab2_lib.baseboard_fab2(sch_1):page76_i259@mstr_discrete.cap~
(chips)',
 PATH='I259',
 DRAWING='@BASEBOARD_FAB2_LIB.BASEBOARD_FAB2(SCH_1):PAGE76',
 NEW_PN='078.1071T.M002',
 NEW_MATERIAL='X6S',
 TOLERANCE='20%',
 SEC_TYPE='0805',
 MATERIAL='X5R',
 BOM_COST='MEM_VRD_PVDDQ_CD',
 PHYS_PAGE='76',
 XY='(-4350,2200)',
 ROT='0',
 VER='1',
 VALUE='100UF',
 PACK_TYPE='0805',
 PART_NUMBER='602433-112',
 LOCATION='C7P5',
 ROOM='VDDQ_ABC_PWR_VR',
 GROUP='PWR_MCP_CAP',
 SEC='1',
 CDS_LIB='mstr_discrete',
 CDS_PART_NAME='CAP_0805-100UF,4V,20%,X5R,6024A',
 VOLTAGE='4V',
 PRIM_FILE='./archive_libs/mstr_discrete/cap/chips/chips.prt';

PART_NAME
 C7P6 'CAP_0805-100UF,4V,20%,X5R,6024A':
 GROUP='PWR_MCP_CAP',
 ROOM='VDDQ_ABC_PWR_VR';

SECTION_NUMBER 1
 '@BASEBOARD_FAB2_LIB.BASEBOARD_FAB2(SCH_1):PAGE76_I268@MSTR_DISCRETE.CAP(CHIPS)':
 C_PATH='@baseboard_fab2_lib.baseboard_fab2(sch_1):page76_i268@mstr_discrete.cap~
(chips)',
 P_PATH='@baseboard_fab2_lib.baseboard_fab2(sch_1):page76_i268@mstr_discrete.cap~
(chips)',
 PATH='I268',
 DRAWING='@BASEBOARD_FAB2_LIB.BASEBOARD_FAB2(SCH_1):PAGE76',
 NEW_PN='078.1071T.M002',
 NEW_MATERIAL='X6S',
 TOLERANCE='20%',
 SEC_TYPE='0805',
 MATERIAL='X5R',
 BOM_COST='MEM_VRD_PVDDQ_CD',
 PHYS_PAGE='76',
 XY='(-1850,2200)',
 ROT='0',
 VER='1',
 VALUE='100UF',
 PACK_TYPE='0805',
 PART_NUMBER='602433-112',
 LOCATION='C7P6',
 ROOM='VDDQ_ABC_PWR_VR',
 GROUP='PWR_MCP_CAP',
 SEC='1',
 CDS_LIB='mstr_discrete',
 CDS_PART_NAME='CAP_0805-100UF,4V,20%,X5R,6024A',
 VOLTAGE='4V',
 PRIM_FILE='./archive_libs/mstr_discrete/cap/chips/chips.prt';

PART_NAME
 C7P7 'CAP_0805-100UF,4V,20%,X5R,6024A':
 GROUP='PWR_MCP_CAP',
 ROOM='VDDQ_ABC_PWR_VR';

SECTION_NUMBER 1
 '@BASEBOARD_FAB2_LIB.BASEBOARD_FAB2(SCH_1):PAGE76_I267@MSTR_DISCRETE.CAP(CHIPS)':
 C_PATH='@baseboard_fab2_lib.baseboard_fab2(sch_1):page76_i267@mstr_discrete.cap~
(chips)',
 P_PATH='@baseboard_fab2_lib.baseboard_fab2(sch_1):page76_i267@mstr_discrete.cap~
(chips)',
 PATH='I267',
 DRAWING='@BASEBOARD_FAB2_LIB.BASEBOARD_FAB2(SCH_1):PAGE76',
 NEW_PN='078.1071T.M002',
 NEW_MATERIAL='X6S',
 TOLERANCE='20%',
 SEC_TYPE='0805',
 MATERIAL='X5R',
 BOM_COST='MEM_VRD_PVDDQ_CD',
 PHYS_PAGE='76',
 XY='(-2600,2200)',
 ROT='0',
 VER='1',
 VALUE='100UF',
 PACK_TYPE='0805',
 PART_NUMBER='602433-112',
 LOCATION='C7P7',
 ROOM='VDDQ_ABC_PWR_VR',
 GROUP='PWR_MCP_CAP',
 SEC='1',
 CDS_LIB='mstr_discrete',
 CDS_PART_NAME='CAP_0805-100UF,4V,20%,X5R,6024A',
 VOLTAGE='4V',
 PRIM_FILE='./archive_libs/mstr_discrete/cap/chips/chips.prt';

PART_NAME
 C7P8 'CAP_0805-100UF,4V,20%,X5R,6024A':
 GROUP='PWR_MCP_CAP',
 ROOM='VDDQ_ABC_PWR_VR';

SECTION_NUMBER 1
 '@BASEBOARD_FAB2_LIB.BASEBOARD_FAB2(SCH_1):PAGE76_I265@MSTR_DISCRETE.CAP(CHIPS)':
 C_PATH='@baseboard_fab2_lib.baseboard_fab2(sch_1):page76_i265@mstr_discrete.cap~
(chips)',
 P_PATH='@baseboard_fab2_lib.baseboard_fab2(sch_1):page76_i265@mstr_discrete.cap~
(chips)',
 PATH='I265',
 DRAWING='@BASEBOARD_FAB2_LIB.BASEBOARD_FAB2(SCH_1):PAGE76',
 NEW_PN='078.1071T.M002',
 NEW_MATERIAL='X6S',
 TOLERANCE='20%',
 SEC_TYPE='0805',
 MATERIAL='X5R',
 BOM_COST='MEM_VRD_PVDDQ_CD',
 PHYS_PAGE='76',
 XY='(-3100,2200)',
 ROT='0',
 VER='1',
 VALUE='100UF',
 PACK_TYPE='0805',
 PART_NUMBER='602433-112',
 LOCATION='C7P8',
 ROOM='VDDQ_ABC_PWR_VR',
 GROUP='PWR_MCP_CAP',
 SEC='1',
 CDS_LIB='mstr_discrete',
 CDS_PART_NAME='CAP_0805-100UF,4V,20%,X5R,6024A',
 VOLTAGE='4V',
 PRIM_FILE='./archive_libs/mstr_discrete/cap/chips/chips.prt';

PART_NAME
 C7P9 'CAP_0805-100UF,4V,20%,X5R,6024A':
 GROUP='PWR_MCP_CAP',
 ROOM='VDDQ_ABC_PWR_VR';

SECTION_NUMBER 1
 '@BASEBOARD_FAB2_LIB.BASEBOARD_FAB2(SCH_1):PAGE76_I258@MSTR_DISCRETE.CAP(CHIPS)':
 C_PATH='@baseboard_fab2_lib.baseboard_fab2(sch_1):page76_i258@mstr_discrete.cap~
(chips)',
 P_PATH='@baseboard_fab2_lib.baseboard_fab2(sch_1):page76_i258@mstr_discrete.cap~
(chips)',
 PATH='I258',
 DRAWING='@BASEBOARD_FAB2_LIB.BASEBOARD_FAB2(SCH_1):PAGE76',
 NEW_PN='078.1071T.M002',
 NEW_MATERIAL='X6S',
 TOLERANCE='20%',
 SEC_TYPE='0805',
 MATERIAL='X5R',
 BOM_COST='MEM_VRD_PVDDQ_CD',
 PHYS_PAGE='76',
 XY='(-4600,2200)',
 ROT='0',
 VER='1',
 VALUE='100UF',
 PACK_TYPE='0805',
 PART_NUMBER='602433-112',
 LOCATION='C7P9',
 ROOM='VDDQ_ABC_PWR_VR',
 GROUP='PWR_MCP_CAP',
 SEC='1',
 CDS_LIB='mstr_discrete',
 CDS_PART_NAME='CAP_0805-100UF,4V,20%,X5R,6024A',
 VOLTAGE='4V',
 PRIM_FILE='./archive_libs/mstr_discrete/cap/chips/chips.prt';

PART_NAME
 C7P10 'CAP_0805-100UF,4V,20%,X5R,6024A':
 GROUP='PWR_MCP_CAP',
 ROOM='VDDQ_ABC_PWR_VR';

SECTION_NUMBER 1
 '@BASEBOARD_FAB2_LIB.BASEBOARD_FAB2(SCH_1):PAGE76_I266@MSTR_DISCRETE.CAP(CHIPS)':
 C_PATH='@baseboard_fab2_lib.baseboard_fab2(sch_1):page76_i266@mstr_discrete.cap~
(chips)',
 P_PATH='@baseboard_fab2_lib.baseboard_fab2(sch_1):page76_i266@mstr_discrete.cap~
(chips)',
 PATH='I266',
 DRAWING='@BASEBOARD_FAB2_LIB.BASEBOARD_FAB2(SCH_1):PAGE76',
 NEW_PN='078.1071T.M002',
 NEW_MATERIAL='X6S',
 TOLERANCE='20%',
 SEC_TYPE='0805',
 MATERIAL='X5R',
 BOM_COST='MEM_VRD_PVDDQ_CD',
 PHYS_PAGE='76',
 XY='(-2350,2200)',
 ROT='0',
 VER='1',
 VALUE='100UF',
 PACK_TYPE='0805',
 PART_NUMBER='602433-112',
 LOCATION='C7P10',
 ROOM='VDDQ_ABC_PWR_VR',
 GROUP='PWR_MCP_CAP',
 SEC='1',
 CDS_LIB='mstr_discrete',
 CDS_PART_NAME='CAP_0805-100UF,4V,20%,X5R,6024A',
 VOLTAGE='4V',
 PRIM_FILE='./archive_libs/mstr_discrete/cap/chips/chips.prt';

PART_NAME
 C7P11 'CAP_0805-100UF,4V,20%,X5R,6024A':
 GROUP='PWR_MCP_CAP',
 ROOM='VDDQ_ABC_PWR_VR';

SECTION_NUMBER 1
 '@BASEBOARD_FAB2_LIB.BASEBOARD_FAB2(SCH_1):PAGE76_I262@MSTR_DISCRETE.CAP(CHIPS)':
 C_PATH='@baseboard_fab2_lib.baseboard_fab2(sch_1):page76_i262@mstr_discrete.cap~
(chips)',
 P_PATH='@baseboard_fab2_lib.baseboard_fab2(sch_1):page76_i262@mstr_discrete.cap~
(chips)',
 PATH='I262',
 DRAWING='@BASEBOARD_FAB2_LIB.BASEBOARD_FAB2(SCH_1):PAGE76',
 NEW_PN='078.1071T.M002',
 NEW_MATERIAL='X6S',
 TOLERANCE='20%',
 SEC_TYPE='0805',
 MATERIAL='X5R',
 BOM_COST='MEM_VRD_PVDDQ_CD',
 PHYS_PAGE='76',
 XY='(-3350,2200)',
 ROT='0',
 VER='1',
 VALUE='100UF',
 PACK_TYPE='0805',
 PART_NUMBER='602433-112',
 LOCATION='C7P11',
 ROOM='VDDQ_ABC_PWR_VR',
 GROUP='PWR_MCP_CAP',
 SEC='1',
 CDS_LIB='mstr_discrete',
 CDS_PART_NAME='CAP_0805-100UF,4V,20%,X5R,6024A',
 VOLTAGE='4V',
 PRIM_FILE='./archive_libs/mstr_discrete/cap/chips/chips.prt';

PART_NAME
 C7P12 'CAP_A_0603V-22.0UF,4V,20%,X6S,A':
 GROUP='PWR_MLCC_CAP',
 ROOM='PVCCIN_CPU1_DECAP_VR';

SECTION_NUMBER 1
 '@BASEBOARD_FAB2_LIB.BASEBOARD_FAB2(SCH_1):PAGE76_I179@DEV_DISCRETE.CAP_A(CHIPS)':
 C_PATH='@baseboard_fab2_lib.baseboard_fab2(sch_1):page76_i179@dev_discrete.cap_~
a(chips)',
 P_PATH='@baseboard_fab2_lib.baseboard_fab2(sch_1):page76_i179@dev_discrete.cap_~
a(chips)',
 PATH='I179',
 DRAWING='@BASEBOARD_FAB2_LIB.BASEBOARD_FAB2(SCH_1):PAGE76',
 TOLERANCE='20%',
 MATERIAL='X6S',
 BOM_COST='PROC',
 PHYS_PAGE='76',
 XY='(-2400,1150)',
 ROT='0',
 VER='1',
 VALUE='22.0UF',
 PACK_TYPE='0603V',
 PART_NUMBER='E15431-004',
 LOCATION='C7P12',
 ROOM='PVCCIN_CPU1_DECAP_VR',
 GROUP='PWR_MLCC_CAP',
 CDS_LIB='dev_discrete',
 CDS_PART_NAME='CAP_A_0603V-22.0UF,4V,20%,X6S,A',
 VOLTAGE='4V',
 PRIM_FILE='./archive_libs/discrete/cap_a/chips/chips.prt';

PART_NAME
 C7P13 'CAP_0805-100UF,4V,20%,X5R,6024A':
 GROUP='PWR_MCP_CAP',
 ROOM='VDDQ_ABC_PWR_VR';

SECTION_NUMBER 1
 '@BASEBOARD_FAB2_LIB.BASEBOARD_FAB2(SCH_1):PAGE76_I269@MSTR_DISCRETE.CAP(CHIPS)':
 C_PATH='@baseboard_fab2_lib.baseboard_fab2(sch_1):page76_i269@mstr_discrete.cap~
(chips)',
 P_PATH='@baseboard_fab2_lib.baseboard_fab2(sch_1):page76_i269@mstr_discrete.cap~
(chips)',
 PATH='I269',
 DRAWING='@BASEBOARD_FAB2_LIB.BASEBOARD_FAB2(SCH_1):PAGE76',
 NEW_PN='078.1071T.M002',
 NEW_MATERIAL='X6S',
 TOLERANCE='20%',
 SEC_TYPE='0805',
 MATERIAL='X5R',
 BOM_COST='MEM_VRD_PVDDQ_CD',
 PHYS_PAGE='76',
 XY='(-2100,2200)',
 ROT='0',
 VER='1',
 VALUE='100UF',
 PACK_TYPE='0805',
 PART_NUMBER='602433-112',
 LOCATION='C7P13',
 ROOM='VDDQ_ABC_PWR_VR',
 GROUP='PWR_MCP_CAP',
 SEC='1',
 CDS_LIB='mstr_discrete',
 CDS_PART_NAME='CAP_0805-100UF,4V,20%,X5R,6024A',
 VOLTAGE='4V',
 PRIM_FILE='./archive_libs/mstr_discrete/cap/chips/chips.prt';

PART_NAME
 C7P14 'CAP_0805-100UF,4V,20%,X5R,6024A':
 GROUP='PWR_MCP_CAP',
 ROOM='VDDQ_ABC_PWR_VR';

SECTION_NUMBER 1
 '@BASEBOARD_FAB2_LIB.BASEBOARD_FAB2(SCH_1):PAGE76_I261@MSTR_DISCRETE.CAP(CHIPS)':
 C_PATH='@baseboard_fab2_lib.baseboard_fab2(sch_1):page76_i261@mstr_discrete.cap~
(chips)',
 P_PATH='@baseboard_fab2_lib.baseboard_fab2(sch_1):page76_i261@mstr_discrete.cap~
(chips)',
 PATH='I261',
 DRAWING='@BASEBOARD_FAB2_LIB.BASEBOARD_FAB2(SCH_1):PAGE76',
 NEW_PN='078.1071T.M002',
 NEW_MATERIAL='X6S',
 TOLERANCE='20%',
 SEC_TYPE='0805',
 MATERIAL='X5R',
 BOM_COST='MEM_VRD_PVDDQ_CD',
 PHYS_PAGE='76',
 XY='(-4100,2200)',
 ROT='0',
 VER='1',
 VALUE='100UF',
 PACK_TYPE='0805',
 PART_NUMBER='602433-112',
 LOCATION='C7P14',
 ROOM='VDDQ_ABC_PWR_VR',
 GROUP='PWR_MCP_CAP',
 SEC='1',
 CDS_LIB='mstr_discrete',
 CDS_PART_NAME='CAP_0805-100UF,4V,20%,X5R,6024A',
 VOLTAGE='4V',
 PRIM_FILE='./archive_libs/mstr_discrete/cap/chips/chips.prt';

PART_NAME
 C7P15 'CAP_0805-100UF,4V,20%,X5R,6024A':
 GROUP='PWR_MCP_CAP',
 ROOM='VDDQ_ABC_PWR_VR';

SECTION_NUMBER 1
 '@BASEBOARD_FAB2_LIB.BASEBOARD_FAB2(SCH_1):PAGE76_I263@MSTR_DISCRETE.CAP(CHIPS)':
 C_PATH='@baseboard_fab2_lib.baseboard_fab2(sch_1):page76_i263@mstr_discrete.cap~
(chips)',
 P_PATH='@baseboard_fab2_lib.baseboard_fab2(sch_1):page76_i263@mstr_discrete.cap~
(chips)',
 PATH='I263',
 DRAWING='@BASEBOARD_FAB2_LIB.BASEBOARD_FAB2(SCH_1):PAGE76',
 NEW_PN='078.1071T.M002',
 NEW_MATERIAL='X6S',
 TOLERANCE='20%',
 SEC_TYPE='0805',
 MATERIAL='X5R',
 BOM_COST='MEM_VRD_PVDDQ_CD',
 PHYS_PAGE='76',
 XY='(-3600,2200)',
 ROT='0',
 VER='1',
 VALUE='100UF',
 PACK_TYPE='0805',
 PART_NUMBER='602433-112',
 LOCATION='C7P15',
 ROOM='VDDQ_ABC_PWR_VR',
 GROUP='PWR_MCP_CAP',
 SEC='1',
 CDS_LIB='mstr_discrete',
 CDS_PART_NAME='CAP_0805-100UF,4V,20%,X5R,6024A',
 VOLTAGE='4V',
 PRIM_FILE='./archive_libs/mstr_discrete/cap/chips/chips.prt';

PART_NAME
 C7P16 'CAP_A_0603V-22.0UF,4V,20%,X6S,A':
 GROUP='PWR_MLCC_CAP',
 ROOM='PVCCIN_CPU1_DECAP_VR';

SECTION_NUMBER 1
 '@BASEBOARD_FAB2_LIB.BASEBOARD_FAB2(SCH_1):PAGE76_I206@DEV_DISCRETE.CAP_A(CHIPS)':
 C_PATH='@baseboard_fab2_lib.baseboard_fab2(sch_1):page76_i206@dev_discrete.cap_~
a(chips)',
 P_PATH='@baseboard_fab2_lib.baseboard_fab2(sch_1):page76_i206@dev_discrete.cap_~
a(chips)',
 PATH='I206',
 DRAWING='@BASEBOARD_FAB2_LIB.BASEBOARD_FAB2(SCH_1):PAGE76',
 TOLERANCE='20%',
 MATERIAL='X6S',
 BOM_COST='PROC',
 PHYS_PAGE='76',
 XY='(-2100,1150)',
 ROT='0',
 VER='1',
 VALUE='22.0UF',
 PACK_TYPE='0603V',
 PART_NUMBER='E15431-004',
 LOCATION='C7P16',
 ROOM='PVCCIN_CPU1_DECAP_VR',
 GROUP='PWR_MLCC_CAP',
 CDS_LIB='dev_discrete',
 CDS_PART_NAME='CAP_A_0603V-22.0UF,4V,20%,X6S,A',
 VOLTAGE='4V',
 PRIM_FILE='./archive_libs/discrete/cap_a/chips/chips.prt';

PART_NAME
 C7P17 'CAP_0805-47UF,4V,20%,X6S,C9533A':
 GROUP='PWR_MLCC_CAP',
 ROOM='PVCCIN_CPU1_DECAP_VR';

SECTION_NUMBER 1
 '@BASEBOARD_FAB2_LIB.BASEBOARD_FAB2(SCH_1):PAGE76_I29@MSTR_DISCRETE.CAP(CHIPS)':
 C_PATH='@baseboard_fab2_lib.baseboard_fab2(sch_1):page76_i29@mstr_discrete.cap(~
chips)',
 P_PATH='@baseboard_fab2_lib.baseboard_fab2(sch_1):page76_i29@mstr_discrete.cap(~
chips)',
 PATH='I29',
 DRAWING='@BASEBOARD_FAB2_LIB.BASEBOARD_FAB2(SCH_1):PAGE76',
 TOLERANCE='20%',
 MATERIAL='X6S',
 BOM_COST='PROC',
 PHYS_PAGE='76',
 XY='(-2700,1150)',
 ROT='0',
 VER='1',
 VALUE='47UF',
 PACK_TYPE='0805',
 PART_NUMBER='C95333-006',
 LOCATION='C7P17',
 ROOM='PVCCIN_CPU1_DECAP_VR',
 GROUP='PWR_MLCC_CAP',
 CDS_LIB='mstr_discrete',
 CDS_PART_NAME='CAP_0805-47UF,4V,20%,X6S,C9533A',
 VOLTAGE='4V',
 PRIM_FILE='./archive_libs/mstr_discrete/cap/chips/chips.prt';

PART_NAME
 C7P18 'CAP_0805-47UF,4V,20%,X6S,C9533A':
 GROUP='PWR_MLCC_CAP',
 ROOM='PVCCIN_CPU1_DECAP_VR';

SECTION_NUMBER 1
 '@BASEBOARD_FAB2_LIB.BASEBOARD_FAB2(SCH_1):PAGE76_I51@MSTR_DISCRETE.CAP(CHIPS)':
 C_PATH='@baseboard_fab2_lib.baseboard_fab2(sch_1):page76_i51@mstr_discrete.cap(~
chips)',
 P_PATH='@baseboard_fab2_lib.baseboard_fab2(sch_1):page76_i51@mstr_discrete.cap(~
chips)',
 PATH='I51',
 DRAWING='@BASEBOARD_FAB2_LIB.BASEBOARD_FAB2(SCH_1):PAGE76',
 TOLERANCE='20%',
 MATERIAL='X6S',
 BOM_COST='PROC',
 PHYS_PAGE='76',
 XY='(-3000,1150)',
 ROT='0',
 VER='1',
 VALUE='47UF',
 PACK_TYPE='0805',
 PART_NUMBER='C95333-006',
 LOCATION='C7P18',
 ROOM='PVCCIN_CPU1_DECAP_VR',
 GROUP='PWR_MLCC_CAP',
 CDS_LIB='mstr_discrete',
 CDS_PART_NAME='CAP_0805-47UF,4V,20%,X6S,C9533A',
 VOLTAGE='4V',
 PRIM_FILE='./archive_libs/mstr_discrete/cap/chips/chips.prt';

PART_NAME
 C7P19 'CAP_0805-47UF,4V,20%,X6S,C9533A':
 GROUP='PWR_MLCC_CAP',
 ROOM='PVCCIN_CPU1_DECAP_VR';

SECTION_NUMBER 1
 '@BASEBOARD_FAB2_LIB.BASEBOARD_FAB2(SCH_1):PAGE76_I215@MSTR_DISCRETE.CAP(CHIPS)':
 C_PATH='@baseboard_fab2_lib.baseboard_fab2(sch_1):page76_i215@mstr_discrete.cap~
(chips)',
 P_PATH='@baseboard_fab2_lib.baseboard_fab2(sch_1):page76_i215@mstr_discrete.cap~
(chips)',
 PATH='I215',
 DRAWING='@BASEBOARD_FAB2_LIB.BASEBOARD_FAB2(SCH_1):PAGE76',
 TOLERANCE='20%',
 SEC_TYPE='0805',
 MATERIAL='X6S',
 BOM_COST='PROC',
 PHYS_PAGE='76',
 XY='(-6850,2200)',
 ROT='0',
 VER='1',
 VALUE='47UF',
 PACK_TYPE='0805',
 PART_NUMBER='C95333-006',
 LOCATION='C7P19',
 ROOM='PVCCIN_CPU1_DECAP_VR',
 GROUP='PWR_MLCC_CAP',
 SEC='1',
 CDS_LIB='mstr_discrete',
 CDS_PART_NAME='CAP_0805-47UF,4V,20%,X6S,C9533A',
 VOLTAGE='4V',
 PRIM_FILE='./archive_libs/mstr_discrete/cap/chips/chips.prt';

PART_NAME
 C7P20 'CAP_0805-100UF,4V,20%,X5R,6024A':
 GROUP='PWR_MLCC_CAP',
 ROOM='VDDQ_ABC_PWR_VR';

SECTION_NUMBER 1
 '@BASEBOARD_FAB2_LIB.BASEBOARD_FAB2(SCH_1):PAGE225_I318@MSTR_DISCRETE.CAP(CHIPS)':
 C_PATH='@baseboard_fab2_lib.baseboard_fab2(sch_1):page225_i318@mstr_discrete.ca~
p(chips)',
 P_PATH='@baseboard_fab2_lib.baseboard_fab2(sch_1):page225_i318@mstr_discrete.ca~
p(chips)',
 PATH='I318',
 DRAWING='@BASEBOARD_FAB2_LIB.BASEBOARD_FAB2(SCH_1):PAGE225',
 NEW_PN='078.1071T.M002',
 NEW_MATERIAL='X6S',
 BOM_SS='NOPOP',
 TOLERANCE='20%',
 SEC_TYPE='0805',
 MATERIAL='X5R',
 BOM_COST='MEM_VRD_PVDDQ_CD',
 PHYS_PAGE='225',
 XY='(1625,3050)',
 ROT='0',
 VER='1',
 VALUE='100UF',
 PACK_TYPE='0805',
 PART_NUMBER='602433-112',
 LOCATION='C7P20',
 ROOM='VDDQ_ABC_PWR_VR',
 GROUP='PWR_MLCC_CAP',
 SEC='1',
 CDS_LIB='mstr_discrete',
 CDS_PART_NAME='CAP_0805-100UF,4V,20%,X5R,6024A',
 VOLTAGE='4V',
 PRIM_FILE='./archive_libs/mstr_discrete/cap/chips/chips.prt';

PART_NAME
 C7R1 'CAP_A_0603V-22.0UF,4V,20%,X6S,A':
 GROUP='PWR_MLCC_CAP',
 ROOM='PVCCIO_CPU1';

SECTION_NUMBER 1
 '@BASEBOARD_FAB2_LIB.BASEBOARD_FAB2(SCH_1):PAGE214_I65@DEV_DISCRETE.CAP_A(CHIPS)':
 C_PATH='@baseboard_fab2_lib.baseboard_fab2(sch_1):page214_i65@dev_discrete.cap_~
a(chips)',
 P_PATH='@baseboard_fab2_lib.baseboard_fab2(sch_1):page214_i65@dev_discrete.cap_~
a(chips)',
 PATH='I65',
 DRAWING='@BASEBOARD_FAB2_LIB.BASEBOARD_FAB2(SCH_1):PAGE214',
 TOLERANCE='20%',
 SEC_TYPE='0603V',
 MATERIAL='X6S',
 BOM_COST='PROC_VRD_PVCCIO_CPU1',
 PHYS_PAGE='214',
 XY='(3350,3425)',
 ROT='0',
 VER='1',
 VALUE='22.0UF',
 PACK_TYPE='0603V',
 PART_NUMBER='E15431-004',
 LOCATION='C7R1',
 ROOM='PVCCIO_CPU1',
 GROUP='PWR_MLCC_CAP',
 SEC='1',
 CDS_LIB='dev_discrete',
 CDS_PART_NAME='CAP_A_0603V-22.0UF,4V,20%,X6S,A',
 VOLTAGE='4V',
 PRIM_FILE='./archive_libs/discrete/cap_a/chips/chips.prt';

PART_NAME
 C7T1 'CAP_0805-100UF,4V,20%,X5R,6024A':
 GROUP='PWR_MLCC_CAP',
 ROOM='VDDQ_ABC_PWR_VR';

SECTION_NUMBER 1
 '@BASEBOARD_FAB2_LIB.BASEBOARD_FAB2(SCH_1):PAGE225_I309@MSTR_DISCRETE.CAP(CHIPS)':
 C_PATH='@baseboard_fab2_lib.baseboard_fab2(sch_1):page225_i309@mstr_discrete.ca~
p(chips)',
 P_PATH='@baseboard_fab2_lib.baseboard_fab2(sch_1):page225_i309@mstr_discrete.ca~
p(chips)',
 PATH='I309',
 DRAWING='@BASEBOARD_FAB2_LIB.BASEBOARD_FAB2(SCH_1):PAGE225',
 NEW_PN='078.1071T.M002',
 NEW_MATERIAL='X6S',
 BOM_SS='NOPOP',
 TOLERANCE='20%',
 SEC_TYPE='0805',
 MATERIAL='X5R',
 BOM_COST='MEM_VRD_PVDDQ_CD',
 PHYS_PAGE='225',
 XY='(3500,2825)',
 ROT='0',
 VER='1',
 VALUE='100UF',
 PACK_TYPE='0805',
 PART_NUMBER='602433-112',
 LOCATION='C7T1',
 ROOM='VDDQ_ABC_PWR_VR',
 GROUP='PWR_MLCC_CAP',
 SEC='1',
 CDS_LIB='mstr_discrete',
 CDS_PART_NAME='CAP_0805-100UF,4V,20%,X5R,6024A',
 VOLTAGE='4V',
 PRIM_FILE='./archive_libs/mstr_discrete/cap/chips/chips.prt';

PART_NAME
 C7T2 'CAP_0603LF-10UF,4V,20%,X6S,E15A':
 GROUP='PWR_MLCC_CAP',
 ROOM='PVPP_KLM_VR';

SECTION_NUMBER 1
 '@BASEBOARD_FAB2_LIB.BASEBOARD_FAB2(SCH_1):PAGE233_I112@MSTR_DISCRETE.CAP(CHIPS)':
 C_PATH='@baseboard_fab2_lib.baseboard_fab2(sch_1):page233_i112@mstr_discrete.ca~
p(chips)',
 P_PATH='@baseboard_fab2_lib.baseboard_fab2(sch_1):page233_i112@mstr_discrete.ca~
p(chips)',
 PATH='I112',
 DRAWING='@BASEBOARD_FAB2_LIB.BASEBOARD_FAB2(SCH_1):PAGE233',
 TOLERANCE='20%',
 MATERIAL='X6S',
 BOM_COST='MEM_VRD_PVPP_AB',
 PHYS_PAGE='233',
 XY='(-7600,725)',
 ROT='0',
 VER='1',
 VALUE='10UF',
 PACK_TYPE='0603LF',
 PART_NUMBER='E15431-001',
 LOCATION='C7T2',
 ROOM='PVPP_KLM_VR',
 GROUP='PWR_MLCC_CAP',
 CDS_LIB='mstr_discrete',
 CDS_PART_NAME='CAP_0603LF-10UF,4V,20%,X6S,E15A',
 VOLTAGE='4V',
 PRIM_FILE='./archive_libs/mstr_discrete/cap/chips/chips.prt';

PART_NAME
 C7T3 'CAP_0603LF-10UF,4V,20%,X6S,E15A':
 GROUP='PWR_MLCC_CAP',
 ROOM='PVPP_KLM_VR';

SECTION_NUMBER 1
 '@BASEBOARD_FAB2_LIB.BASEBOARD_FAB2(SCH_1):PAGE233_I113@MSTR_DISCRETE.CAP(CHIPS)':
 C_PATH='@baseboard_fab2_lib.baseboard_fab2(sch_1):page233_i113@mstr_discrete.ca~
p(chips)',
 P_PATH='@baseboard_fab2_lib.baseboard_fab2(sch_1):page233_i113@mstr_discrete.ca~
p(chips)',
 PATH='I113',
 DRAWING='@BASEBOARD_FAB2_LIB.BASEBOARD_FAB2(SCH_1):PAGE233',
 TOLERANCE='20%',
 MATERIAL='X6S',
 BOM_COST='MEM_VRD_PVPP_AB',
 PHYS_PAGE='233',
 XY='(-7325,725)',
 ROT='0',
 VER='1',
 VALUE='10UF',
 PACK_TYPE='0603LF',
 PART_NUMBER='E15431-001',
 LOCATION='C7T3',
 ROOM='PVPP_KLM_VR',
 GROUP='PWR_MLCC_CAP',
 CDS_LIB='mstr_discrete',
 CDS_PART_NAME='CAP_0603LF-10UF,4V,20%,X6S,E15A',
 VOLTAGE='4V',
 PRIM_FILE='./archive_libs/mstr_discrete/cap/chips/chips.prt';

PART_NAME
 C7T4 'CAP_A_0603V-47UF,4V,20%,X5R,60A':
 GROUP='PWR_MLCC_CAP';

SECTION_NUMBER 1
 '@BASEBOARD_FAB2_LIB.BASEBOARD_FAB2(SCH_1):PAGE225_I295@DEV_DISCRETE.CAP_A(CHIPS)':
 C_PATH='@baseboard_fab2_lib.baseboard_fab2(sch_1):page225_i295@dev_discrete.cap~
_a(chips)',
 P_PATH='@baseboard_fab2_lib.baseboard_fab2(sch_1):page225_i295@dev_discrete.cap~
_a(chips)',
 PATH='I295',
 DRAWING='@BASEBOARD_FAB2_LIB.BASEBOARD_FAB2(SCH_1):PAGE225',
 BOM_SS='E15431-004',
 TOLERANCE='20%',
 SEC_TYPE='0603V',
 MATERIAL='X5R',
 PHYS_PAGE='225',
 XY='(-800,-450)',
 ROT='0',
 VER='1',
 VALUE='47UF',
 PACK_TYPE='0603V',
 PART_NUMBER='602433-106',
 LOCATION='C7T4',
 GROUP='PWR_MLCC_CAP',
 SEC='1',
 CDS_LIB='dev_discrete',
 CDS_PART_NAME='CAP_A_0603V-47UF,4V,20%,X5R,60A',
 VOLTAGE='4V',
 PRIM_FILE='./archive_libs/discrete/cap_a/chips/chips.prt';

PART_NAME
 C7T5 'CAP_A_0603V-47UF,4V,20%,X5R,60A':
 GROUP='PWR_MLCC_CAP';

SECTION_NUMBER 1
 '@BASEBOARD_FAB2_LIB.BASEBOARD_FAB2(SCH_1):PAGE225_I296@DEV_DISCRETE.CAP_A(CHIPS)':
 C_PATH='@baseboard_fab2_lib.baseboard_fab2(sch_1):page225_i296@dev_discrete.cap~
_a(chips)',
 P_PATH='@baseboard_fab2_lib.baseboard_fab2(sch_1):page225_i296@dev_discrete.cap~
_a(chips)',
 PATH='I296',
 DRAWING='@BASEBOARD_FAB2_LIB.BASEBOARD_FAB2(SCH_1):PAGE225',
 BOM_SS='E15431-004',
 TOLERANCE='20%',
 SEC_TYPE='0603V',
 MATERIAL='X5R',
 PHYS_PAGE='225',
 XY='(-500,-450)',
 ROT='0',
 VER='1',
 VALUE='47UF',
 PACK_TYPE='0603V',
 PART_NUMBER='602433-106',
 LOCATION='C7T5',
 GROUP='PWR_MLCC_CAP',
 SEC='1',
 CDS_LIB='dev_discrete',
 CDS_PART_NAME='CAP_A_0603V-47UF,4V,20%,X5R,60A',
 VOLTAGE='4V',
 PRIM_FILE='./archive_libs/discrete/cap_a/chips/chips.prt';

PART_NAME
 C7U1 'CAP_A_0603V-47UF,4V,20%,X5R,60A':
 GROUP='PWR_MLCC_CAP';

SECTION_NUMBER 1
 '@BASEBOARD_FAB2_LIB.BASEBOARD_FAB2(SCH_1):PAGE225_I293@DEV_DISCRETE.CAP_A(CHIPS)':
 C_PATH='@baseboard_fab2_lib.baseboard_fab2(sch_1):page225_i293@dev_discrete.cap~
_a(chips)',
 P_PATH='@baseboard_fab2_lib.baseboard_fab2(sch_1):page225_i293@dev_discrete.cap~
_a(chips)',
 PATH='I293',
 DRAWING='@BASEBOARD_FAB2_LIB.BASEBOARD_FAB2(SCH_1):PAGE225',
 BOM_SS='E15431-004',
 TOLERANCE='20%',
 SEC_TYPE='0603V',
 MATERIAL='X5R',
 PHYS_PAGE='225',
 XY='(-1375,-450)',
 ROT='0',
 VER='1',
 VALUE='47UF',
 PACK_TYPE='0603V',
 PART_NUMBER='602433-106',
 LOCATION='C7U1',
 GROUP='PWR_MLCC_CAP',
 SEC='1',
 CDS_LIB='dev_discrete',
 CDS_PART_NAME='CAP_A_0603V-47UF,4V,20%,X5R,60A',
 VOLTAGE='4V',
 PRIM_FILE='./archive_libs/discrete/cap_a/chips/chips.prt';

PART_NAME
 C7U2 'CAP_A_0603V-47UF,4V,20%,X5R,60A':
 GROUP='PWR_MLCC_CAP';

SECTION_NUMBER 1
 '@BASEBOARD_FAB2_LIB.BASEBOARD_FAB2(SCH_1):PAGE225_I292@DEV_DISCRETE.CAP_A(CHIPS)':
 C_PATH='@baseboard_fab2_lib.baseboard_fab2(sch_1):page225_i292@dev_discrete.cap~
_a(chips)',
 P_PATH='@baseboard_fab2_lib.baseboard_fab2(sch_1):page225_i292@dev_discrete.cap~
_a(chips)',
 PATH='I292',
 DRAWING='@BASEBOARD_FAB2_LIB.BASEBOARD_FAB2(SCH_1):PAGE225',
 BOM_SS='E15431-004',
 TOLERANCE='20%',
 SEC_TYPE='0603V',
 MATERIAL='X5R',
 PHYS_PAGE='225',
 XY='(-1650,-450)',
 ROT='0',
 VER='1',
 VALUE='47UF',
 PACK_TYPE='0603V',
 PART_NUMBER='602433-106',
 LOCATION='C7U2',
 GROUP='PWR_MLCC_CAP',
 SEC='1',
 CDS_LIB='dev_discrete',
 CDS_PART_NAME='CAP_A_0603V-47UF,4V,20%,X5R,60A',
 VOLTAGE='4V',
 PRIM_FILE='./archive_libs/discrete/cap_a/chips/chips.prt';

PART_NAME
 C7U3 'CAP_0603LF-10UF,4V,20%,X6S,E15A':
 GROUP='PWR_MLCC_CAP',
 ROOM='PVPP_KLM_VR';

SECTION_NUMBER 1
 '@BASEBOARD_FAB2_LIB.BASEBOARD_FAB2(SCH_1):PAGE233_I136@MSTR_DISCRETE.CAP(CHIPS)':
 C_PATH='@baseboard_fab2_lib.baseboard_fab2(sch_1):page233_i136@mstr_discrete.ca~
p(chips)',
 P_PATH='@baseboard_fab2_lib.baseboard_fab2(sch_1):page233_i136@mstr_discrete.ca~
p(chips)',
 PATH='I136',
 DRAWING='@BASEBOARD_FAB2_LIB.BASEBOARD_FAB2(SCH_1):PAGE233',
 TOLERANCE='20%',
 SEC_TYPE='0603LF',
 MATERIAL='X6S',
 BOM_COST='MEM_VRD_PVPP_AB',
 PHYS_PAGE='233',
 XY='(-5000,725)',
 ROT='0',
 VER='1',
 VALUE='10UF',
 PACK_TYPE='0603LF',
 PART_NUMBER='E15431-001',
 LOCATION='C7U3',
 ROOM='PVPP_KLM_VR',
 GROUP='PWR_MLCC_CAP',
 SEC='1',
 CDS_LIB='mstr_discrete',
 CDS_PART_NAME='CAP_0603LF-10UF,4V,20%,X6S,E15A',
 VOLTAGE='4V',
 PRIM_FILE='./archive_libs/mstr_discrete/cap/chips/chips.prt';

PART_NAME
 C7U4 'CAP_0603LF-10UF,4V,20%,X6S,E15A':
 GROUP='PWR_MLCC_CAP',
 ROOM='PVPP_KLM_VR';

SECTION_NUMBER 1
 '@BASEBOARD_FAB2_LIB.BASEBOARD_FAB2(SCH_1):PAGE233_I109@MSTR_DISCRETE.CAP(CHIPS)':
 C_PATH='@baseboard_fab2_lib.baseboard_fab2(sch_1):page233_i109@mstr_discrete.ca~
p(chips)',
 P_PATH='@baseboard_fab2_lib.baseboard_fab2(sch_1):page233_i109@mstr_discrete.ca~
p(chips)',
 PATH='I109',
 DRAWING='@BASEBOARD_FAB2_LIB.BASEBOARD_FAB2(SCH_1):PAGE233',
 TOLERANCE='20%',
 MATERIAL='X6S',
 BOM_COST='MEM_VRD_PVPP_AB',
 PHYS_PAGE='233',
 XY='(-8150,725)',
 ROT='0',
 VER='1',
 VALUE='10UF',
 PACK_TYPE='0603LF',
 PART_NUMBER='E15431-001',
 LOCATION='C7U4',
 ROOM='PVPP_KLM_VR',
 GROUP='PWR_MLCC_CAP',
 CDS_LIB='mstr_discrete',
 CDS_PART_NAME='CAP_0603LF-10UF,4V,20%,X6S,E15A',
 VOLTAGE='4V',
 PRIM_FILE='./archive_libs/mstr_discrete/cap/chips/chips.prt';

PART_NAME
 C7U5 'CAP_0603LF-10UF,4V,20%,X6S,E15A':
 GROUP='PWR_MLCC_CAP',
 ROOM='PVPP_KLM_VR';

SECTION_NUMBER 1
 '@BASEBOARD_FAB2_LIB.BASEBOARD_FAB2(SCH_1):PAGE233_I111@MSTR_DISCRETE.CAP(CHIPS)':
 C_PATH='@baseboard_fab2_lib.baseboard_fab2(sch_1):page233_i111@mstr_discrete.ca~
p(chips)',
 P_PATH='@baseboard_fab2_lib.baseboard_fab2(sch_1):page233_i111@mstr_discrete.ca~
p(chips)',
 PATH='I111',
 DRAWING='@BASEBOARD_FAB2_LIB.BASEBOARD_FAB2(SCH_1):PAGE233',
 TOLERANCE='20%',
 MATERIAL='X6S',
 BOM_COST='MEM_VRD_PVPP_AB',
 PHYS_PAGE='233',
 XY='(-7875,725)',
 ROT='0',
 VER='1',
 VALUE='10UF',
 PACK_TYPE='0603LF',
 PART_NUMBER='E15431-001',
 LOCATION='C7U5',
 ROOM='PVPP_KLM_VR',
 GROUP='PWR_MLCC_CAP',
 CDS_LIB='mstr_discrete',
 CDS_PART_NAME='CAP_0603LF-10UF,4V,20%,X6S,E15A',
 VOLTAGE='4V',
 PRIM_FILE='./archive_libs/mstr_discrete/cap/chips/chips.prt';

PART_NAME
 C7U6 'CAP_0603LF-10UF,4V,20%,X6S,E15A':
 GROUP='PWR_MLCC_CAP',
 ROOM='PVPP_KLM_VR';

SECTION_NUMBER 1
 '@BASEBOARD_FAB2_LIB.BASEBOARD_FAB2(SCH_1):PAGE233_I115@MSTR_DISCRETE.CAP(CHIPS)':
 C_PATH='@baseboard_fab2_lib.baseboard_fab2(sch_1):page233_i115@mstr_discrete.ca~
p(chips)',
 P_PATH='@baseboard_fab2_lib.baseboard_fab2(sch_1):page233_i115@mstr_discrete.ca~
p(chips)',
 PATH='I115',
 DRAWING='@BASEBOARD_FAB2_LIB.BASEBOARD_FAB2(SCH_1):PAGE233',
 TOLERANCE='20%',
 MATERIAL='X6S',
 BOM_COST='MEM_VRD_PVPP_AB',
 PHYS_PAGE='233',
 XY='(-7050,725)',
 ROT='0',
 VER='1',
 VALUE='10UF',
 PACK_TYPE='0603LF',
 PART_NUMBER='E15431-001',
 LOCATION='C7U6',
 ROOM='PVPP_KLM_VR',
 GROUP='PWR_MLCC_CAP',
 CDS_LIB='mstr_discrete',
 CDS_PART_NAME='CAP_0603LF-10UF,4V,20%,X6S,E15A',
 VOLTAGE='4V',
 PRIM_FILE='./archive_libs/mstr_discrete/cap/chips/chips.prt';

PART_NAME
 C7U7 'CAP_0805-100UF,4V,20%,X5R,6024A':
 GROUP='PWR_MLCC_CAP',
 ROOM='VDDQ_ABC_PWR_VR';

SECTION_NUMBER 1
 '@BASEBOARD_FAB2_LIB.BASEBOARD_FAB2(SCH_1):PAGE225_I308@MSTR_DISCRETE.CAP(CHIPS)':
 C_PATH='@baseboard_fab2_lib.baseboard_fab2(sch_1):page225_i308@mstr_discrete.ca~
p(chips)',
 P_PATH='@baseboard_fab2_lib.baseboard_fab2(sch_1):page225_i308@mstr_discrete.ca~
p(chips)',
 PATH='I308',
 DRAWING='@BASEBOARD_FAB2_LIB.BASEBOARD_FAB2(SCH_1):PAGE225',
 NEW_PN='078.1071T.M002',
 NEW_MATERIAL='X6S',
 BOM_SS='NOPOP',
 TOLERANCE='20%',
 SEC_TYPE='0805',
 MATERIAL='X5R',
 BOM_COST='MEM_VRD_PVDDQ_CD',
 PHYS_PAGE='225',
 XY='(3150,2825)',
 ROT='0',
 VER='1',
 VALUE='100UF',
 PACK_TYPE='0805',
 PART_NUMBER='602433-112',
 LOCATION='C7U7',
 ROOM='VDDQ_ABC_PWR_VR',
 GROUP='PWR_MLCC_CAP',
 SEC='1',
 CDS_LIB='mstr_discrete',
 CDS_PART_NAME='CAP_0805-100UF,4V,20%,X5R,6024A',
 VOLTAGE='4V',
 PRIM_FILE='./archive_libs/mstr_discrete/cap/chips/chips.prt';

PART_NAME
 C7W1 'CAP_A_0402V-0.1UF,16V,10%,X7R,A':
 ROOM='PROC_SIDEBAND';

SECTION_NUMBER 1
 '@BASEBOARD_FAB2_LIB.BASEBOARD_FAB2(SCH_1):PAGE166_I36@DEV_DISCRETE.CAP_A(CHIPS)':
 C_PATH='@baseboard_fab2_lib.baseboard_fab2(sch_1):page166_i36@dev_discrete.cap_~
a(chips)',
 P_PATH='@baseboard_fab2_lib.baseboard_fab2(sch_1):page166_i36@dev_discrete.cap_~
a(chips)',
 PATH='I36',
 DRAWING='@BASEBOARD_FAB2_LIB.BASEBOARD_FAB2(SCH_1):PAGE166',
 TOLERANCE='10%',
 SEC_TYPE='0402V',
 MATERIAL='X7R',
 BOM_COST='PROC_SIDEBAND',
 PHYS_PAGE='166',
 XY='(-2725,3225)',
 ROT='0',
 VER='1',
 VALUE='0.1UF',
 PACK_TYPE='0402V',
 PART_NUMBER='A36096-030',
 LOCATION='C7W1',
 ROOM='PROC_SIDEBAND',
 SEC='1',
 CDS_LIB='dev_discrete',
 CDS_PART_NAME='CAP_A_0402V-0.1UF,16V,10%,X7R,A',
 VOLTAGE='16V',
 PRIM_FILE='./archive_libs/discrete/cap_a/chips/chips.prt';

PART_NAME
 C7W2 'SE100U16VM-48-GP_SMD-TCG2-SE10A':;

SECTION_NUMBER 1
 '@BASEBOARD_FAB2_LIB.BASEBOARD_FAB2(SCH_1):PAGE220_I324@W_HDL.SE100U16VM-48-GP(CHIPS)':
 C_PATH='@baseboard_fab2_lib.baseboard_fab2(sch_1):page220_i324@w_hdl.\se100u16v~
m-48-gp\(chips)',
 P_PATH='@baseboard_fab2_lib.baseboard_fab2(sch_1):page220_i324@w_hdl.\se100u16v~
m-48-gp\(chips)',
 PATH='I324',
 DRAWING='@BASEBOARD_FAB2_LIB.BASEBOARD_FAB2(SCH_1):PAGE220',
 RATED='16V',
 ATTRIBUTE='100UF',
 SEC_TYPE='SMD-TCG2',
 PHYS_PAGE='220',
 XY='(-1450,1025)',
 ROT='0',
 VER='1',
 VALUE='SE100U16VM-48-GP',
 PACK_TYPE='SMD-TCG2',
 PART_NUMBER='077.51081.0011',
 LOCATION='C7W2',
 SEC='1',
 CDS_LIB='w_hdl',
 CDS_PART_NAME='SE100U16VM-48-GP_SMD-TCG2-SE10A',
 PRIM_FILE='C:/<user>/w_hdl/se100u16vm#2d48#2dgp/chips/chips.prt';

PART_NAME
 C7W5 'SC22U16V5MX-4-GP_SMD-BCG5-SC22A':;

SECTION_NUMBER 1
 '@BASEBOARD_FAB2_LIB.BASEBOARD_FAB2(SCH_1):PAGE220_I298@W_HDL.SC22U16V5MX-4-GP(CHIPS)':
 C_PATH='@baseboard_fab2_lib.baseboard_fab2(sch_1):page220_i298@w_hdl.\sc22u16v5~
mx-4-gp\(chips)',
 P_PATH='@baseboard_fab2_lib.baseboard_fab2(sch_1):page220_i298@w_hdl.\sc22u16v5~
mx-4-gp\(chips)',
 PATH='I298',
 DRAWING='@BASEBOARD_FAB2_LIB.BASEBOARD_FAB2(SCH_1):PAGE220',
 TYPE='X6S',
 PACK_SIZE='0805',
 RATED='16V',
 ATTRIBUTE='22UF',
 TOLERANCE='20%',
 SEC_TYPE='SMD-BCG5',
 PHYS_PAGE='220',
 XY='(-500,1025)',
 ROT='0',
 VER='1',
 VALUE='SC22U16V5MX-4-GP',
 PACK_TYPE='SMD-BCG5',
 PART_NUMBER='078.22611.0811',
 LOCATION='C7W5',
 SEC='1',
 CDS_LIB='w_hdl',
 CDS_PART_NAME='SC22U16V5MX-4-GP_SMD-BCG5-SC22A',
 PRIM_FILE='C:/<user>/w_hdl/sc22u16v5mx#2d4#2dgp/chips/chips.prt';

PART_NAME
 C7W6 'SC22U16V5MX-4-GP_SMD-BCG5-SC22A':;

SECTION_NUMBER 1
 '@BASEBOARD_FAB2_LIB.BASEBOARD_FAB2(SCH_1):PAGE220_I302@W_HDL.SC22U16V5MX-4-GP(CHIPS)':
 C_PATH='@baseboard_fab2_lib.baseboard_fab2(sch_1):page220_i302@w_hdl.\sc22u16v5~
mx-4-gp\(chips)',
 P_PATH='@baseboard_fab2_lib.baseboard_fab2(sch_1):page220_i302@w_hdl.\sc22u16v5~
mx-4-gp\(chips)',
 PATH='I302',
 DRAWING='@BASEBOARD_FAB2_LIB.BASEBOARD_FAB2(SCH_1):PAGE220',
 TYPE='X6S',
 PACK_SIZE='0805',
 RATED='16V',
 ATTRIBUTE='22UF',
 TOLERANCE='20%',
 SEC_TYPE='SMD-BCG5',
 PHYS_PAGE='220',
 XY='(-200,1025)',
 ROT='0',
 VER='1',
 VALUE='SC22U16V5MX-4-GP',
 PACK_TYPE='SMD-BCG5',
 PART_NUMBER='078.22611.0811',
 LOCATION='C7W6',
 SEC='1',
 CDS_LIB='w_hdl',
 CDS_PART_NAME='SC22U16V5MX-4-GP_SMD-BCG5-SC22A',
 PRIM_FILE='C:/<user>/w_hdl/sc22u16v5mx#2d4#2dgp/chips/chips.prt';

PART_NAME
 C7W7 'SC22U16V5MX-4-GP_SMD-BCG5-SC22A':;

SECTION_NUMBER 1
 '@BASEBOARD_FAB2_LIB.BASEBOARD_FAB2(SCH_1):PAGE220_I301@W_HDL.SC22U16V5MX-4-GP(CHIPS)':
 C_PATH='@baseboard_fab2_lib.baseboard_fab2(sch_1):page220_i301@w_hdl.\sc22u16v5~
mx-4-gp\(chips)',
 P_PATH='@baseboard_fab2_lib.baseboard_fab2(sch_1):page220_i301@w_hdl.\sc22u16v5~
mx-4-gp\(chips)',
 PATH='I301',
 DRAWING='@BASEBOARD_FAB2_LIB.BASEBOARD_FAB2(SCH_1):PAGE220',
 TYPE='X6S',
 PACK_SIZE='0805',
 RATED='16V',
 ATTRIBUTE='22UF',
 TOLERANCE='20%',
 SEC_TYPE='SMD-BCG5',
 PHYS_PAGE='220',
 XY='(100,1025)',
 ROT='0',
 VER='1',
 VALUE='SC22U16V5MX-4-GP',
 PACK_TYPE='SMD-BCG5',
 PART_NUMBER='078.22611.0811',
 LOCATION='C7W7',
 SEC='1',
 CDS_LIB='w_hdl',
 CDS_PART_NAME='SC22U16V5MX-4-GP_SMD-BCG5-SC22A',
 PRIM_FILE='C:/<user>/w_hdl/sc22u16v5mx#2d4#2dgp/chips/chips.prt';

PART_NAME
 C7W8 'SC22U16V5MX-4-GP_SMD-BCG5-SC22A':;

SECTION_NUMBER 1
 '@BASEBOARD_FAB2_LIB.BASEBOARD_FAB2(SCH_1):PAGE220_I300@W_HDL.SC22U16V5MX-4-GP(CHIPS)':
 C_PATH='@baseboard_fab2_lib.baseboard_fab2(sch_1):page220_i300@w_hdl.\sc22u16v5~
mx-4-gp\(chips)',
 P_PATH='@baseboard_fab2_lib.baseboard_fab2(sch_1):page220_i300@w_hdl.\sc22u16v5~
mx-4-gp\(chips)',
 PATH='I300',
 DRAWING='@BASEBOARD_FAB2_LIB.BASEBOARD_FAB2(SCH_1):PAGE220',
 TYPE='X6S',
 PACK_SIZE='0805',
 RATED='16V',
 ATTRIBUTE='22UF',
 TOLERANCE='20%',
 SEC_TYPE='SMD-BCG5',
 PHYS_PAGE='220',
 XY='(400,1025)',
 ROT='0',
 VER='1',
 VALUE='SC22U16V5MX-4-GP',
 PACK_TYPE='SMD-BCG5',
 PART_NUMBER='078.22611.0811',
 LOCATION='C7W8',
 SEC='1',
 CDS_LIB='w_hdl',
 CDS_PART_NAME='SC22U16V5MX-4-GP_SMD-BCG5-SC22A',
 PRIM_FILE='C:/<user>/w_hdl/sc22u16v5mx#2d4#2dgp/chips/chips.prt';

PART_NAME
 C7W9 'SC22U16V5MX-4-GP_SMD-BCG5-SC22A':;

SECTION_NUMBER 1
 '@BASEBOARD_FAB2_LIB.BASEBOARD_FAB2(SCH_1):PAGE220_I299@W_HDL.SC22U16V5MX-4-GP(CHIPS)':
 C_PATH='@baseboard_fab2_lib.baseboard_fab2(sch_1):page220_i299@w_hdl.\sc22u16v5~
mx-4-gp\(chips)',
 P_PATH='@baseboard_fab2_lib.baseboard_fab2(sch_1):page220_i299@w_hdl.\sc22u16v5~
mx-4-gp\(chips)',
 PATH='I299',
 DRAWING='@BASEBOARD_FAB2_LIB.BASEBOARD_FAB2(SCH_1):PAGE220',
 TYPE='X6S',
 PACK_SIZE='0805',
 RATED='16V',
 ATTRIBUTE='22UF',
 TOLERANCE='20%',
 SEC_TYPE='SMD-BCG5',
 PHYS_PAGE='220',
 XY='(700,1025)',
 ROT='0',
 VER='1',
 VALUE='SC22U16V5MX-4-GP',
 PACK_TYPE='SMD-BCG5',
 PART_NUMBER='078.22611.0811',
 LOCATION='C7W9',
 SEC='1',
 CDS_LIB='w_hdl',
 CDS_PART_NAME='SC22U16V5MX-4-GP_SMD-BCG5-SC22A',
 PRIM_FILE='C:/<user>/w_hdl/sc22u16v5mx#2d4#2dgp/chips/chips.prt';

PART_NAME
 C7W10 'SC22U16V5MX-4-GP_SMD-BCG5-SC22A':;

SECTION_NUMBER 1
 '@BASEBOARD_FAB2_LIB.BASEBOARD_FAB2(SCH_1):PAGE220_I306@W_HDL.SC22U16V5MX-4-GP(CHIPS)':
 C_PATH='@baseboard_fab2_lib.baseboard_fab2(sch_1):page220_i306@w_hdl.\sc22u16v5~
mx-4-gp\(chips)',
 P_PATH='@baseboard_fab2_lib.baseboard_fab2(sch_1):page220_i306@w_hdl.\sc22u16v5~
mx-4-gp\(chips)',
 PATH='I306',
 DRAWING='@BASEBOARD_FAB2_LIB.BASEBOARD_FAB2(SCH_1):PAGE220',
 TYPE='X6S',
 PACK_SIZE='0805',
 RATED='16V',
 ATTRIBUTE='22UF',
 TOLERANCE='20%',
 SEC_TYPE='SMD-BCG5',
 PHYS_PAGE='220',
 XY='(1000,1025)',
 ROT='0',
 VER='1',
 VALUE='SC22U16V5MX-4-GP',
 PACK_TYPE='SMD-BCG5',
 PART_NUMBER='078.22611.0811',
 LOCATION='C7W10',
 SEC='1',
 CDS_LIB='w_hdl',
 CDS_PART_NAME='SC22U16V5MX-4-GP_SMD-BCG5-SC22A',
 PRIM_FILE='C:/<user>/w_hdl/sc22u16v5mx#2d4#2dgp/chips/chips.prt';

PART_NAME
 C7W11 'SC22U16V5MX-4-GP_SMD-BCG5-SC22A':;

SECTION_NUMBER 1
 '@BASEBOARD_FAB2_LIB.BASEBOARD_FAB2(SCH_1):PAGE220_I305@W_HDL.SC22U16V5MX-4-GP(CHIPS)':
 C_PATH='@baseboard_fab2_lib.baseboard_fab2(sch_1):page220_i305@w_hdl.\sc22u16v5~
mx-4-gp\(chips)',
 P_PATH='@baseboard_fab2_lib.baseboard_fab2(sch_1):page220_i305@w_hdl.\sc22u16v5~
mx-4-gp\(chips)',
 PATH='I305',
 DRAWING='@BASEBOARD_FAB2_LIB.BASEBOARD_FAB2(SCH_1):PAGE220',
 TYPE='X6S',
 PACK_SIZE='0805',
 RATED='16V',
 ATTRIBUTE='22UF',
 TOLERANCE='20%',
 SEC_TYPE='SMD-BCG5',
 PHYS_PAGE='220',
 XY='(1300,1025)',
 ROT='0',
 VER='1',
 VALUE='SC22U16V5MX-4-GP',
 PACK_TYPE='SMD-BCG5',
 PART_NUMBER='078.22611.0811',
 LOCATION='C7W11',
 SEC='1',
 CDS_LIB='w_hdl',
 CDS_PART_NAME='SC22U16V5MX-4-GP_SMD-BCG5-SC22A',
 PRIM_FILE='C:/<user>/w_hdl/sc22u16v5mx#2d4#2dgp/chips/chips.prt';

PART_NAME
 C7W12 'SC22U16V5MX-4-GP_SMD-BCG5-SC22A':;

SECTION_NUMBER 1
 '@BASEBOARD_FAB2_LIB.BASEBOARD_FAB2(SCH_1):PAGE220_I304@W_HDL.SC22U16V5MX-4-GP(CHIPS)':
 C_PATH='@baseboard_fab2_lib.baseboard_fab2(sch_1):page220_i304@w_hdl.\sc22u16v5~
mx-4-gp\(chips)',
 P_PATH='@baseboard_fab2_lib.baseboard_fab2(sch_1):page220_i304@w_hdl.\sc22u16v5~
mx-4-gp\(chips)',
 PATH='I304',
 DRAWING='@BASEBOARD_FAB2_LIB.BASEBOARD_FAB2(SCH_1):PAGE220',
 TYPE='X6S',
 PACK_SIZE='0805',
 RATED='16V',
 ATTRIBUTE='22UF',
 TOLERANCE='20%',
 SEC_TYPE='SMD-BCG5',
 PHYS_PAGE='220',
 XY='(1600,1025)',
 ROT='0',
 VER='1',
 VALUE='SC22U16V5MX-4-GP',
 PACK_TYPE='SMD-BCG5',
 PART_NUMBER='078.22611.0811',
 LOCATION='C7W12',
 SEC='1',
 CDS_LIB='w_hdl',
 CDS_PART_NAME='SC22U16V5MX-4-GP_SMD-BCG5-SC22A',
 PRIM_FILE='C:/<user>/w_hdl/sc22u16v5mx#2d4#2dgp/chips/chips.prt';

PART_NAME
 C7W13 'SC22U16V5MX-4-GP_SMD-BCG5-SC22A':;

SECTION_NUMBER 1
 '@BASEBOARD_FAB2_LIB.BASEBOARD_FAB2(SCH_1):PAGE220_I303@W_HDL.SC22U16V5MX-4-GP(CHIPS)':
 C_PATH='@baseboard_fab2_lib.baseboard_fab2(sch_1):page220_i303@w_hdl.\sc22u16v5~
mx-4-gp\(chips)',
 P_PATH='@baseboard_fab2_lib.baseboard_fab2(sch_1):page220_i303@w_hdl.\sc22u16v5~
mx-4-gp\(chips)',
 PATH='I303',
 DRAWING='@BASEBOARD_FAB2_LIB.BASEBOARD_FAB2(SCH_1):PAGE220',
 TYPE='X6S',
 PACK_SIZE='0805',
 RATED='16V',
 ATTRIBUTE='22UF',
 TOLERANCE='20%',
 SEC_TYPE='SMD-BCG5',
 PHYS_PAGE='220',
 XY='(1900,1025)',
 ROT='0',
 VER='1',
 VALUE='SC22U16V5MX-4-GP',
 PACK_TYPE='SMD-BCG5',
 PART_NUMBER='078.22611.0811',
 LOCATION='C7W13',
 SEC='1',
 CDS_LIB='w_hdl',
 CDS_PART_NAME='SC22U16V5MX-4-GP_SMD-BCG5-SC22A',
 PRIM_FILE='C:/<user>/w_hdl/sc22u16v5mx#2d4#2dgp/chips/chips.prt';

PART_NAME
 C8A2 'CAP_0402LF-220PF,50V,10%,X7R,AA':
 ROOM='PVNN_PCH_STBY',
 NO_XNET_CONNECTION='1';

SECTION_NUMBER 1
 '@BASEBOARD_FAB2_LIB.BASEBOARD_FAB2(SCH_1):PAGE235_I209@MSTR_DISCRETE.CAP(CHIPS)':
 C_PATH='@baseboard_fab2_lib.baseboard_fab2(sch_1):page235_i209@mstr_discrete.ca~
p(chips)',
 P_PATH='@baseboard_fab2_lib.baseboard_fab2(sch_1):page235_i209@mstr_discrete.ca~
p(chips)',
 PATH='I209',
 DRAWING='@BASEBOARD_FAB2_LIB.BASEBOARD_FAB2(SCH_1):PAGE235',
 TOLERANCE='10%',
 SEC_TYPE='0402LF',
 MATERIAL='X7R',
 NO_XNET_CONNECTION='1',
 PHYS_PAGE='235',
 XY='(-12375,2600)',
 ROT='0',
 VER='1',
 VALUE='220PF',
 PACK_TYPE='0402LF',
 PART_NUMBER='A36096-050',
 LOCATION='C8A2',
 ROOM='PVNN_PCH_STBY',
 SEC='1',
 CDS_LIB='mstr_discrete',
 CDS_PART_NAME='CAP_0402LF-220PF,50V,10%,X7R,AA',
 VOLTAGE='50V',
 PRIM_FILE='./archive_libs/mstr_discrete/cap/chips/chips.prt';

PART_NAME
 C8A3 'CAP_A_0402V-0.1UF,16V,10%,X7R,A':
 ROOM='CPU_FANS';

SECTION_NUMBER 1
 '@BASEBOARD_FAB2_LIB.BASEBOARD_FAB2(SCH_1):PAGE235_I255@DEV_DISCRETE.CAP_A(CHIPS)':
 C_PATH='@baseboard_fab2_lib.baseboard_fab2(sch_1):page235_i255@dev_discrete.cap~
_a(chips)',
 P_PATH='@baseboard_fab2_lib.baseboard_fab2(sch_1):page235_i255@dev_discrete.cap~
_a(chips)',
 PATH='I255',
 DRAWING='@BASEBOARD_FAB2_LIB.BASEBOARD_FAB2(SCH_1):PAGE235',
 TOLERANCE='10%',
 SEC_TYPE='0402V',
 MATERIAL='X7R',
 BOM_COST='SM_THERM',
 PHYS_PAGE='235',
 XY='(-12750,5150)',
 ROT='0',
 VER='1',
 VALUE='0.1UF',
 PACK_TYPE='0402V',
 PART_NUMBER='A36096-030',
 LOCATION='C8A3',
 ROOM='CPU_FANS',
 SEC='1',
 CDS_LIB='dev_discrete',
 CDS_PART_NAME='CAP_A_0402V-0.1UF,16V,10%,X7R,A',
 VOLTAGE='16V',
 PRIM_FILE='./archive_libs/discrete/cap_a/chips/chips.prt';

PART_NAME
 C8A4 'CAP_0603LF-0.1UF,25V,10%,X7R,6A':
 ROOM='P1V8_PCH_STBY_VR';

SECTION_NUMBER 1
 '@BASEBOARD_FAB2_LIB.BASEBOARD_FAB2(SCH_1):PAGE237_I31@MSTR_DISCRETE.CAP(CHIPS)':
 C_PATH='@baseboard_fab2_lib.baseboard_fab2(sch_1):page237_i31@mstr_discrete.cap~
(chips)',
 P_PATH='@baseboard_fab2_lib.baseboard_fab2(sch_1):page237_i31@mstr_discrete.cap~
(chips)',
 PATH='I31',
 DRAWING='@BASEBOARD_FAB2_LIB.BASEBOARD_FAB2(SCH_1):PAGE237',
 TOLERANCE='10%',
 SEC_TYPE='0603LF',
 MATERIAL='X7R',
 BOM_COST='P1V8_PCH_STBY_VR',
 PHYS_PAGE='237',
 XY='(-1550,3175)',
 ROT='0',
 VER='1',
 VALUE='0.1UF',
 PACK_TYPE='0603LF',
 PART_NUMBER='602433-020',
 LOCATION='C8A4',
 ROOM='P1V8_PCH_STBY_VR',
 SEC='1',
 CDS_LIB='mstr_discrete',
 CDS_PART_NAME='CAP_0603LF-0.1UF,25V,10%,X7R,6A',
 VOLTAGE='25V',
 PRIM_FILE='./archive_libs/mstr_discrete/cap/chips/chips.prt';

PART_NAME
 C8A6 'CAP_0603-10UF,6.3V,20%,X6S,E15A':
 ROOM='P1V8_PCH_STBY_VR';

SECTION_NUMBER 1
 '@BASEBOARD_FAB2_LIB.BASEBOARD_FAB2(SCH_1):PAGE237_I29@MSTR_DISCRETE.CAP(CHIPS)':
 C_PATH='@baseboard_fab2_lib.baseboard_fab2(sch_1):page237_i29@mstr_discrete.cap~
(chips)',
 P_PATH='@baseboard_fab2_lib.baseboard_fab2(sch_1):page237_i29@mstr_discrete.cap~
(chips)',
 PATH='I29',
 DRAWING='@BASEBOARD_FAB2_LIB.BASEBOARD_FAB2(SCH_1):PAGE237',
 TOLERANCE='20%',
 SEC_TYPE='0603',
 MATERIAL='X6S',
 BOM_COST='P1V8_PCH_STBY_VR',
 PHYS_PAGE='237',
 XY='(-1975,3150)',
 ROT='0',
 VER='1',
 VALUE='10UF',
 PACK_TYPE='0603',
 PART_NUMBER='E15431-002',
 LOCATION='C8A6',
 ROOM='P1V8_PCH_STBY_VR',
 SEC='1',
 CDS_LIB='mstr_discrete',
 CDS_PART_NAME='CAP_0603-10UF,6.3V,20%,X6S,E15A',
 VOLTAGE='6.3V',
 PRIM_FILE='./archive_libs/mstr_discrete/cap/chips/chips.prt';

PART_NAME
 C8A7 'CAP_A_0402V-1.0UF,6.3V,10%,X6SA':
 ROOM='PVNN_PCH_STBY';

SECTION_NUMBER 1
 '@BASEBOARD_FAB2_LIB.BASEBOARD_FAB2(SCH_1):PAGE235_I143@DEV_DISCRETE.CAP_A(CHIPS)':
 C_PATH='@baseboard_fab2_lib.baseboard_fab2(sch_1):page235_i143@dev_discrete.cap~
_a(chips)',
 P_PATH='@baseboard_fab2_lib.baseboard_fab2(sch_1):page235_i143@dev_discrete.cap~
_a(chips)',
 PATH='I143',
 DRAWING='@BASEBOARD_FAB2_LIB.BASEBOARD_FAB2(SCH_1):PAGE235',
 TOLERANCE='10%',
 SEC_TYPE='0402V',
 MATERIAL='X6S',
 PHYS_PAGE='235',
 XY='(-8800,1975)',
 ROT='0',
 VER='1',
 VALUE='1.0UF',
 PACK_TYPE='0402V',
 PART_NUMBER='D97712-004',
 LOCATION='C8A7',
 ROOM='PVNN_PCH_STBY',
 SEC='1',
 CDS_LIB='dev_discrete',
 CDS_PART_NAME='CAP_A_0402V-1.0UF,6.3V,10%,X6SA',
 VOLTAGE='6.3V',
 PRIM_FILE='./archive_libs/discrete/cap_a/chips/chips.prt';

PART_NAME
 C8A8 'CAP_A_0402V-0.1UF,16V,10%,X7R,A':
 ROOM='PVNN_PCH_STBY';

SECTION_NUMBER 1
 '@BASEBOARD_FAB2_LIB.BASEBOARD_FAB2(SCH_1):PAGE235_I145@DEV_DISCRETE.CAP_A(CHIPS)':
 C_PATH='@baseboard_fab2_lib.baseboard_fab2(sch_1):page235_i145@dev_discrete.cap~
_a(chips)',
 P_PATH='@baseboard_fab2_lib.baseboard_fab2(sch_1):page235_i145@dev_discrete.cap~
_a(chips)',
 PATH='I145',
 DRAWING='@BASEBOARD_FAB2_LIB.BASEBOARD_FAB2(SCH_1):PAGE235',
 TOLERANCE='10%',
 SEC_TYPE='0402V',
 MATERIAL='X7R',
 PHYS_PAGE='235',
 XY='(-9200,1975)',
 ROT='0',
 VER='1',
 VALUE='0.1UF',
 PACK_TYPE='0402V',
 PART_NUMBER='A36096-030',
 LOCATION='C8A8',
 ROOM='PVNN_PCH_STBY',
 SEC='1',
 CDS_LIB='dev_discrete',
 CDS_PART_NAME='CAP_A_0402V-0.1UF,16V,10%,X7R,A',
 VOLTAGE='16V',
 PRIM_FILE='./archive_libs/discrete/cap_a/chips/chips.prt';

PART_NAME
 C8A9 'CAP_0402LF-1000PF,50V,10%,X7R,A':
 ROOM='PVNN_PCH_STBY';

SECTION_NUMBER 1
 '@BASEBOARD_FAB2_LIB.BASEBOARD_FAB2(SCH_1):PAGE235_I218@MSTR_DISCRETE.CAP(CHIPS)':
 C_PATH='@baseboard_fab2_lib.baseboard_fab2(sch_1):page235_i218@mstr_discrete.ca~
p(chips)',
 P_PATH='@baseboard_fab2_lib.baseboard_fab2(sch_1):page235_i218@mstr_discrete.ca~
p(chips)',
 PATH='I218',
 DRAWING='@BASEBOARD_FAB2_LIB.BASEBOARD_FAB2(SCH_1):PAGE235',
 TOLERANCE='10%',
 SEC_TYPE='0402LF',
 MATERIAL='X7R',
 PHYS_PAGE='235',
 XY='(-8000,4325)',
 ROT='0',
 VER='1',
 VALUE='1000PF',
 PACK_TYPE='0402LF',
 PART_NUMBER='A36096-046',
 LOCATION='C8A9',
 ROOM='PVNN_PCH_STBY',
 SEC='1',
 CDS_LIB='mstr_discrete',
 CDS_PART_NAME='CAP_0402LF-1000PF,50V,10%,X7R,A',
 VOLTAGE='50V',
 PRIM_FILE='./archive_libs/mstr_discrete/cap/chips/chips.prt';

PART_NAME
 C8A10 'CAP_0402LF-1000PF,50V,10%,EMPTA':
 ROOM='P1V8_PCH_STBY_VR';

SECTION_NUMBER 1
 '@BASEBOARD_FAB2_LIB.BASEBOARD_FAB2(SCH_1):PAGE237_I55@MSTR_DISCRETE.CAP(CHIPS)':
 C_PATH='@baseboard_fab2_lib.baseboard_fab2(sch_1):page237_i55@mstr_discrete.cap~
(chips)',
 P_PATH='@baseboard_fab2_lib.baseboard_fab2(sch_1):page237_i55@mstr_discrete.cap~
(chips)',
 PATH='I55',
 DRAWING='@BASEBOARD_FAB2_LIB.BASEBOARD_FAB2(SCH_1):PAGE237',
 TOLERANCE='10%',
 MATERIAL='EMPTY',
 BOM_COST='P1V8_PCH_STBY_VR',
 PHYS_PAGE='237',
 XY='(-1500,2200)',
 ROT='2',
 VER='1',
 VALUE='1000PF',
 PACK_TYPE='0402LF',
 PART_NUMBER='A36096-046',
 LOCATION='C8A10',
 ROOM='P1V8_PCH_STBY_VR',
 CDS_LIB='mstr_discrete',
 CDS_PART_NAME='CAP_0402LF-1000PF,50V,10%,EMPTA',
 VOLTAGE='50V',
 PRIM_FILE='./archive_libs/mstr_discrete/cap/chips/chips.prt';

PART_NAME
 C8A11 'CAP_0402LF-1000PF,50V,10%,X7R,A':
 ROOM='P1V8_PCH_STBY_VR';

SECTION_NUMBER 1
 '@BASEBOARD_FAB2_LIB.BASEBOARD_FAB2(SCH_1):PAGE237_I5@MSTR_DISCRETE.CAP(CHIPS)':
 C_PATH='@baseboard_fab2_lib.baseboard_fab2(sch_1):page237_i5@mstr_discrete.cap(~
chips)',
 P_PATH='@baseboard_fab2_lib.baseboard_fab2(sch_1):page237_i5@mstr_discrete.cap(~
chips)',
 PATH='I5',
 DRAWING='@BASEBOARD_FAB2_LIB.BASEBOARD_FAB2(SCH_1):PAGE237',
 TOLERANCE='10%',
 MATERIAL='X7R',
 BOM_COST='P1V8_PCH_STBY_VR',
 PHYS_PAGE='237',
 XY='(1350,3475)',
 ROT='0',
 VER='1',
 VALUE='1000PF',
 PACK_TYPE='0402LF',
 PART_NUMBER='A36096-046',
 LOCATION='C8A11',
 ROOM='P1V8_PCH_STBY_VR',
 CDS_LIB='mstr_discrete',
 CDS_PART_NAME='CAP_0402LF-1000PF,50V,10%,X7R,A',
 VOLTAGE='50V',
 PRIM_FILE='./archive_libs/mstr_discrete/cap/chips/chips.prt';

PART_NAME
 C8A12 'CAP_0805-47UF,4V,20%,X6S,C9533A':
 ROOM='P1V8_PCH_STBY_VR';

SECTION_NUMBER 1
 '@BASEBOARD_FAB2_LIB.BASEBOARD_FAB2(SCH_1):PAGE237_I77@MSTR_DISCRETE.CAP(CHIPS)':
 C_PATH='@baseboard_fab2_lib.baseboard_fab2(sch_1):page237_i77@mstr_discrete.cap~
(chips)',
 P_PATH='@baseboard_fab2_lib.baseboard_fab2(sch_1):page237_i77@mstr_discrete.cap~
(chips)',
 PATH='I77',
 DRAWING='@BASEBOARD_FAB2_LIB.BASEBOARD_FAB2(SCH_1):PAGE237',
 TOLERANCE='20%',
 SEC_TYPE='0805',
 MATERIAL='X6S',
 PHYS_PAGE='237',
 XY='(3650,2200)',
 ROT='0',
 VER='1',
 VALUE='47UF',
 PACK_TYPE='0805',
 PART_NUMBER='C95333-006',
 LOCATION='C8A12',
 ROOM='P1V8_PCH_STBY_VR',
 SEC='1',
 CDS_LIB='mstr_discrete',
 CDS_PART_NAME='CAP_0805-47UF,4V,20%,X6S,C9533A',
 VOLTAGE='4V',
 PRIM_FILE='./archive_libs/mstr_discrete/cap/chips/chips.prt';

PART_NAME
 C8A13 'CAP_0805-47UF,4V,20%,X6S,C9533A':
 ROOM='SB_DECOUPLING';

SECTION_NUMBER 1
 '@BASEBOARD_FAB2_LIB.BASEBOARD_FAB2(SCH_1):PAGE131_I37@MSTR_DISCRETE.CAP(CHIPS)':
 C_PATH='@baseboard_fab2_lib.baseboard_fab2(sch_1):page131_i37@mstr_discrete.cap~
(chips)',
 P_PATH='@baseboard_fab2_lib.baseboard_fab2(sch_1):page131_i37@mstr_discrete.cap~
(chips)',
 PATH='I37',
 DRAWING='@BASEBOARD_FAB2_LIB.BASEBOARD_FAB2(SCH_1):PAGE131',
 TOLERANCE='20%',
 MATERIAL='X6S',
 BOM_COST='SB',
 PHYS_PAGE='131',
 XY='(-3250,2025)',
 ROT='0',
 VER='1',
 VALUE='47UF',
 PACK_TYPE='0805',
 PART_NUMBER='C95333-006',
 LOCATION='C8A13',
 ROOM='SB_DECOUPLING',
 CDS_LIB='mstr_discrete',
 CDS_PART_NAME='CAP_0805-47UF,4V,20%,X6S,C9533A',
 VOLTAGE='4V',
 PRIM_FILE='./archive_libs/mstr_discrete/cap/chips/chips.prt';

PART_NAME
 C8A14 'CAP_0805-22UF,6.3V,20%,X6S,C95A':
 ROOM='P1V8_PCH_STBY_VR';

SECTION_NUMBER 1
 '@BASEBOARD_FAB2_LIB.BASEBOARD_FAB2(SCH_1):PAGE237_I13@MSTR_DISCRETE.CAP(CHIPS)':
 C_PATH='@baseboard_fab2_lib.baseboard_fab2(sch_1):page237_i13@mstr_discrete.cap~
(chips)',
 P_PATH='@baseboard_fab2_lib.baseboard_fab2(sch_1):page237_i13@mstr_discrete.cap~
(chips)',
 PATH='I13',
 DRAWING='@BASEBOARD_FAB2_LIB.BASEBOARD_FAB2(SCH_1):PAGE237',
 TOLERANCE='20%',
 SEC_TYPE='0805',
 MATERIAL='X6S',
 BOM_COST='P1V8_PCH_STBY_VR',
 PHYS_PAGE='237',
 XY='(3100,2200)',
 ROT='0',
 VER='1',
 VALUE='22UF',
 PACK_TYPE='0805',
 PART_NUMBER='C95333-008',
 LOCATION='C8A14',
 ROOM='P1V8_PCH_STBY_VR',
 SEC='1',
 CDS_LIB='mstr_discrete',
 CDS_PART_NAME='CAP_0805-22UF,6.3V,20%,X6S,C95A',
 VOLTAGE='6.3V',
 PRIM_FILE='./archive_libs/mstr_discrete/cap/chips/chips.prt';

PART_NAME
 C8A15 'CAPP_SM-470UF,2V,20%,ALUM,6990A':
 ROOM='P1V05_PCH_STBY';

SECTION_NUMBER 1
 '@BASEBOARD_FAB2_LIB.BASEBOARD_FAB2(SCH_1):PAGE236_I78@MSTR_DISCRETE.CAPP(CHIPS)':
 C_PATH='@baseboard_fab2_lib.baseboard_fab2(sch_1):page236_i78@mstr_discrete.cap~
p(chips)',
 P_PATH='@baseboard_fab2_lib.baseboard_fab2(sch_1):page236_i78@mstr_discrete.cap~
p(chips)',
 PATH='I78',
 DRAWING='@BASEBOARD_FAB2_LIB.BASEBOARD_FAB2(SCH_1):PAGE236',
 TOLERANCE='20%',
 SEC_TYPE='SM',
 MATERIAL='ALUM',
 PHYS_PAGE='236',
 XY='(12425,2050)',
 ROT='0',
 VER='1',
 VALUE='470UF',
 PACK_TYPE='SM',
 PART_NUMBER='699013-031',
 LOCATION='C8A15',
 ROOM='P1V05_PCH_STBY',
 SEC='1',
 CDS_LIB='mstr_discrete',
 CDS_PART_NAME='CAPP_SM-470UF,2V,20%,ALUM,6990A',
 VOLTAGE='2V',
 PRIM_FILE='./archive_libs/mstr_discrete/capp/chips/chips.prt';

PART_NAME
 C8B1 'CAP_A_0603V-22.0UF,4V,20%,X6S,A':
 ROOM='SB_DECOUPLING';

SECTION_NUMBER 1
 '@BASEBOARD_FAB2_LIB.BASEBOARD_FAB2(SCH_1):PAGE130_I41@DEV_DISCRETE.CAP_A(CHIPS)':
 C_PATH='@baseboard_fab2_lib.baseboard_fab2(sch_1):page130_i41@dev_discrete.cap_~
a(chips)',
 P_PATH='@baseboard_fab2_lib.baseboard_fab2(sch_1):page130_i41@dev_discrete.cap_~
a(chips)',
 PATH='I41',
 DRAWING='@BASEBOARD_FAB2_LIB.BASEBOARD_FAB2(SCH_1):PAGE130',
 TOLERANCE='20%',
 MATERIAL='X6S',
 BOM_COST='SB',
 PHYS_PAGE='130',
 XY='(-4350,2750)',
 ROT='0',
 VER='1',
 VALUE='22.0UF',
 PACK_TYPE='0603V',
 PART_NUMBER='E15431-004',
 LOCATION='C8B1',
 ROOM='SB_DECOUPLING',
 CDS_LIB='dev_discrete',
 CDS_PART_NAME='CAP_A_0603V-22.0UF,4V,20%,X6S,A',
 VOLTAGE='4V',
 PRIM_FILE='./archive_libs/discrete/cap_a/chips/chips.prt';

PART_NAME
 C8B2 'CAP_A_0603V-22.0UF,4V,20%,X6S,A':
 ROOM='SB_DECOUPLING';

SECTION_NUMBER 1
 '@BASEBOARD_FAB2_LIB.BASEBOARD_FAB2(SCH_1):PAGE130_I30@DEV_DISCRETE.CAP_A(CHIPS)':
 C_PATH='@baseboard_fab2_lib.baseboard_fab2(sch_1):page130_i30@dev_discrete.cap_~
a(chips)',
 P_PATH='@baseboard_fab2_lib.baseboard_fab2(sch_1):page130_i30@dev_discrete.cap_~
a(chips)',
 PATH='I30',
 DRAWING='@BASEBOARD_FAB2_LIB.BASEBOARD_FAB2(SCH_1):PAGE130',
 TOLERANCE='20%',
 MATERIAL='X6S',
 BOM_COST='SB',
 PHYS_PAGE='130',
 XY='(-3100,2750)',
 ROT='0',
 VER='1',
 VALUE='22.0UF',
 PACK_TYPE='0603V',
 PART_NUMBER='E15431-004',
 LOCATION='C8B2',
 ROOM='SB_DECOUPLING',
 CDS_LIB='dev_discrete',
 CDS_PART_NAME='CAP_A_0603V-22.0UF,4V,20%,X6S,A',
 VOLTAGE='4V',
 PRIM_FILE='./archive_libs/discrete/cap_a/chips/chips.prt';

PART_NAME
 C8B3 'CAP_A_0603V-22.0UF,4V,20%,X6S,A':
 ROOM='SB_DECOUPLING';

SECTION_NUMBER 1
 '@BASEBOARD_FAB2_LIB.BASEBOARD_FAB2(SCH_1):PAGE130_I32@DEV_DISCRETE.CAP_A(CHIPS)':
 C_PATH='@baseboard_fab2_lib.baseboard_fab2(sch_1):page130_i32@dev_discrete.cap_~
a(chips)',
 P_PATH='@baseboard_fab2_lib.baseboard_fab2(sch_1):page130_i32@dev_discrete.cap_~
a(chips)',
 PATH='I32',
 DRAWING='@BASEBOARD_FAB2_LIB.BASEBOARD_FAB2(SCH_1):PAGE130',
 TOLERANCE='20%',
 MATERIAL='X6S',
 BOM_COST='SB',
 PHYS_PAGE='130',
 XY='(-1975,1900)',
 ROT='0',
 VER='1',
 VALUE='22.0UF',
 PACK_TYPE='0603V',
 PART_NUMBER='E15431-004',
 LOCATION='C8B3',
 ROOM='SB_DECOUPLING',
 CDS_LIB='dev_discrete',
 CDS_PART_NAME='CAP_A_0603V-22.0UF,4V,20%,X6S,A',
 VOLTAGE='4V',
 PRIM_FILE='./archive_libs/discrete/cap_a/chips/chips.prt';

PART_NAME
 C8B4 'CAP_A_0603V-22.0UF,4V,20%,X6S,A':
 ROOM='SB_DECOUPLING';

SECTION_NUMBER 1
 '@BASEBOARD_FAB2_LIB.BASEBOARD_FAB2(SCH_1):PAGE130_I39@DEV_DISCRETE.CAP_A(CHIPS)':
 C_PATH='@baseboard_fab2_lib.baseboard_fab2(sch_1):page130_i39@dev_discrete.cap_~
a(chips)',
 P_PATH='@baseboard_fab2_lib.baseboard_fab2(sch_1):page130_i39@dev_discrete.cap_~
a(chips)',
 PATH='I39',
 DRAWING='@BASEBOARD_FAB2_LIB.BASEBOARD_FAB2(SCH_1):PAGE130',
 TOLERANCE='20%',
 MATERIAL='X6S',
 BOM_COST='SB',
 PHYS_PAGE='130',
 XY='(-3925,2750)',
 ROT='0',
 VER='1',
 VALUE='22.0UF',
 PACK_TYPE='0603V',
 PART_NUMBER='E15431-004',
 LOCATION='C8B4',
 ROOM='SB_DECOUPLING',
 CDS_LIB='dev_discrete',
 CDS_PART_NAME='CAP_A_0603V-22.0UF,4V,20%,X6S,A',
 VOLTAGE='4V',
 PRIM_FILE='./archive_libs/discrete/cap_a/chips/chips.prt';

PART_NAME
 C8B5 'CAP_A_0402V-0.1UF,16V,10%,X7R,A':
 ROOM='P5V_PWR_SWITCH';

SECTION_NUMBER 1
 '@BASEBOARD_FAB2_LIB.BASEBOARD_FAB2(SCH_1):PAGE198_I37@DEV_DISCRETE.CAP_A(CHIPS)':
 C_PATH='@baseboard_fab2_lib.baseboard_fab2(sch_1):page198_i37@dev_discrete.cap_~
a(chips)',
 P_PATH='@baseboard_fab2_lib.baseboard_fab2(sch_1):page198_i37@dev_discrete.cap_~
a(chips)',
 PATH='I37',
 DRAWING='@BASEBOARD_FAB2_LIB.BASEBOARD_FAB2(SCH_1):PAGE198',
 TOLERANCE='10%',
 SEC_TYPE='0402V',
 MATERIAL='X7R',
 BOM_COST='PWR_SWITCH',
 PHYS_PAGE='198',
 XY='(-1050,4400)',
 ROT='0',
 VER='1',
 VALUE='0.1UF',
 PACK_TYPE='0402V',
 PART_NUMBER='A36096-030',
 LOCATION='C8B5',
 ROOM='P5V_PWR_SWITCH',
 SEC='1',
 CDS_LIB='dev_discrete',
 CDS_PART_NAME='CAP_A_0402V-0.1UF,16V,10%,X7R,A',
 VOLTAGE='16V',
 PRIM_FILE='./archive_libs/discrete/cap_a/chips/chips.prt';

PART_NAME
 C8B6 'CAP_0805-10UF,16V,10%,X6S,C953A':
 ROOM='P5V_PWR_SWITCH';

SECTION_NUMBER 1
 '@BASEBOARD_FAB2_LIB.BASEBOARD_FAB2(SCH_1):PAGE198_I40@MSTR_DISCRETE.CAP(CHIPS)':
 C_PATH='@baseboard_fab2_lib.baseboard_fab2(sch_1):page198_i40@mstr_discrete.cap~
(chips)',
 P_PATH='@baseboard_fab2_lib.baseboard_fab2(sch_1):page198_i40@mstr_discrete.cap~
(chips)',
 PATH='I40',
 DRAWING='@BASEBOARD_FAB2_LIB.BASEBOARD_FAB2(SCH_1):PAGE198',
 TOLERANCE='10%',
 SEC_TYPE='0805',
 MATERIAL='X6S',
 PHYS_PAGE='198',
 XY='(-1100,3250)',
 ROT='0',
 VER='1',
 VALUE='10UF',
 PACK_TYPE='0805',
 PART_NUMBER='C95333-007',
 LOCATION='C8B6',
 ROOM='P5V_PWR_SWITCH',
 SEC='1',
 CDS_LIB='mstr_discrete',
 CDS_PART_NAME='CAP_0805-10UF,16V,10%,X6S,C953A',
 VOLTAGE='16V',
 PRIM_FILE='./archive_libs/mstr_discrete/cap/chips/chips.prt';

PART_NAME
 C8B7 'CAP_A_0402V-0.1UF,16V,10%,X7R,A':
 ROOM='P5V_PWR_SWITCH';

SECTION_NUMBER 1
 '@BASEBOARD_FAB2_LIB.BASEBOARD_FAB2(SCH_1):PAGE198_I41@DEV_DISCRETE.CAP_A(CHIPS)':
 C_PATH='@baseboard_fab2_lib.baseboard_fab2(sch_1):page198_i41@dev_discrete.cap_~
a(chips)',
 P_PATH='@baseboard_fab2_lib.baseboard_fab2(sch_1):page198_i41@dev_discrete.cap_~
a(chips)',
 PATH='I41',
 DRAWING='@BASEBOARD_FAB2_LIB.BASEBOARD_FAB2(SCH_1):PAGE198',
 TOLERANCE='10%',
 SEC_TYPE='0402V',
 MATERIAL='X7R',
 BOM_COST='PWR_SWITCH',
 PHYS_PAGE='198',
 XY='(-775,3250)',
 ROT='0',
 VER='1',
 VALUE='0.1UF',
 PACK_TYPE='0402V',
 PART_NUMBER='A36096-030',
 LOCATION='C8B7',
 ROOM='P5V_PWR_SWITCH',
 SEC='1',
 CDS_LIB='dev_discrete',
 CDS_PART_NAME='CAP_A_0402V-0.1UF,16V,10%,X7R,A',
 VOLTAGE='16V',
 PRIM_FILE='./archive_libs/discrete/cap_a/chips/chips.prt';

PART_NAME
 C8B8 'CAP_A_0402V-0.1UF,16V,10%,X7R,A':
 ROOM='P5V_PWR_SWITCH';

SECTION_NUMBER 1
 '@BASEBOARD_FAB2_LIB.BASEBOARD_FAB2(SCH_1):PAGE198_I26@DEV_DISCRETE.CAP_A(CHIPS)':
 C_PATH='@baseboard_fab2_lib.baseboard_fab2(sch_1):page198_i26@dev_discrete.cap_~
a(chips)',
 P_PATH='@baseboard_fab2_lib.baseboard_fab2(sch_1):page198_i26@dev_discrete.cap_~
a(chips)',
 PATH='I26',
 DRAWING='@BASEBOARD_FAB2_LIB.BASEBOARD_FAB2(SCH_1):PAGE198',
 TOLERANCE='10%',
 SEC_TYPE='0402V',
 MATERIAL='X7R',
 PHYS_PAGE='198',
 XY='(-4300,4125)',
 ROT='0',
 VER='1',
 VALUE='0.1UF',
 PACK_TYPE='0402V',
 PART_NUMBER='A36096-030',
 LOCATION='C8B8',
 ROOM='P5V_PWR_SWITCH',
 SEC='1',
 CDS_LIB='dev_discrete',
 CDS_PART_NAME='CAP_A_0402V-0.1UF,16V,10%,X7R,A',
 VOLTAGE='16V',
 PRIM_FILE='./archive_libs/discrete/cap_a/chips/chips.prt';

PART_NAME
 C8B9 'CAP_A_0603V-22.0UF,4V,20%,X6S,A':
 ROOM='SB_DECOUPLING';

SECTION_NUMBER 1
 '@BASEBOARD_FAB2_LIB.BASEBOARD_FAB2(SCH_1):PAGE131_I14@DEV_DISCRETE.CAP_A(CHIPS)':
 C_PATH='@baseboard_fab2_lib.baseboard_fab2(sch_1):page131_i14@dev_discrete.cap_~
a(chips)',
 P_PATH='@baseboard_fab2_lib.baseboard_fab2(sch_1):page131_i14@dev_discrete.cap_~
a(chips)',
 PATH='I14',
 DRAWING='@BASEBOARD_FAB2_LIB.BASEBOARD_FAB2(SCH_1):PAGE131',
 TOLERANCE='20%',
 MATERIAL='X6S',
 BOM_COST='SB',
 PHYS_PAGE='131',
 XY='(500,3025)',
 ROT='0',
 VER='1',
 VALUE='22.0UF',
 PACK_TYPE='0603V',
 PART_NUMBER='E15431-004',
 LOCATION='C8B9',
 ROOM='SB_DECOUPLING',
 CDS_LIB='dev_discrete',
 CDS_PART_NAME='CAP_A_0603V-22.0UF,4V,20%,X6S,A',
 VOLTAGE='4V',
 PRIM_FILE='./archive_libs/discrete/cap_a/chips/chips.prt';

PART_NAME
 C8B10 'CAP_A_0603V-22.0UF,4V,20%,X6S,A':
 ROOM='SB_DECOUPLING';

SECTION_NUMBER 1
 '@BASEBOARD_FAB2_LIB.BASEBOARD_FAB2(SCH_1):PAGE131_I8@DEV_DISCRETE.CAP_A(CHIPS)':
 C_PATH='@baseboard_fab2_lib.baseboard_fab2(sch_1):page131_i8@dev_discrete.cap_a~
(chips)',
 P_PATH='@baseboard_fab2_lib.baseboard_fab2(sch_1):page131_i8@dev_discrete.cap_a~
(chips)',
 PATH='I8',
 DRAWING='@BASEBOARD_FAB2_LIB.BASEBOARD_FAB2(SCH_1):PAGE131',
 TOLERANCE='20%',
 MATERIAL='X6S',
 BOM_COST='SB',
 PHYS_PAGE='131',
 XY='(950,3025)',
 ROT='0',
 VER='1',
 VALUE='22.0UF',
 PACK_TYPE='0603V',
 PART_NUMBER='E15431-004',
 LOCATION='C8B10',
 ROOM='SB_DECOUPLING',
 CDS_LIB='dev_discrete',
 CDS_PART_NAME='CAP_A_0603V-22.0UF,4V,20%,X6S,A',
 VOLTAGE='4V',
 PRIM_FILE='./archive_libs/discrete/cap_a/chips/chips.prt';

PART_NAME
 C8B11 'CAP_A_0603V-22.0UF,4V,20%,X6S,A':
 ROOM='SB_DECOUPLING';

SECTION_NUMBER 1
 '@BASEBOARD_FAB2_LIB.BASEBOARD_FAB2(SCH_1):PAGE131_I15@DEV_DISCRETE.CAP_A(CHIPS)':
 C_PATH='@baseboard_fab2_lib.baseboard_fab2(sch_1):page131_i15@dev_discrete.cap_~
a(chips)',
 P_PATH='@baseboard_fab2_lib.baseboard_fab2(sch_1):page131_i15@dev_discrete.cap_~
a(chips)',
 PATH='I15',
 DRAWING='@BASEBOARD_FAB2_LIB.BASEBOARD_FAB2(SCH_1):PAGE131',
 TOLERANCE='20%',
 MATERIAL='X6S',
 BOM_COST='SB',
 PHYS_PAGE='131',
 XY='(50,3025)',
 ROT='0',
 VER='1',
 VALUE='22.0UF',
 PACK_TYPE='0603V',
 PART_NUMBER='E15431-004',
 LOCATION='C8B11',
 ROOM='SB_DECOUPLING',
 CDS_LIB='dev_discrete',
 CDS_PART_NAME='CAP_A_0603V-22.0UF,4V,20%,X6S,A',
 VOLTAGE='4V',
 PRIM_FILE='./archive_libs/discrete/cap_a/chips/chips.prt';

PART_NAME
 C8B12 'CAP_0805-10UF,16V,10%,X6S,C953A':
 ROOM='P5V_PWR_SWITCH';

SECTION_NUMBER 1
 '@BASEBOARD_FAB2_LIB.BASEBOARD_FAB2(SCH_1):PAGE198_I38@MSTR_DISCRETE.CAP(CHIPS)':
 C_PATH='@baseboard_fab2_lib.baseboard_fab2(sch_1):page198_i38@mstr_discrete.cap~
(chips)',
 P_PATH='@baseboard_fab2_lib.baseboard_fab2(sch_1):page198_i38@mstr_discrete.cap~
(chips)',
 PATH='I38',
 DRAWING='@BASEBOARD_FAB2_LIB.BASEBOARD_FAB2(SCH_1):PAGE198',
 TOLERANCE='10%',
 SEC_TYPE='0805',
 MATERIAL='X6S',
 PHYS_PAGE='198',
 XY='(-1375,4400)',
 ROT='0',
 VER='1',
 VALUE='10UF',
 PACK_TYPE='0805',
 PART_NUMBER='C95333-007',
 LOCATION='C8B12',
 ROOM='P5V_PWR_SWITCH',
 SEC='1',
 CDS_LIB='mstr_discrete',
 CDS_PART_NAME='CAP_0805-10UF,16V,10%,X6S,C953A',
 VOLTAGE='16V',
 PRIM_FILE='./archive_libs/mstr_discrete/cap/chips/chips.prt';

PART_NAME
 C8B13 'CAP_A_0603V-22.0UF,4V,20%,X6S,A':
 ROOM='SB_DECOUPLING';

SECTION_NUMBER 1
 '@BASEBOARD_FAB2_LIB.BASEBOARD_FAB2(SCH_1):PAGE131_I20@DEV_DISCRETE.CAP_A(CHIPS)':
 C_PATH='@baseboard_fab2_lib.baseboard_fab2(sch_1):page131_i20@dev_discrete.cap_~
a(chips)',
 P_PATH='@baseboard_fab2_lib.baseboard_fab2(sch_1):page131_i20@dev_discrete.cap_~
a(chips)',
 PATH='I20',
 DRAWING='@BASEBOARD_FAB2_LIB.BASEBOARD_FAB2(SCH_1):PAGE131',
 TOLERANCE='20%',
 MATERIAL='X6S',
 BOM_COST='SB',
 PHYS_PAGE='131',
 XY='(-850,3025)',
 ROT='0',
 VER='1',
 VALUE='22.0UF',
 PACK_TYPE='0603V',
 PART_NUMBER='E15431-004',
 LOCATION='C8B13',
 ROOM='SB_DECOUPLING',
 CDS_LIB='dev_discrete',
 CDS_PART_NAME='CAP_A_0603V-22.0UF,4V,20%,X6S,A',
 VOLTAGE='4V',
 PRIM_FILE='./archive_libs/discrete/cap_a/chips/chips.prt';

PART_NAME
 C8B14 'CAP_A_0603V-22.0UF,4V,20%,X6S,A':
 ROOM='SB_DECOUPLING';

SECTION_NUMBER 1
 '@BASEBOARD_FAB2_LIB.BASEBOARD_FAB2(SCH_1):PAGE131_I16@DEV_DISCRETE.CAP_A(CHIPS)':
 C_PATH='@baseboard_fab2_lib.baseboard_fab2(sch_1):page131_i16@dev_discrete.cap_~
a(chips)',
 P_PATH='@baseboard_fab2_lib.baseboard_fab2(sch_1):page131_i16@dev_discrete.cap_~
a(chips)',
 PATH='I16',
 DRAWING='@BASEBOARD_FAB2_LIB.BASEBOARD_FAB2(SCH_1):PAGE131',
 TOLERANCE='20%',
 MATERIAL='X6S',
 BOM_COST='SB',
 PHYS_PAGE='131',
 XY='(-400,3025)',
 ROT='0',
 VER='1',
 VALUE='22.0UF',
 PACK_TYPE='0603V',
 PART_NUMBER='E15431-004',
 LOCATION='C8B14',
 ROOM='SB_DECOUPLING',
 CDS_LIB='dev_discrete',
 CDS_PART_NAME='CAP_A_0603V-22.0UF,4V,20%,X6S,A',
 VOLTAGE='4V',
 PRIM_FILE='./archive_libs/discrete/cap_a/chips/chips.prt';

PART_NAME
 C8B15 'CAP_0805-47UF,4V,20%,X6S,C9533A':
 ROOM='SB_DECOUPLING';

SECTION_NUMBER 1
 '@BASEBOARD_FAB2_LIB.BASEBOARD_FAB2(SCH_1):PAGE131_I24@MSTR_DISCRETE.CAP(CHIPS)':
 C_PATH='@baseboard_fab2_lib.baseboard_fab2(sch_1):page131_i24@mstr_discrete.cap~
(chips)',
 P_PATH='@baseboard_fab2_lib.baseboard_fab2(sch_1):page131_i24@mstr_discrete.cap~
(chips)',
 PATH='I24',
 DRAWING='@BASEBOARD_FAB2_LIB.BASEBOARD_FAB2(SCH_1):PAGE131',
 TOLERANCE='20%',
 MATERIAL='X6S',
 BOM_COST='SB',
 PHYS_PAGE='131',
 XY='(-400,2025)',
 ROT='0',
 VER='1',
 VALUE='47UF',
 PACK_TYPE='0805',
 PART_NUMBER='C95333-006',
 LOCATION='C8B15',
 ROOM='SB_DECOUPLING',
 CDS_LIB='mstr_discrete',
 CDS_PART_NAME='CAP_0805-47UF,4V,20%,X6S,C9533A',
 VOLTAGE='4V',
 PRIM_FILE='./archive_libs/mstr_discrete/cap/chips/chips.prt';

PART_NAME
 C8B16 'CAP_0805-47UF,4V,20%,X6S,C9533A':
 ROOM='SB_DECOUPLING';

SECTION_NUMBER 1
 '@BASEBOARD_FAB2_LIB.BASEBOARD_FAB2(SCH_1):PAGE131_I22@MSTR_DISCRETE.CAP(CHIPS)':
 C_PATH='@baseboard_fab2_lib.baseboard_fab2(sch_1):page131_i22@mstr_discrete.cap~
(chips)',
 P_PATH='@baseboard_fab2_lib.baseboard_fab2(sch_1):page131_i22@mstr_discrete.cap~
(chips)',
 PATH='I22',
 DRAWING='@BASEBOARD_FAB2_LIB.BASEBOARD_FAB2(SCH_1):PAGE131',
 TOLERANCE='20%',
 MATERIAL='X6S',
 BOM_COST='SB',
 PHYS_PAGE='131',
 XY='(50,2025)',
 ROT='0',
 VER='1',
 VALUE='47UF',
 PACK_TYPE='0805',
 PART_NUMBER='C95333-006',
 LOCATION='C8B16',
 ROOM='SB_DECOUPLING',
 CDS_LIB='mstr_discrete',
 CDS_PART_NAME='CAP_0805-47UF,4V,20%,X6S,C9533A',
 VOLTAGE='4V',
 PRIM_FILE='./archive_libs/mstr_discrete/cap/chips/chips.prt';

PART_NAME
 C8C1 'CAP_0402LF-33.0PF,50V,5%,COG,AA':;

SECTION_NUMBER 1
 '@BASEBOARD_FAB2_LIB.BASEBOARD_FAB2(SCH_1):PAGE118_I178@MSTR_DISCRETE.CAP(CHIPS)':
 C_PATH='@baseboard_fab2_lib.baseboard_fab2(sch_1):page118_i178@mstr_discrete.ca~
p(chips)',
 P_PATH='@baseboard_fab2_lib.baseboard_fab2(sch_1):page118_i178@mstr_discrete.ca~
p(chips)',
 PATH='I178',
 DRAWING='@BASEBOARD_FAB2_LIB.BASEBOARD_FAB2(SCH_1):PAGE118',
 TOLERANCE='5%',
 SEC_TYPE='0402LF',
 MATERIAL='COG',
 PHYS_PAGE='118',
 XY='(-7700,600)',
 ROT='0',
 VER='1',
 VALUE='33.0PF',
 PACK_TYPE='0402LF',
 PART_NUMBER='A36095-031',
 LOCATION='C8C1',
 SEC='1',
 CDS_LIB='mstr_discrete',
 CDS_PART_NAME='CAP_0402LF-33.0PF,50V,5%,COG,AA',
 VOLTAGE='50V',
 PRIM_FILE='./archive_libs/mstr_discrete/cap/chips/chips.prt';

PART_NAME
 C8C2 'CAP_0402LF-33.0PF,50V,5%,COG,AA':;

SECTION_NUMBER 1
 '@BASEBOARD_FAB2_LIB.BASEBOARD_FAB2(SCH_1):PAGE118_I179@MSTR_DISCRETE.CAP(CHIPS)':
 C_PATH='@baseboard_fab2_lib.baseboard_fab2(sch_1):page118_i179@mstr_discrete.ca~
p(chips)',
 P_PATH='@baseboard_fab2_lib.baseboard_fab2(sch_1):page118_i179@mstr_discrete.ca~
p(chips)',
 PATH='I179',
 DRAWING='@BASEBOARD_FAB2_LIB.BASEBOARD_FAB2(SCH_1):PAGE118',
 TOLERANCE='5%',
 SEC_TYPE='0402LF',
 MATERIAL='COG',
 PHYS_PAGE='118',
 XY='(-7250,600)',
 ROT='0',
 VER='1',
 VALUE='33.0PF',
 PACK_TYPE='0402LF',
 PART_NUMBER='A36095-031',
 LOCATION='C8C2',
 SEC='1',
 CDS_LIB='mstr_discrete',
 CDS_PART_NAME='CAP_0402LF-33.0PF,50V,5%,COG,AA',
 VOLTAGE='50V',
 PRIM_FILE='./archive_libs/mstr_discrete/cap/chips/chips.prt';

PART_NAME
 C8C3 'CAP_0603-10UF,6.3V,20%,X6S,E15A':
 ROOM='SB_DECOUPLING';

SECTION_NUMBER 1
 '@BASEBOARD_FAB2_LIB.BASEBOARD_FAB2(SCH_1):PAGE130_I19@MSTR_DISCRETE.CAP(CHIPS)':
 C_PATH='@baseboard_fab2_lib.baseboard_fab2(sch_1):page130_i19@mstr_discrete.cap~
(chips)',
 P_PATH='@baseboard_fab2_lib.baseboard_fab2(sch_1):page130_i19@mstr_discrete.cap~
(chips)',
 PATH='I19',
 DRAWING='@BASEBOARD_FAB2_LIB.BASEBOARD_FAB2(SCH_1):PAGE130',
 TOLERANCE='20%',
 MATERIAL='X6S',
 BOM_COST='SB',
 PHYS_PAGE='130',
 XY='(-2550,4925)',
 ROT='0',
 VER='1',
 VALUE='10UF',
 PACK_TYPE='0603',
 PART_NUMBER='E15431-002',
 LOCATION='C8C3',
 ROOM='SB_DECOUPLING',
 CDS_LIB='mstr_discrete',
 CDS_PART_NAME='CAP_0603-10UF,6.3V,20%,X6S,E15A',
 VOLTAGE='6.3V',
 PRIM_FILE='./archive_libs/mstr_discrete/cap/chips/chips.prt';

PART_NAME
 C8C4 'CAP_0603-10UF,6.3V,20%,X6S,E15A':
 ROOM='SB_DECOUPLING';

SECTION_NUMBER 1
 '@BASEBOARD_FAB2_LIB.BASEBOARD_FAB2(SCH_1):PAGE130_I20@MSTR_DISCRETE.CAP(CHIPS)':
 C_PATH='@baseboard_fab2_lib.baseboard_fab2(sch_1):page130_i20@mstr_discrete.cap~
(chips)',
 P_PATH='@baseboard_fab2_lib.baseboard_fab2(sch_1):page130_i20@mstr_discrete.cap~
(chips)',
 PATH='I20',
 DRAWING='@BASEBOARD_FAB2_LIB.BASEBOARD_FAB2(SCH_1):PAGE130',
 TOLERANCE='20%',
 MATERIAL='X6S',
 BOM_COST='SB',
 PHYS_PAGE='130',
 XY='(-2975,4925)',
 ROT='0',
 VER='1',
 VALUE='10UF',
 PACK_TYPE='0603',
 PART_NUMBER='E15431-002',
 LOCATION='C8C4',
 ROOM='SB_DECOUPLING',
 CDS_LIB='mstr_discrete',
 CDS_PART_NAME='CAP_0603-10UF,6.3V,20%,X6S,E15A',
 VOLTAGE='6.3V',
 PRIM_FILE='./archive_libs/mstr_discrete/cap/chips/chips.prt';

PART_NAME
 C8C5 'CAP_0603-10UF,6.3V,20%,X6S,E15A':
 ROOM='SB_DECOUPLING';

SECTION_NUMBER 1
 '@BASEBOARD_FAB2_LIB.BASEBOARD_FAB2(SCH_1):PAGE130_I21@MSTR_DISCRETE.CAP(CHIPS)':
 C_PATH='@baseboard_fab2_lib.baseboard_fab2(sch_1):page130_i21@mstr_discrete.cap~
(chips)',
 P_PATH='@baseboard_fab2_lib.baseboard_fab2(sch_1):page130_i21@mstr_discrete.cap~
(chips)',
 PATH='I21',
 DRAWING='@BASEBOARD_FAB2_LIB.BASEBOARD_FAB2(SCH_1):PAGE130',
 TOLERANCE='20%',
 MATERIAL='X6S',
 BOM_COST='SB',
 PHYS_PAGE='130',
 XY='(-3375,4925)',
 ROT='0',
 VER='1',
 VALUE='10UF',
 PACK_TYPE='0603',
 PART_NUMBER='E15431-002',
 LOCATION='C8C5',
 ROOM='SB_DECOUPLING',
 CDS_LIB='mstr_discrete',
 CDS_PART_NAME='CAP_0603-10UF,6.3V,20%,X6S,E15A',
 VOLTAGE='6.3V',
 PRIM_FILE='./archive_libs/mstr_discrete/cap/chips/chips.prt';

PART_NAME
 C8C6 'CAP_0603-10UF,6.3V,20%,X6S,E15A':
 ROOM='SB_DECOUPLING';

SECTION_NUMBER 1
 '@BASEBOARD_FAB2_LIB.BASEBOARD_FAB2(SCH_1):PAGE130_I22@MSTR_DISCRETE.CAP(CHIPS)':
 C_PATH='@baseboard_fab2_lib.baseboard_fab2(sch_1):page130_i22@mstr_discrete.cap~
(chips)',
 P_PATH='@baseboard_fab2_lib.baseboard_fab2(sch_1):page130_i22@mstr_discrete.cap~
(chips)',
 PATH='I22',
 DRAWING='@BASEBOARD_FAB2_LIB.BASEBOARD_FAB2(SCH_1):PAGE130',
 TOLERANCE='20%',
 MATERIAL='X6S',
 BOM_COST='SB',
 PHYS_PAGE='130',
 XY='(-3775,4925)',
 ROT='0',
 VER='1',
 VALUE='10UF',
 PACK_TYPE='0603',
 PART_NUMBER='E15431-002',
 LOCATION='C8C6',
 ROOM='SB_DECOUPLING',
 CDS_LIB='mstr_discrete',
 CDS_PART_NAME='CAP_0603-10UF,6.3V,20%,X6S,E15A',
 VOLTAGE='6.3V',
 PRIM_FILE='./archive_libs/mstr_discrete/cap/chips/chips.prt';

PART_NAME
 C8C12 'CAP_A_0402V-0.1UF,16V,10%,X7R,A':;

SECTION_NUMBER 1
 '@BASEBOARD_FAB2_LIB.BASEBOARD_FAB2(SCH_1):PAGE188_I121@DEV_DISCRETE.CAP_A(CHIPS)':
 C_PATH='@baseboard_fab2_lib.baseboard_fab2(sch_1):page188_i121@dev_discrete.cap~
_a(chips)',
 P_PATH='@baseboard_fab2_lib.baseboard_fab2(sch_1):page188_i121@dev_discrete.cap~
_a(chips)',
 PATH='I121',
 DRAWING='@BASEBOARD_FAB2_LIB.BASEBOARD_FAB2(SCH_1):PAGE188',
 TOLERANCE='10%',
 SEC_TYPE='0402V',
 MATERIAL='X7R',
 PHYS_PAGE='188',
 XY='(3075,3700)',
 ROT='0',
 VER='2',
 VALUE='0.1UF',
 PACK_TYPE='0402V',
 PART_NUMBER='A36096-030',
 LOCATION='C8C12',
 SEC='1',
 CDS_LIB='dev_discrete',
 CDS_PART_NAME='CAP_A_0402V-0.1UF,16V,10%,X7R,A',
 VOLTAGE='16V',
 PRIM_FILE='./archive_libs/discrete/cap_a/chips/chips.prt';

PART_NAME
 C8C13 'CAP_A_0402V-0.1UF,16V,10%,X7R,A':;

SECTION_NUMBER 1
 '@BASEBOARD_FAB2_LIB.BASEBOARD_FAB2(SCH_1):PAGE188_I120@DEV_DISCRETE.CAP_A(CHIPS)':
 C_PATH='@baseboard_fab2_lib.baseboard_fab2(sch_1):page188_i120@dev_discrete.cap~
_a(chips)',
 P_PATH='@baseboard_fab2_lib.baseboard_fab2(sch_1):page188_i120@dev_discrete.cap~
_a(chips)',
 PATH='I120',
 DRAWING='@BASEBOARD_FAB2_LIB.BASEBOARD_FAB2(SCH_1):PAGE188',
 TOLERANCE='10%',
 SEC_TYPE='0402V',
 MATERIAL='X7R',
 PHYS_PAGE='188',
 XY='(3075,3375)',
 ROT='0',
 VER='2',
 VALUE='0.1UF',
 PACK_TYPE='0402V',
 PART_NUMBER='A36096-030',
 LOCATION='C8C13',
 SEC='1',
 CDS_LIB='dev_discrete',
 CDS_PART_NAME='CAP_A_0402V-0.1UF,16V,10%,X7R,A',
 VOLTAGE='16V',
 PRIM_FILE='./archive_libs/discrete/cap_a/chips/chips.prt';

PART_NAME
 C8C14 'CAP_A_0402V-0.1UF,16V,10%,X7R,A':;

SECTION_NUMBER 1
 '@BASEBOARD_FAB2_LIB.BASEBOARD_FAB2(SCH_1):PAGE188_I86@DEV_DISCRETE.CAP_A(CHIPS)':
 C_PATH='@baseboard_fab2_lib.baseboard_fab2(sch_1):page188_i86@dev_discrete.cap_~
a(chips)',
 P_PATH='@baseboard_fab2_lib.baseboard_fab2(sch_1):page188_i86@dev_discrete.cap_~
a(chips)',
 PATH='I86',
 DRAWING='@BASEBOARD_FAB2_LIB.BASEBOARD_FAB2(SCH_1):PAGE188',
 TOLERANCE='10%',
 SEC_TYPE='0402V',
 MATERIAL='X7R',
 PHYS_PAGE='188',
 XY='(3075,2600)',
 ROT='0',
 VER='2',
 VALUE='0.1UF',
 PACK_TYPE='0402V',
 PART_NUMBER='A36096-030',
 LOCATION='C8C14',
 SEC='1',
 CDS_LIB='dev_discrete',
 CDS_PART_NAME='CAP_A_0402V-0.1UF,16V,10%,X7R,A',
 VOLTAGE='16V',
 PRIM_FILE='./archive_libs/discrete/cap_a/chips/chips.prt';

PART_NAME
 C8C15 'CAP_A_0402V-0.1UF,16V,10%,X7R,A':;

SECTION_NUMBER 1
 '@BASEBOARD_FAB2_LIB.BASEBOARD_FAB2(SCH_1):PAGE188_I82@DEV_DISCRETE.CAP_A(CHIPS)':
 C_PATH='@baseboard_fab2_lib.baseboard_fab2(sch_1):page188_i82@dev_discrete.cap_~
a(chips)',
 P_PATH='@baseboard_fab2_lib.baseboard_fab2(sch_1):page188_i82@dev_discrete.cap_~
a(chips)',
 PATH='I82',
 DRAWING='@BASEBOARD_FAB2_LIB.BASEBOARD_FAB2(SCH_1):PAGE188',
 TOLERANCE='10%',
 SEC_TYPE='0402V',
 MATERIAL='X7R',
 PHYS_PAGE='188',
 XY='(3075,2925)',
 ROT='0',
 VER='2',
 VALUE='0.1UF',
 PACK_TYPE='0402V',
 PART_NUMBER='A36096-030',
 LOCATION='C8C15',
 SEC='1',
 CDS_LIB='dev_discrete',
 CDS_PART_NAME='CAP_A_0402V-0.1UF,16V,10%,X7R,A',
 VOLTAGE='16V',
 PRIM_FILE='./archive_libs/discrete/cap_a/chips/chips.prt';

PART_NAME
 C8D1 'CAP_A_0402V-0.1UF,16V,10%,X7R,A':;

SECTION_NUMBER 1
 '@BASEBOARD_FAB2_LIB.BASEBOARD_FAB2(SCH_1):PAGE157_I376@DEV_DISCRETE.CAP_A(CHIPS)':
 C_PATH='@baseboard_fab2_lib.baseboard_fab2(sch_1):page157_i376@dev_discrete.cap~
_a(chips)',
 P_PATH='@baseboard_fab2_lib.baseboard_fab2(sch_1):page157_i376@dev_discrete.cap~
_a(chips)',
 PATH='I376',
 DRAWING='@BASEBOARD_FAB2_LIB.BASEBOARD_FAB2(SCH_1):PAGE157',
 TOLERANCE='10%',
 SEC_TYPE='0402V',
 MATERIAL='X7R',
 PHYS_PAGE='157',
 XY='(-500,1750)',
 ROT='0',
 VER='1',
 VALUE='0.1UF',
 PACK_TYPE='0402V',
 PART_NUMBER='A36096-030',
 LOCATION='C8D1',
 SEC='1',
 CDS_LIB='dev_discrete',
 CDS_PART_NAME='CAP_A_0402V-0.1UF,16V,10%,X7R,A',
 VOLTAGE='16V',
 PRIM_FILE='./archive_libs/discrete/cap_a/chips/chips.prt';

PART_NAME
 C8D2 'CAP_A_0402V-0.1UF,16V,10%,X7R,A':
 ROOM='FAST_PROCHOT';

SECTION_NUMBER 1
 '@BASEBOARD_FAB2_LIB.BASEBOARD_FAB2(SCH_1):PAGE170_I33@DEV_DISCRETE.CAP_A(CHIPS)':
 C_PATH='@baseboard_fab2_lib.baseboard_fab2(sch_1):page170_i33@dev_discrete.cap_~
a(chips)',
 P_PATH='@baseboard_fab2_lib.baseboard_fab2(sch_1):page170_i33@dev_discrete.cap_~
a(chips)',
 PATH='I33',
 DRAWING='@BASEBOARD_FAB2_LIB.BASEBOARD_FAB2(SCH_1):PAGE170',
 TOLERANCE='10%',
 SEC_TYPE='0402V',
 MATERIAL='X7R',
 BOM_COST='FAST_PROCHOT',
 PHYS_PAGE='170',
 XY='(-200,4775)',
 ROT='0',
 VER='1',
 VALUE='0.1UF',
 PACK_TYPE='0402V',
 PART_NUMBER='A36096-030',
 LOCATION='C8D2',
 ROOM='FAST_PROCHOT',
 SEC='1',
 CDS_LIB='dev_discrete',
 CDS_PART_NAME='CAP_A_0402V-0.1UF,16V,10%,X7R,A',
 VOLTAGE='16V',
 PRIM_FILE='./archive_libs/discrete/cap_a/chips/chips.prt';

PART_NAME
 C8D3 'CAP_0402LF-470PF,50V,10%,EMPTYA':
 ROOM='PROC_SIDEBAND';

SECTION_NUMBER 1
 '@BASEBOARD_FAB2_LIB.BASEBOARD_FAB2(SCH_1):PAGE170_I42@MSTR_DISCRETE.CAP(CHIPS)':
 C_PATH='@baseboard_fab2_lib.baseboard_fab2(sch_1):page170_i42@mstr_discrete.cap~
(chips)',
 P_PATH='@baseboard_fab2_lib.baseboard_fab2(sch_1):page170_i42@mstr_discrete.cap~
(chips)',
 PATH='I42',
 DRAWING='@BASEBOARD_FAB2_LIB.BASEBOARD_FAB2(SCH_1):PAGE170',
 TOLERANCE='10%',
 SEC_TYPE='0402LF',
 MATERIAL='EMPTY',
 BOM_COST='PROC_SIDEBAND',
 PHYS_PAGE='170',
 XY='(-3700,4250)',
 ROT='0',
 VER='1',
 VALUE='470PF',
 PACK_TYPE='0402LF',
 PART_NUMBER='A36096-049',
 LOCATION='C8D3',
 ROOM='PROC_SIDEBAND',
 SEC='1',
 CDS_LIB='mstr_discrete',
 CDS_PART_NAME='CAP_0402LF-470PF,50V,10%,EMPTYA',
 VOLTAGE='50V',
 PRIM_FILE='./archive_libs/mstr_discrete/cap/chips/chips.prt';

PART_NAME
 C8D4 'CAP_A_0402V-0.1UF,16V,10%,X7R,A':
 ROOM='V_SUPER';

SECTION_NUMBER 1
 '@BASEBOARD_FAB2_LIB.BASEBOARD_FAB2(SCH_1):PAGE196_I105@DEV_DISCRETE.CAP_A(CHIPS)':
 C_PATH='@baseboard_fab2_lib.baseboard_fab2(sch_1):page196_i105@dev_discrete.cap~
_a(chips)',
 P_PATH='@baseboard_fab2_lib.baseboard_fab2(sch_1):page196_i105@dev_discrete.cap~
_a(chips)',
 PATH='I105',
 DRAWING='@BASEBOARD_FAB2_LIB.BASEBOARD_FAB2(SCH_1):PAGE196',
 TOLERANCE='10%',
 MATERIAL='X7R',
 PHYS_PAGE='196',
 XY='(-1000,1950)',
 ROT='0',
 VER='1',
 VALUE='0.1UF',
 PACK_TYPE='0402V',
 PART_NUMBER='A36096-030',
 LOCATION='C8D4',
 ROOM='V_SUPER',
 CDS_LIB='dev_discrete',
 CDS_PART_NAME='CAP_A_0402V-0.1UF,16V,10%,X7R,A',
 VOLTAGE='16V',
 PRIM_FILE='./archive_libs/discrete/cap_a/chips/chips.prt';

PART_NAME
 C8E1 'CAP_A_0402V-0.1UF,16V,10%,X7R,A':
 ROOM='IO_SLOT';

SECTION_NUMBER 1
 '@BASEBOARD_FAB2_LIB.BASEBOARD_FAB2(SCH_1):PAGE181_I34@DEV_DISCRETE.CAP_A(CHIPS)':
 C_PATH='@baseboard_fab2_lib.baseboard_fab2(sch_1):page181_i34@dev_discrete.cap_~
a(chips)',
 P_PATH='@baseboard_fab2_lib.baseboard_fab2(sch_1):page181_i34@dev_discrete.cap_~
a(chips)',
 PATH='I34',
 DRAWING='@BASEBOARD_FAB2_LIB.BASEBOARD_FAB2(SCH_1):PAGE181',
 TOLERANCE='10%',
 SEC_TYPE='0402V',
 MATERIAL='X7R',
 BOM_COST='IO_SLOT',
 PHYS_PAGE='181',
 XY='(-700,800)',
 ROT='0',
 VER='1',
 VALUE='0.1UF',
 PACK_TYPE='0402V',
 PART_NUMBER='A36096-030',
 LOCATION='C8E1',
 ROOM='IO_SLOT',
 SEC='1',
 CDS_LIB='dev_discrete',
 CDS_PART_NAME='CAP_A_0402V-0.1UF,16V,10%,X7R,A',
 VOLTAGE='16V',
 PRIM_FILE='./archive_libs/discrete/cap_a/chips/chips.prt';

PART_NAME
 C8E2 'CAP_A_0402V-0.1UF,16V,10%,X7R,A':
 ROOM='PROC_SIDEBAND';

SECTION_NUMBER 1
 '@BASEBOARD_FAB2_LIB.BASEBOARD_FAB2(SCH_1):PAGE170_I40@DEV_DISCRETE.CAP_A(CHIPS)':
 C_PATH='@baseboard_fab2_lib.baseboard_fab2(sch_1):page170_i40@dev_discrete.cap_~
a(chips)',
 P_PATH='@baseboard_fab2_lib.baseboard_fab2(sch_1):page170_i40@dev_discrete.cap_~
a(chips)',
 PATH='I40',
 DRAWING='@BASEBOARD_FAB2_LIB.BASEBOARD_FAB2(SCH_1):PAGE170',
 TOLERANCE='10%',
 SEC_TYPE='0402V',
 MATERIAL='X7R',
 BOM_COST='PROC_SIDEBAND',
 PHYS_PAGE='170',
 XY='(-1350,5100)',
 ROT='0',
 VER='1',
 VALUE='0.1UF',
 PACK_TYPE='0402V',
 PART_NUMBER='A36096-030',
 LOCATION='C8E2',
 ROOM='PROC_SIDEBAND',
 SEC='1',
 CDS_LIB='dev_discrete',
 CDS_PART_NAME='CAP_A_0402V-0.1UF,16V,10%,X7R,A',
 VOLTAGE='16V',
 PRIM_FILE='./archive_libs/discrete/cap_a/chips/chips.prt';

PART_NAME
 C8E3 'CAP_A_0402V-0.1UF,16V,10%,X7R,A':
 ROOM='V_SUPER';

SECTION_NUMBER 1
 '@BASEBOARD_FAB2_LIB.BASEBOARD_FAB2(SCH_1):PAGE196_I94@DEV_DISCRETE.CAP_A(CHIPS)':
 C_PATH='@baseboard_fab2_lib.baseboard_fab2(sch_1):page196_i94@dev_discrete.cap_~
a(chips)',
 P_PATH='@baseboard_fab2_lib.baseboard_fab2(sch_1):page196_i94@dev_discrete.cap_~
a(chips)',
 PATH='I94',
 DRAWING='@BASEBOARD_FAB2_LIB.BASEBOARD_FAB2(SCH_1):PAGE196',
 TOLERANCE='10%',
 SEC_TYPE='0402V',
 MATERIAL='X7R',
 PHYS_PAGE='196',
 XY='(-300,2950)',
 ROT='0',
 VER='1',
 VALUE='0.1UF',
 PACK_TYPE='0402V',
 PART_NUMBER='A36096-030',
 LOCATION='C8E3',
 ROOM='V_SUPER',
 SEC='1',
 CDS_LIB='dev_discrete',
 CDS_PART_NAME='CAP_A_0402V-0.1UF,16V,10%,X7R,A',
 VOLTAGE='16V',
 PRIM_FILE='./archive_libs/discrete/cap_a/chips/chips.prt';

PART_NAME
 C8E4 'ST220U10VDM-LGP_SMD-TCG-ST220UA':;

SECTION_NUMBER 1
 '@BASEBOARD_FAB2_LIB.BASEBOARD_FAB2(SCH_1):PAGE241_I100@W_HDL.ST220U10VDM-LGP(CHIPS)':
 C_PATH='@baseboard_fab2_lib.baseboard_fab2(sch_1):page241_i100@w_hdl.\st220u10v~
dm-lgp\(chips)',
 P_PATH='@baseboard_fab2_lib.baseboard_fab2(sch_1):page241_i100@w_hdl.\st220u10v~
dm-lgp\(chips)',
 PATH='I100',
 DRAWING='@BASEBOARD_FAB2_LIB.BASEBOARD_FAB2(SCH_1):PAGE241',
 TYPE='TMAX=105C',
 PACK_SIZE='ESR=25MOHM',
 RATED='10V',
 ATTRIBUTE='220UF',
 TOLERANCE='IRP=2400MA',
 SEC_TYPE='SMD-TCG',
 PHYS_PAGE='241',
 XY='(2850,3825)',
 ROT='0',
 VER='1',
 VALUE='ST220U10VDM-LGP',
 PACK_TYPE='SMD-TCG',
 PART_NUMBER='77.22271.L03',
 LOCATION='C8E4',
 SEC='1',
 CDS_LIB='w_hdl',
 CDS_PART_NAME='ST220U10VDM-LGP_SMD-TCG-ST220UA',
 PRIM_FILE='C:/<user>/w_hdl/st220u10vdm#2dlgp/chips/chips.prt';

PART_NAME
 C8E5 'CAP_A_0402V-0.1UF,16V,10%,X7R,A':
 ROOM='PCIE_WAKE_BUFFER';

SECTION_NUMBER 1
 '@BASEBOARD_FAB2_LIB.BASEBOARD_FAB2(SCH_1):PAGE142_I20@DEV_DISCRETE.CAP_A(CHIPS)':
 C_PATH='@baseboard_fab2_lib.baseboard_fab2(sch_1):page142_i20@dev_discrete.cap_~
a(chips)',
 P_PATH='@baseboard_fab2_lib.baseboard_fab2(sch_1):page142_i20@dev_discrete.cap_~
a(chips)',
 PATH='I20',
 DRAWING='@BASEBOARD_FAB2_LIB.BASEBOARD_FAB2(SCH_1):PAGE142',
 TOLERANCE='10%',
 SEC_TYPE='0402V',
 MATERIAL='X7R',
 BOM_COST='SB',
 PHYS_PAGE='142',
 XY='(-3500,1550)',
 ROT='0',
 VER='1',
 VALUE='0.1UF',
 PACK_TYPE='0402V',
 PART_NUMBER='A36096-030',
 LOCATION='C8E5',
 ROOM='PCIE_WAKE_BUFFER',
 SEC='1',
 CDS_LIB='dev_discrete',
 CDS_PART_NAME='CAP_A_0402V-0.1UF,16V,10%,X7R,A',
 VOLTAGE='16V',
 PRIM_FILE='./archive_libs/discrete/cap_a/chips/chips.prt';

PART_NAME
 C8E6 'CAP_0603LF-0.1UF,25V,10%,X7R,6A':
 ROOM='P5V_STBY_VR',
 REUSE_ID='27';

SECTION_NUMBER 1
 '@BASEBOARD_FAB2_LIB.BASEBOARD_FAB2(SCH_1):PAGE241_I12@MSTR_DISCRETE.CAP(CHIPS)':
 C_PATH='@baseboard_fab2_lib.baseboard_fab2(sch_1):page241_i12@mstr_discrete.cap~
(chips)',
 P_PATH='@baseboard_fab2_lib.baseboard_fab2(sch_1):page241_i12@mstr_discrete.cap~
(chips)',
 PATH='I12',
 DRAWING='@BASEBOARD_FAB2_LIB.BASEBOARD_FAB2(SCH_1):PAGE241',
 SPOF='TRUE',
 TOLERANCE='10%',
 SEC_TYPE='0603LF',
 MATERIAL='X7R',
 BOM_COST='P5V_STBY_VR',
 PHYS_PAGE='241',
 REUSE_ID='27',
 XY='(1200,3675)',
 ROT='0',
 VER='2',
 VALUE='0.1UF',
 PACK_TYPE='0603LF',
 PART_NUMBER='602433-020',
 LOCATION='C8E6',
 ROOM='P5V_STBY_VR',
 SEC='1',
 CDS_LIB='mstr_discrete',
 CDS_PART_NAME='CAP_0603LF-0.1UF,25V,10%,X7R,6A',
 VOLTAGE='25V',
 PRIM_FILE='./archive_libs/mstr_discrete/cap/chips/chips.prt';

PART_NAME
 C8E7 'SC22U16V5MX-4-GP_SMD-BCG5-SC22A':;

SECTION_NUMBER 1
 '@BASEBOARD_FAB2_LIB.BASEBOARD_FAB2(SCH_1):PAGE241_I103@W_HDL.SC22U16V5MX-4-GP(CHIPS)':
 C_PATH='@baseboard_fab2_lib.baseboard_fab2(sch_1):page241_i103@w_hdl.\sc22u16v5~
mx-4-gp\(chips)',
 P_PATH='@baseboard_fab2_lib.baseboard_fab2(sch_1):page241_i103@w_hdl.\sc22u16v5~
mx-4-gp\(chips)',
 PATH='I103',
 DRAWING='@BASEBOARD_FAB2_LIB.BASEBOARD_FAB2(SCH_1):PAGE241',
 TYPE='X6S',
 PACK_SIZE='0805',
 RATED='16V',
 ATTRIBUTE='22UF',
 TOLERANCE='20%',
 SEC_TYPE='SMD-BCG5',
 PHYS_PAGE='241',
 XY='(3400,3825)',
 ROT='0',
 VER='1',
 VALUE='SC22U16V5MX-4-GP',
 PACK_TYPE='SMD-BCG5',
 PART_NUMBER='078.22611.0811',
 LOCATION='C8E7',
 SEC='1',
 CDS_LIB='w_hdl',
 CDS_PART_NAME='SC22U16V5MX-4-GP_SMD-BCG5-SC22A',
 PRIM_FILE='C:/<user>/w_hdl/sc22u16v5mx#2d4#2dgp/chips/chips.prt';

PART_NAME
 C8E8 'CAP_A_0402V-0.1UF,16V,10%,X7R,A':
 ROOM='SB';

SECTION_NUMBER 1
 '@BASEBOARD_FAB2_LIB.BASEBOARD_FAB2(SCH_1):PAGE136_I128@DEV_DISCRETE.CAP_A(CHIPS)':
 C_PATH='@baseboard_fab2_lib.baseboard_fab2(sch_1):page136_i128@dev_discrete.cap~
_a(chips)',
 P_PATH='@baseboard_fab2_lib.baseboard_fab2(sch_1):page136_i128@dev_discrete.cap~
_a(chips)',
 PATH='I128',
 DRAWING='@BASEBOARD_FAB2_LIB.BASEBOARD_FAB2(SCH_1):PAGE136',
 TOLERANCE='10%',
 SEC_TYPE='0402V',
 MATERIAL='X7R',
 BOM_COST='SB',
 PHYS_PAGE='136',
 XY='(575,1575)',
 ROT='0',
 VER='1',
 VALUE='0.1UF',
 PACK_TYPE='0402V',
 PART_NUMBER='A36096-030',
 LOCATION='C8E8',
 ROOM='SB',
 SEC='1',
 CDS_LIB='dev_discrete',
 CDS_PART_NAME='CAP_A_0402V-0.1UF,16V,10%,X7R,A',
 VOLTAGE='16V',
 PRIM_FILE='./archive_libs/discrete/cap_a/chips/chips.prt';

PART_NAME
 C8E9 'SC22U16V5MX-4-GP_SMD-BCG5-SC22A':;

SECTION_NUMBER 1
 '@BASEBOARD_FAB2_LIB.BASEBOARD_FAB2(SCH_1):PAGE241_I104@W_HDL.SC22U16V5MX-4-GP(CHIPS)':
 C_PATH='@baseboard_fab2_lib.baseboard_fab2(sch_1):page241_i104@w_hdl.\sc22u16v5~
mx-4-gp\(chips)',
 P_PATH='@baseboard_fab2_lib.baseboard_fab2(sch_1):page241_i104@w_hdl.\sc22u16v5~
mx-4-gp\(chips)',
 PATH='I104',
 DRAWING='@BASEBOARD_FAB2_LIB.BASEBOARD_FAB2(SCH_1):PAGE241',
 TYPE='X6S',
 PACK_SIZE='0805',
 RATED='16V',
 ATTRIBUTE='22UF',
 TOLERANCE='20%',
 SEC_TYPE='SMD-BCG5',
 PHYS_PAGE='241',
 XY='(3800,3825)',
 ROT='0',
 VER='1',
 VALUE='SC22U16V5MX-4-GP',
 PACK_TYPE='SMD-BCG5',
 PART_NUMBER='078.22611.0811',
 LOCATION='C8E9',
 SEC='1',
 CDS_LIB='w_hdl',
 CDS_PART_NAME='SC22U16V5MX-4-GP_SMD-BCG5-SC22A',
 PRIM_FILE='C:/<user>/w_hdl/sc22u16v5mx#2d4#2dgp/chips/chips.prt';

PART_NAME
 C8E10 'CAP_1206LF-22UF,16V,10%,X6S,D3A':
 ROOM='P3V3_STBY_VR';

SECTION_NUMBER 1
 '@BASEBOARD_FAB2_LIB.BASEBOARD_FAB2(SCH_1):PAGE240_I137@MSTR_DISCRETE.CAP(CHIPS)':
 C_PATH='@baseboard_fab2_lib.baseboard_fab2(sch_1):page240_i137@mstr_discrete.ca~
p(chips)',
 P_PATH='@baseboard_fab2_lib.baseboard_fab2(sch_1):page240_i137@mstr_discrete.ca~
p(chips)',
 PATH='I137',
 DRAWING='@BASEBOARD_FAB2_LIB.BASEBOARD_FAB2(SCH_1):PAGE240',
 TOLERANCE='10%',
 MATERIAL='X6S',
 BOM_COST='P3V3_STBY_VR',
 PHYS_PAGE='240',
 XY='(8150,4325)',
 ROT='0',
 VER='1',
 VALUE='22UF',
 PACK_TYPE='1206LF',
 PART_NUMBER='D38464-005',
 LOCATION='C8E10',
 ROOM='P3V3_STBY_VR',
 CDS_LIB='mstr_discrete',
 CDS_PART_NAME='CAP_1206LF-22UF,16V,10%,X6S,D3A',
 VOLTAGE='16V',
 PRIM_FILE='./archive_libs/mstr_discrete/cap/chips/chips.prt';

PART_NAME
 C8E11 'SC22U16V5MX-4-GP_SMD-BCG5-SC22A':;

SECTION_NUMBER 1
 '@BASEBOARD_FAB2_LIB.BASEBOARD_FAB2(SCH_1):PAGE240_I183@W_HDL.SC22U16V5MX-4-GP(CHIPS)':
 C_PATH='@baseboard_fab2_lib.baseboard_fab2(sch_1):page240_i183@w_hdl.\sc22u16v5~
mx-4-gp\(chips)',
 P_PATH='@baseboard_fab2_lib.baseboard_fab2(sch_1):page240_i183@w_hdl.\sc22u16v5~
mx-4-gp\(chips)',
 PATH='I183',
 DRAWING='@BASEBOARD_FAB2_LIB.BASEBOARD_FAB2(SCH_1):PAGE240',
 TYPE='X6S',
 PACK_SIZE='0805',
 RATED='16V',
 ATTRIBUTE='22UF',
 TOLERANCE='20%',
 SEC_TYPE='SMD-BCG5',
 PHYS_PAGE='240',
 XY='(7450,4275)',
 ROT='0',
 VER='1',
 VALUE='SC22U16V5MX-4-GP',
 PACK_TYPE='SMD-BCG5',
 PART_NUMBER='078.22611.0811',
 LOCATION='C8E11',
 SEC='1',
 CDS_LIB='w_hdl',
 CDS_PART_NAME='SC22U16V5MX-4-GP_SMD-BCG5-SC22A',
 PRIM_FILE='C:/<user>/w_hdl/sc22u16v5mx#2d4#2dgp/chips/chips.prt';

PART_NAME
 C8E12 'CAP_0603LF-0.1UF,25V,10%,X7R,6A':
 ROOM='P3V3_STBY_VR',
 REUSE_ID='27';

SECTION_NUMBER 1
 '@BASEBOARD_FAB2_LIB.BASEBOARD_FAB2(SCH_1):PAGE240_I129@MSTR_DISCRETE.CAP(CHIPS)':
 C_PATH='@baseboard_fab2_lib.baseboard_fab2(sch_1):page240_i129@mstr_discrete.ca~
p(chips)',
 P_PATH='@baseboard_fab2_lib.baseboard_fab2(sch_1):page240_i129@mstr_discrete.ca~
p(chips)',
 PATH='I129',
 DRAWING='@BASEBOARD_FAB2_LIB.BASEBOARD_FAB2(SCH_1):PAGE240',
 SPOF='TRUE',
 TOLERANCE='10%',
 MATERIAL='X7R',
 BOM_COST='P3V3_STBY_VR',
 PHYS_PAGE='240',
 REUSE_ID='27',
 XY='(8300,3425)',
 ROT='2',
 VER='2',
 VALUE='0.1UF',
 PACK_TYPE='0603LF',
 PART_NUMBER='602433-020',
 LOCATION='C8E12',
 ROOM='P3V3_STBY_VR',
 CDS_LIB='mstr_discrete',
 CDS_PART_NAME='CAP_0603LF-0.1UF,25V,10%,X7R,6A',
 VOLTAGE='25V',
 PRIM_FILE='./archive_libs/mstr_discrete/cap/chips/chips.prt';

PART_NAME
 C8E13 'CAP_0402LF-1000PF,50V,10%,EMPTA':
 ROOM='P5V_STBY_VR',
 REUSE_ID='1';

SECTION_NUMBER 1
 '@BASEBOARD_FAB2_LIB.BASEBOARD_FAB2(SCH_1):PAGE241_I41@MSTR_DISCRETE.CAP(CHIPS)':
 C_PATH='@baseboard_fab2_lib.baseboard_fab2(sch_1):page241_i41@mstr_discrete.cap~
(chips)',
 P_PATH='@baseboard_fab2_lib.baseboard_fab2(sch_1):page241_i41@mstr_discrete.cap~
(chips)',
 PATH='I41',
 DRAWING='@BASEBOARD_FAB2_LIB.BASEBOARD_FAB2(SCH_1):PAGE241',
 FIN='VR_1P2',
 TOLERANCE='10%',
 SEC_TYPE='0402LF',
 MATERIAL='EMPTY',
 BOM_COST='P5V_STBY_VR',
 PHYS_PAGE='241',
 REUSE_ID='1',
 XY='(-2000,3075)',
 ROT='2',
 VER='1',
 VALUE='1000PF',
 PACK_TYPE='0402LF',
 PART_NUMBER='A36096-046',
 LOCATION='C8E13',
 ROOM='P5V_STBY_VR',
 SEC='1',
 CDS_LIB='mstr_discrete',
 CDS_PART_NAME='CAP_0402LF-1000PF,50V,10%,EMPTA',
 VOLTAGE='50V',
 PRIM_FILE='./archive_libs/mstr_discrete/cap/chips/chips.prt';

PART_NAME
 C8E14 'CAP_0402-1.0UF,16V,10%,X6S,D97A':
 ROOM='P3V3_STBY_VR',
 REUSE_ID='1';

SECTION_NUMBER 1
 '@BASEBOARD_FAB2_LIB.BASEBOARD_FAB2(SCH_1):PAGE240_I139@MSTR_DISCRETE.CAP(CHIPS)':
 C_PATH='@baseboard_fab2_lib.baseboard_fab2(sch_1):page240_i139@mstr_discrete.ca~
p(chips)',
 P_PATH='@baseboard_fab2_lib.baseboard_fab2(sch_1):page240_i139@mstr_discrete.ca~
p(chips)',
 PATH='I139',
 DRAWING='@BASEBOARD_FAB2_LIB.BASEBOARD_FAB2(SCH_1):PAGE240',
 FIN='VR_1P2',
 TOLERANCE='10%',
 MATERIAL='X6S',
 BOM_COST='P3V3_STBY_VR',
 PHYS_PAGE='240',
 REUSE_ID='1',
 XY='(8475,4350)',
 ROT='0',
 VER='1',
 VALUE='1.0UF',
 PACK_TYPE='0402',
 PART_NUMBER='D97712-011',
 LOCATION='C8E14',
 ROOM='P3V3_STBY_VR',
 CDS_LIB='mstr_discrete',
 CDS_PART_NAME='CAP_0402-1.0UF,16V,10%,X6S,D97A',
 VOLTAGE='16V',
 PRIM_FILE='./archive_libs/mstr_discrete/cap/chips/chips.prt';

PART_NAME
 C8E15 'CAP_0402LF-0.022UF,16V,10%,X7RA':
 ROOM='P5V_STBY_VR',
 REUSE_ID='16';

SECTION_NUMBER 1
 '@BASEBOARD_FAB2_LIB.BASEBOARD_FAB2(SCH_1):PAGE241_I63@MSTR_DISCRETE.CAP(CHIPS)':
 C_PATH='@baseboard_fab2_lib.baseboard_fab2(sch_1):page241_i63@mstr_discrete.cap~
(chips)',
 P_PATH='@baseboard_fab2_lib.baseboard_fab2(sch_1):page241_i63@mstr_discrete.cap~
(chips)',
 PATH='I63',
 DRAWING='@BASEBOARD_FAB2_LIB.BASEBOARD_FAB2(SCH_1):PAGE241',
 TOLERANCE='10%',
 SEC_TYPE='0402LF',
 MATERIAL='X7R',
 BOM_COST='P5V_STBY_VR',
 PHYS_PAGE='241',
 REUSE_ID='16',
 XY='(-1025,3000)',
 ROT='2',
 VER='1',
 VALUE='0.022UF',
 PACK_TYPE='0402LF',
 PART_NUMBER='A36096-073',
 LOCATION='C8E15',
 ROOM='P5V_STBY_VR',
 SEC='1',
 CDS_LIB='mstr_discrete',
 CDS_PART_NAME='CAP_0402LF-0.022UF,16V,10%,X7RA',
 VOLTAGE='16V',
 PRIM_FILE='./archive_libs/mstr_discrete/cap/chips/chips.prt';

PART_NAME
 C8E16 'CAP_0402LF-270PF,50V,10%,X7R,AA':
 ROOM='P5V_STBY_VR',
 REUSE_ID='4';

SECTION_NUMBER 1
 '@BASEBOARD_FAB2_LIB.BASEBOARD_FAB2(SCH_1):PAGE241_I53@MSTR_DISCRETE.CAP(CHIPS)':
 C_PATH='@baseboard_fab2_lib.baseboard_fab2(sch_1):page241_i53@mstr_discrete.cap~
(chips)',
 P_PATH='@baseboard_fab2_lib.baseboard_fab2(sch_1):page241_i53@mstr_discrete.cap~
(chips)',
 PATH='I53',
 DRAWING='@BASEBOARD_FAB2_LIB.BASEBOARD_FAB2(SCH_1):PAGE241',
 TOLERANCE='10%',
 SEC_TYPE='0402LF',
 MATERIAL='X7R',
 BOM_COST='P5V_STBY_VR',
 PHYS_PAGE='241',
 REUSE_ID='4',
 XY='(200,2575)',
 ROT='0',
 VER='2',
 VALUE='270PF',
 PACK_TYPE='0402LF',
 PART_NUMBER='A36096-065',
 LOCATION='C8E16',
 ROOM='P5V_STBY_VR',
 SEC='1',
 CDS_LIB='mstr_discrete',
 CDS_PART_NAME='CAP_0402LF-270PF,50V,10%,X7R,AA',
 VOLTAGE='50V',
 PRIM_FILE='./archive_libs/mstr_discrete/cap/chips/chips.prt';

PART_NAME
 C8E17 'CAP_0402LF-1000PF,50V,10%,EMPTA':
 ROOM='P3V3_STBY_VR',
 REUSE_ID='1';

SECTION_NUMBER 1
 '@BASEBOARD_FAB2_LIB.BASEBOARD_FAB2(SCH_1):PAGE240_I113@MSTR_DISCRETE.CAP(CHIPS)':
 C_PATH='@baseboard_fab2_lib.baseboard_fab2(sch_1):page240_i113@mstr_discrete.ca~
p(chips)',
 P_PATH='@baseboard_fab2_lib.baseboard_fab2(sch_1):page240_i113@mstr_discrete.ca~
p(chips)',
 PATH='I113',
 DRAWING='@BASEBOARD_FAB2_LIB.BASEBOARD_FAB2(SCH_1):PAGE240',
 FIN='VR_1P2',
 TOLERANCE='10%',
 MATERIAL='EMPTY',
 BOM_COST='P3V3_STBY_VR',
 PHYS_PAGE='240',
 REUSE_ID='1',
 XY='(6175,2475)',
 ROT='2',
 VER='1',
 VALUE='1000PF',
 PACK_TYPE='0402LF',
 PART_NUMBER='A36096-046',
 LOCATION='C8E17',
 ROOM='P3V3_STBY_VR',
 CDS_LIB='mstr_discrete',
 CDS_PART_NAME='CAP_0402LF-1000PF,50V,10%,EMPTA',
 VOLTAGE='50V',
 PRIM_FILE='./archive_libs/mstr_discrete/cap/chips/chips.prt';

PART_NAME
 C8E18 'CAP_A_0402V-0.1UF,16V,10%,X7R,A':
 ROOM='SB_BMC_SPI_MUX';

SECTION_NUMBER 1
 '@BASEBOARD_FAB2_LIB.BASEBOARD_FAB2(SCH_1):PAGE154_I14@DEV_DISCRETE.CAP_A(CHIPS)':
 C_PATH='@baseboard_fab2_lib.baseboard_fab2(sch_1):page154_i14@dev_discrete.cap_~
a(chips)',
 P_PATH='@baseboard_fab2_lib.baseboard_fab2(sch_1):page154_i14@dev_discrete.cap_~
a(chips)',
 PATH='I14',
 DRAWING='@BASEBOARD_FAB2_LIB.BASEBOARD_FAB2(SCH_1):PAGE154',
 TOLERANCE='10%',
 SEC_TYPE='0402V',
 MATERIAL='X7R',
 BOM_COST='MIO_BIOS_MEM',
 PHYS_PAGE='154',
 XY='(-5400,4350)',
 ROT='0',
 VER='1',
 VALUE='0.1UF',
 PACK_TYPE='0402V',
 PART_NUMBER='A36096-030',
 LOCATION='C8E18',
 ROOM='SB_BMC_SPI_MUX',
 SEC='1',
 CDS_LIB='dev_discrete',
 CDS_PART_NAME='CAP_A_0402V-0.1UF,16V,10%,X7R,A',
 VOLTAGE='16V',
 PRIM_FILE='./archive_libs/discrete/cap_a/chips/chips.prt';

PART_NAME
 C8E19 'CAP_A_0402V-0.1UF,16V,10%,X7R,A':
 ROOM='P12V_PWR_SWITCH';

SECTION_NUMBER 1
 '@BASEBOARD_FAB2_LIB.BASEBOARD_FAB2(SCH_1):PAGE198_I28@DEV_DISCRETE.CAP_A(CHIPS)':
 C_PATH='@baseboard_fab2_lib.baseboard_fab2(sch_1):page198_i28@dev_discrete.cap_~
a(chips)',
 P_PATH='@baseboard_fab2_lib.baseboard_fab2(sch_1):page198_i28@dev_discrete.cap_~
a(chips)',
 PATH='I28',
 DRAWING='@BASEBOARD_FAB2_LIB.BASEBOARD_FAB2(SCH_1):PAGE198',
 TOLERANCE='10%',
 SEC_TYPE='0402V',
 MATERIAL='X7R',
 PHYS_PAGE='198',
 XY='(-7725,2175)',
 ROT='0',
 VER='1',
 VALUE='0.1UF',
 PACK_TYPE='0402V',
 PART_NUMBER='A36096-030',
 LOCATION='C8E19',
 ROOM='P12V_PWR_SWITCH',
 SEC='1',
 CDS_LIB='dev_discrete',
 CDS_PART_NAME='CAP_A_0402V-0.1UF,16V,10%,X7R,A',
 VOLTAGE='16V',
 PRIM_FILE='./archive_libs/discrete/cap_a/chips/chips.prt';

PART_NAME
 C8F1 'CAP_0402LF-2200PF,50V,10%,X7R,A':
 ROOM='P5V_STBY_VR',
 REUSE_ID='5';

SECTION_NUMBER 1
 '@BASEBOARD_FAB2_LIB.BASEBOARD_FAB2(SCH_1):PAGE241_I57@MSTR_DISCRETE.CAP(CHIPS)':
 C_PATH='@baseboard_fab2_lib.baseboard_fab2(sch_1):page241_i57@mstr_discrete.cap~
(chips)',
 P_PATH='@baseboard_fab2_lib.baseboard_fab2(sch_1):page241_i57@mstr_discrete.cap~
(chips)',
 PATH='I57',
 DRAWING='@BASEBOARD_FAB2_LIB.BASEBOARD_FAB2(SCH_1):PAGE241',
 TOLERANCE='10%',
 SEC_TYPE='0402LF',
 MATERIAL='X7R',
 BOM_COST='P5V_STBY_VR',
 PHYS_PAGE='241',
 REUSE_ID='5',
 XY='(575,2200)',
 ROT='0',
 VER='2',
 VALUE='2200PF',
 PACK_TYPE='0402LF',
 PART_NUMBER='A36096-075',
 LOCATION='C8F1',
 ROOM='P5V_STBY_VR',
 SEC='1',
 CDS_LIB='mstr_discrete',
 CDS_PART_NAME='CAP_0402LF-2200PF,50V,10%,X7R,A',
 VOLTAGE='50V',
 PRIM_FILE='./archive_libs/mstr_discrete/cap/chips/chips.prt';

PART_NAME
 C8F2 'CAP_0402LF-1000PF,50V,10%,X7R,A':
 ROOM='P3V3_STBY_VR',
 REUSE_ID='17';

SECTION_NUMBER 1
 '@BASEBOARD_FAB2_LIB.BASEBOARD_FAB2(SCH_1):PAGE240_I116@MSTR_DISCRETE.CAP(CHIPS)':
 C_PATH='@baseboard_fab2_lib.baseboard_fab2(sch_1):page240_i116@mstr_discrete.ca~
p(chips)',
 P_PATH='@baseboard_fab2_lib.baseboard_fab2(sch_1):page240_i116@mstr_discrete.ca~
p(chips)',
 PATH='I116',
 DRAWING='@BASEBOARD_FAB2_LIB.BASEBOARD_FAB2(SCH_1):PAGE240',
 TOLERANCE='10%',
 MATERIAL='X7R',
 BOM_COST='P3V3_STBY_VR',
 PHYS_PAGE='240',
 REUSE_ID='17',
 XY='(6350,3350)',
 ROT='0',
 VER='1',
 VALUE='1000PF',
 PACK_TYPE='0402LF',
 PART_NUMBER='A36096-046',
 LOCATION='C8F2',
 ROOM='P3V3_STBY_VR',
 CDS_LIB='mstr_discrete',
 CDS_PART_NAME='CAP_0402LF-1000PF,50V,10%,X7R,A',
 VOLTAGE='50V',
 PRIM_FILE='./archive_libs/mstr_discrete/cap/chips/chips.prt';

PART_NAME
 C8F3 'CAP_0402LF-3300PF,50V,10%,EMPTA':
 ROOM='P3V3_STBY_VR',
 REUSE_ID='26';

SECTION_NUMBER 1
 '@BASEBOARD_FAB2_LIB.BASEBOARD_FAB2(SCH_1):PAGE240_I163@MSTR_DISCRETE.CAP(CHIPS)':
 C_PATH='@baseboard_fab2_lib.baseboard_fab2(sch_1):page240_i163@mstr_discrete.ca~
p(chips)',
 P_PATH='@baseboard_fab2_lib.baseboard_fab2(sch_1):page240_i163@mstr_discrete.ca~
p(chips)',
 PATH='I163',
 DRAWING='@BASEBOARD_FAB2_LIB.BASEBOARD_FAB2(SCH_1):PAGE240',
 TOLERANCE='10%',
 MATERIAL='EMPTY',
 BOM_COST='P3V3_STBY_VR',
 PHYS_PAGE='240',
 REUSE_ID='26',
 XY='(9750,3900)',
 ROT='0',
 VER='1',
 VALUE='3300PF',
 PACK_TYPE='0402LF',
 PART_NUMBER='A36096-091',
 LOCATION='C8F3',
 ROOM='P3V3_STBY_VR',
 CDS_LIB='mstr_discrete',
 CDS_PART_NAME='CAP_0402LF-3300PF,50V,10%,EMPTA',
 VOLTAGE='50V',
 PRIM_FILE='./archive_libs/mstr_discrete/cap/chips/chips.prt';

PART_NAME
 C8F4 'CAP_A_0402V-1.0UF,6.3V,10%,X6SA':
 ROOM='BMC_BOOT_SPI';

SECTION_NUMBER 1
 '@BASEBOARD_FAB2_LIB.BASEBOARD_FAB2(SCH_1):PAGE162_I30@DEV_DISCRETE.CAP_A(CHIPS)':
 C_PATH='@baseboard_fab2_lib.baseboard_fab2(sch_1):page162_i30@dev_discrete.cap_~
a(chips)',
 P_PATH='@baseboard_fab2_lib.baseboard_fab2(sch_1):page162_i30@dev_discrete.cap_~
a(chips)',
 PATH='I30',
 DRAWING='@BASEBOARD_FAB2_LIB.BASEBOARD_FAB2(SCH_1):PAGE162',
 TOLERANCE='10%',
 SEC_TYPE='0402V',
 MATERIAL='X6S',
 BOM_COST='SM_MEM',
 PHYS_PAGE='162',
 XY='(7350,3400)',
 ROT='0',
 VER='1',
 VALUE='1.0UF',
 PACK_TYPE='0402V',
 PART_NUMBER='D97712-004',
 LOCATION='C8F4',
 ROOM='BMC_BOOT_SPI',
 SEC='1',
 CDS_LIB='dev_discrete',
 CDS_PART_NAME='CAP_A_0402V-1.0UF,6.3V,10%,X6SA',
 VOLTAGE='6.3V',
 PRIM_FILE='./archive_libs/discrete/cap_a/chips/chips.prt';

PART_NAME
 C8F5 'CAP_A_0402V-0.01UF,25V,10%,X7RA':
 ROOM='BMC_BOOT_SPI';

SECTION_NUMBER 1
 '@BASEBOARD_FAB2_LIB.BASEBOARD_FAB2(SCH_1):PAGE162_I28@DEV_DISCRETE.CAP_A(CHIPS)':
 C_PATH='@baseboard_fab2_lib.baseboard_fab2(sch_1):page162_i28@dev_discrete.cap_~
a(chips)',
 P_PATH='@baseboard_fab2_lib.baseboard_fab2(sch_1):page162_i28@dev_discrete.cap_~
a(chips)',
 PATH='I28',
 DRAWING='@BASEBOARD_FAB2_LIB.BASEBOARD_FAB2(SCH_1):PAGE162',
 TOLERANCE='10%',
 SEC_TYPE='0402V',
 MATERIAL='X7R',
 BOM_COST='SM_MEM',
 PHYS_PAGE='162',
 XY='(7650,3400)',
 ROT='0',
 VER='1',
 VALUE='0.01UF',
 PACK_TYPE='0402V',
 PART_NUMBER='A36096-045',
 LOCATION='C8F5',
 ROOM='BMC_BOOT_SPI',
 SEC='1',
 CDS_LIB='dev_discrete',
 CDS_PART_NAME='CAP_A_0402V-0.01UF,25V,10%,X7RA',
 VOLTAGE='25V',
 PRIM_FILE='./archive_libs/discrete/cap_a/chips/chips.prt';

PART_NAME
 C8F6 'CAP_A_0402V-0.01UF,25V,10%,X7RA':
 GROUP='M2_SATA';

SECTION_NUMBER 1
 '@BASEBOARD_FAB2_LIB.BASEBOARD_FAB2(SCH_1):PAGE185_I138@DEV_DISCRETE.CAP_A(CHIPS)':
 C_PATH='@baseboard_fab2_lib.baseboard_fab2(sch_1):page185_i138@dev_discrete.cap~
_a(chips)',
 P_PATH='@baseboard_fab2_lib.baseboard_fab2(sch_1):page185_i138@dev_discrete.cap~
_a(chips)',
 PATH='I138',
 DRAWING='@BASEBOARD_FAB2_LIB.BASEBOARD_FAB2(SCH_1):PAGE185',
 TOLERANCE='10%',
 SEC_TYPE='0402V',
 MATERIAL='X7R',
 PHYS_PAGE='185',
 XY='(-2600,2100)',
 ROT='1',
 VER='1',
 VALUE='0.01UF',
 PACK_TYPE='0402V',
 PART_NUMBER='A36096-045',
 LOCATION='C8F6',
 GROUP='M2_SATA',
 SEC='1',
 CDS_LIB='dev_discrete',
 CDS_PART_NAME='CAP_A_0402V-0.01UF,25V,10%,X7RA',
 VOLTAGE='25V',
 PRIM_FILE='./archive_libs/discrete/cap_a/chips/chips.prt';

PART_NAME
 C8F7 'CAP_0402-0.22UF,16V,10%,X7R,A3A':
 GROUP='M2_PCIE',
 ROOM='M_2';

SECTION_NUMBER 1
 '@BASEBOARD_FAB2_LIB.BASEBOARD_FAB2(SCH_1):PAGE185_I96@MSTR_DISCRETE.CAP(CHIPS)':
 C_PATH='@baseboard_fab2_lib.baseboard_fab2(sch_1):page185_i96@mstr_discrete.cap~
(chips)',
 P_PATH='@baseboard_fab2_lib.baseboard_fab2(sch_1):page185_i96@mstr_discrete.cap~
(chips)',
 PATH='I96',
 DRAWING='@BASEBOARD_FAB2_LIB.BASEBOARD_FAB2(SCH_1):PAGE185',
 TOLERANCE='10%',
 SEC_TYPE='0402',
 MATERIAL='X7R',
 BOM_COST='ST_FLASH',
 PHYS_PAGE='185',
 XY='(-2575,1825)',
 ROT='0',
 VER='2',
 VALUE='0.22UF',
 PACK_TYPE='0402',
 PART_NUMBER='A36096-155',
 LOCATION='C8F7',
 ROOM='M_2',
 GROUP='M2_PCIE',
 SEC='1',
 CDS_LIB='mstr_discrete',
 CDS_PART_NAME='CAP_0402-0.22UF,16V,10%,X7R,A3A',
 VOLTAGE='16V',
 PRIM_FILE='./archive_libs/mstr_discrete/cap/chips/chips.prt';

PART_NAME
 C8F8 'ST470U6D3VDM-7-GP_SMD-TCG4-ST4A':;

SECTION_NUMBER 1
 '@BASEBOARD_FAB2_LIB.BASEBOARD_FAB2(SCH_1):PAGE240_I190@W_HDL.ST470U6D3VDM-7-GP(CHIPS)':
 C_PATH='@baseboard_fab2_lib.baseboard_fab2(sch_1):page240_i190@w_hdl.\st470u6d3~
vdm-7-gp\(chips)',
 P_PATH='@baseboard_fab2_lib.baseboard_fab2(sch_1):page240_i190@w_hdl.\st470u6d3~
vdm-7-gp\(chips)',
 PATH='I190',
 DRAWING='@BASEBOARD_FAB2_LIB.BASEBOARD_FAB2(SCH_1):PAGE240',
 TYPE='TMAX=105C',
 PACK_SIZE='ESR=35MOHM',
 RATED='6.3V',
 ATTRIBUTE='470UF',
 TOLERANCE='IRP=1.7A',
 SEC_TYPE='SMD-TCG4',
 PHYS_PAGE='240',
 XY='(11500,3825)',
 ROT='0',
 VER='1',
 VALUE='ST470U6D3VDM-7-GP',
 PACK_TYPE='SMD-TCG4',
 PART_NUMBER='077.C4771.0061',
 LOCATION='C8F8',
 SEC='1',
 CDS_LIB='w_hdl',
 CDS_PART_NAME='ST470U6D3VDM-7-GP_SMD-TCG4-ST4A',
 PRIM_FILE='C:/<user>/w_hdl/st470u6d3vdm#2d7#2dgp/chips/chips.prt';

PART_NAME
 C8F11 'CAP_A_0402V-0.01UF,25V,10%,X7RA':
 GROUP='M2_SATA';

SECTION_NUMBER 1
 '@BASEBOARD_FAB2_LIB.BASEBOARD_FAB2(SCH_1):PAGE185_I139@DEV_DISCRETE.CAP_A(CHIPS)':
 C_PATH='@baseboard_fab2_lib.baseboard_fab2(sch_1):page185_i139@dev_discrete.cap~
_a(chips)',
 P_PATH='@baseboard_fab2_lib.baseboard_fab2(sch_1):page185_i139@dev_discrete.cap~
_a(chips)',
 PATH='I139',
 DRAWING='@BASEBOARD_FAB2_LIB.BASEBOARD_FAB2(SCH_1):PAGE185',
 TOLERANCE='10%',
 SEC_TYPE='0402V',
 MATERIAL='X7R',
 PHYS_PAGE='185',
 XY='(-2600,1600)',
 ROT='1',
 VER='1',
 VALUE='0.01UF',
 PACK_TYPE='0402V',
 PART_NUMBER='A36096-045',
 LOCATION='C8F11',
 GROUP='M2_SATA',
 SEC='1',
 CDS_LIB='dev_discrete',
 CDS_PART_NAME='CAP_A_0402V-0.01UF,25V,10%,X7RA',
 VOLTAGE='25V',
 PRIM_FILE='./archive_libs/discrete/cap_a/chips/chips.prt';

PART_NAME
 C8F12 'CAP_0402-0.22UF,16V,10%,X7R,A3A':
 GROUP='M2_PCIE',
 ROOM='M_2';

SECTION_NUMBER 1
 '@BASEBOARD_FAB2_LIB.BASEBOARD_FAB2(SCH_1):PAGE185_I140@MSTR_DISCRETE.CAP(CHIPS)':
 C_PATH='@baseboard_fab2_lib.baseboard_fab2(sch_1):page185_i140@mstr_discrete.ca~
p(chips)',
 P_PATH='@baseboard_fab2_lib.baseboard_fab2(sch_1):page185_i140@mstr_discrete.ca~
p(chips)',
 PATH='I140',
 DRAWING='@BASEBOARD_FAB2_LIB.BASEBOARD_FAB2(SCH_1):PAGE185',
 TOLERANCE='10%',
 SEC_TYPE='0402',
 MATERIAL='X7R',
 BOM_COST='ST_FLASH',
 PHYS_PAGE='185',
 XY='(-2600,1375)',
 ROT='0',
 VER='2',
 VALUE='0.22UF',
 PACK_TYPE='0402',
 PART_NUMBER='A36096-155',
 LOCATION='C8F12',
 ROOM='M_2',
 GROUP='M2_PCIE',
 SEC='1',
 CDS_LIB='mstr_discrete',
 CDS_PART_NAME='CAP_0402-0.22UF,16V,10%,X7R,A3A',
 VOLTAGE='16V',
 PRIM_FILE='./archive_libs/mstr_discrete/cap/chips/chips.prt';

PART_NAME
 C8F13 'CAP_A_0402V-0.01UF,25V,10%,X7RA':
 GROUP='M2_SATA';

SECTION_NUMBER 1
 '@BASEBOARD_FAB2_LIB.BASEBOARD_FAB2(SCH_1):PAGE185_I141@DEV_DISCRETE.CAP_A(CHIPS)':
 C_PATH='@baseboard_fab2_lib.baseboard_fab2(sch_1):page185_i141@dev_discrete.cap~
_a(chips)',
 P_PATH='@baseboard_fab2_lib.baseboard_fab2(sch_1):page185_i141@dev_discrete.cap~
_a(chips)',
 PATH='I141',
 DRAWING='@BASEBOARD_FAB2_LIB.BASEBOARD_FAB2(SCH_1):PAGE185',
 TOLERANCE='10%',
 SEC_TYPE='0402V',
 MATERIAL='X7R',
 PHYS_PAGE='185',
 XY='(-2600,1175)',
 ROT='1',
 VER='1',
 VALUE='0.01UF',
 PACK_TYPE='0402V',
 PART_NUMBER='A36096-045',
 LOCATION='C8F13',
 GROUP='M2_SATA',
 SEC='1',
 CDS_LIB='dev_discrete',
 CDS_PART_NAME='CAP_A_0402V-0.01UF,25V,10%,X7RA',
 VOLTAGE='25V',
 PRIM_FILE='./archive_libs/discrete/cap_a/chips/chips.prt';

PART_NAME
 C8F14 'ST470U6D3VDM-7-GP_SMD-TCG4-ST4A':;

SECTION_NUMBER 1
 '@BASEBOARD_FAB2_LIB.BASEBOARD_FAB2(SCH_1):PAGE240_I189@W_HDL.ST470U6D3VDM-7-GP(CHIPS)':
 C_PATH='@baseboard_fab2_lib.baseboard_fab2(sch_1):page240_i189@w_hdl.\st470u6d3~
vdm-7-gp\(chips)',
 P_PATH='@baseboard_fab2_lib.baseboard_fab2(sch_1):page240_i189@w_hdl.\st470u6d3~
vdm-7-gp\(chips)',
 PATH='I189',
 DRAWING='@BASEBOARD_FAB2_LIB.BASEBOARD_FAB2(SCH_1):PAGE240',
 TYPE='TMAX=105C',
 PACK_SIZE='ESR=35MOHM',
 RATED='6.3V',
 ATTRIBUTE='470UF',
 TOLERANCE='IRP=1.7A',
 SEC_TYPE='SMD-TCG4',
 PHYS_PAGE='240',
 XY='(11100,3825)',
 ROT='0',
 VER='1',
 VALUE='ST470U6D3VDM-7-GP',
 PACK_TYPE='SMD-TCG4',
 PART_NUMBER='077.C4771.0061',
 LOCATION='C8F14',
 SEC='1',
 CDS_LIB='w_hdl',
 CDS_PART_NAME='ST470U6D3VDM-7-GP_SMD-TCG4-ST4A',
 PRIM_FILE='C:/<user>/w_hdl/st470u6d3vdm#2d7#2dgp/chips/chips.prt';

PART_NAME
 C8F15 'CAP_A_0402V-0.01UF,25V,10%,X7RA':
 GROUP='M2_SATA';

SECTION_NUMBER 1
 '@BASEBOARD_FAB2_LIB.BASEBOARD_FAB2(SCH_1):PAGE185_I142@DEV_DISCRETE.CAP_A(CHIPS)':
 C_PATH='@baseboard_fab2_lib.baseboard_fab2(sch_1):page185_i142@dev_discrete.cap~
_a(chips)',
 P_PATH='@baseboard_fab2_lib.baseboard_fab2(sch_1):page185_i142@dev_discrete.cap~
_a(chips)',
 PATH='I142',
 DRAWING='@BASEBOARD_FAB2_LIB.BASEBOARD_FAB2(SCH_1):PAGE185',
 TOLERANCE='10%',
 SEC_TYPE='0402V',
 MATERIAL='X7R',
 PHYS_PAGE='185',
 XY='(-2575,750)',
 ROT='1',
 VER='1',
 VALUE='0.01UF',
 PACK_TYPE='0402V',
 PART_NUMBER='A36096-045',
 LOCATION='C8F15',
 GROUP='M2_SATA',
 SEC='1',
 CDS_LIB='dev_discrete',
 CDS_PART_NAME='CAP_A_0402V-0.01UF,25V,10%,X7RA',
 VOLTAGE='25V',
 PRIM_FILE='./archive_libs/discrete/cap_a/chips/chips.prt';

PART_NAME
 C8F16 'CAP_A_0402V-0.1UF,16V,10%,X7R,A':
 ROOM='BMC_MISC';

SECTION_NUMBER 1
 '@BASEBOARD_FAB2_LIB.BASEBOARD_FAB2(SCH_1):PAGE156_I275@DEV_DISCRETE.CAP_A(CHIPS)':
 C_PATH='@baseboard_fab2_lib.baseboard_fab2(sch_1):page156_i275@dev_discrete.cap~
_a(chips)',
 P_PATH='@baseboard_fab2_lib.baseboard_fab2(sch_1):page156_i275@dev_discrete.cap~
_a(chips)',
 PATH='I275',
 DRAWING='@BASEBOARD_FAB2_LIB.BASEBOARD_FAB2(SCH_1):PAGE156',
 TOLERANCE='10%',
 SEC_TYPE='0402V',
 MATERIAL='X7R',
 BOM_COST='SM_CONTROLLER',
 PHYS_PAGE='156',
 XY='(-3200,4600)',
 ROT='0',
 VER='1',
 VALUE='0.1UF',
 PACK_TYPE='0402V',
 PART_NUMBER='A36096-030',
 LOCATION='C8F16',
 ROOM='BMC_MISC',
 SEC='1',
 CDS_LIB='dev_discrete',
 CDS_PART_NAME='CAP_A_0402V-0.1UF,16V,10%,X7R,A',
 VOLTAGE='16V',
 PRIM_FILE='./archive_libs/discrete/cap_a/chips/chips.prt';

PART_NAME
 C8F17 'CAP_A_0402V-0.1UF,16V,10%,X7R,A':
 ROOM='P3V3_PWR_SWITCH';

SECTION_NUMBER 1
 '@BASEBOARD_FAB2_LIB.BASEBOARD_FAB2(SCH_1):PAGE198_I24@DEV_DISCRETE.CAP_A(CHIPS)':
 C_PATH='@baseboard_fab2_lib.baseboard_fab2(sch_1):page198_i24@dev_discrete.cap_~
a(chips)',
 P_PATH='@baseboard_fab2_lib.baseboard_fab2(sch_1):page198_i24@dev_discrete.cap_~
a(chips)',
 PATH='I24',
 DRAWING='@BASEBOARD_FAB2_LIB.BASEBOARD_FAB2(SCH_1):PAGE198',
 TOLERANCE='10%',
 SEC_TYPE='0402V',
 MATERIAL='X7R',
 PHYS_PAGE='198',
 XY='(-8000,4200)',
 ROT='0',
 VER='1',
 VALUE='0.1UF',
 PACK_TYPE='0402V',
 PART_NUMBER='A36096-030',
 LOCATION='C8F17',
 ROOM='P3V3_PWR_SWITCH',
 SEC='1',
 CDS_LIB='dev_discrete',
 CDS_PART_NAME='CAP_A_0402V-0.1UF,16V,10%,X7R,A',
 VOLTAGE='16V',
 PRIM_FILE='./archive_libs/discrete/cap_a/chips/chips.prt';

PART_NAME
 C8F18 'CAP_0402LF-15.0PF,50V,5%,COG,AA':
 ROOM='SB';

SECTION_NUMBER 1
 '@BASEBOARD_FAB2_LIB.BASEBOARD_FAB2(SCH_1):PAGE101_I147@MSTR_DISCRETE.CAP(CHIPS)':
 C_PATH='@baseboard_fab2_lib.baseboard_fab2(sch_1):page101_i147@mstr_discrete.ca~
p(chips)',
 P_PATH='@baseboard_fab2_lib.baseboard_fab2(sch_1):page101_i147@mstr_discrete.ca~
p(chips)',
 PATH='I147',
 DRAWING='@BASEBOARD_FAB2_LIB.BASEBOARD_FAB2(SCH_1):PAGE101',
 TOLERANCE='5%',
 SEC_TYPE='0402LF',
 MATERIAL='COG',
 BOM_COST='SYS_CLOCK',
 PHYS_PAGE='101',
 XY='(-7150,800)',
 ROT='0',
 VER='1',
 VALUE='15.0PF',
 PACK_TYPE='0402LF',
 PART_NUMBER='A36095-047',
 LOCATION='C8F18',
 ROOM='SB',
 SEC='1',
 CDS_LIB='mstr_discrete',
 CDS_PART_NAME='CAP_0402LF-15.0PF,50V,5%,COG,AA',
 VOLTAGE='50V',
 PRIM_FILE='./archive_libs/mstr_discrete/cap/chips/chips.prt';

PART_NAME
 C8F19 'CAP_0402LF-15.0PF,50V,5%,COG,AA':
 ROOM='SB';

SECTION_NUMBER 1
 '@BASEBOARD_FAB2_LIB.BASEBOARD_FAB2(SCH_1):PAGE101_I146@MSTR_DISCRETE.CAP(CHIPS)':
 C_PATH='@baseboard_fab2_lib.baseboard_fab2(sch_1):page101_i146@mstr_discrete.ca~
p(chips)',
 P_PATH='@baseboard_fab2_lib.baseboard_fab2(sch_1):page101_i146@mstr_discrete.ca~
p(chips)',
 PATH='I146',
 DRAWING='@BASEBOARD_FAB2_LIB.BASEBOARD_FAB2(SCH_1):PAGE101',
 TOLERANCE='5%',
 SEC_TYPE='0402LF',
 MATERIAL='COG',
 BOM_COST='SYS_CLOCK',
 PHYS_PAGE='101',
 XY='(-7600,800)',
 ROT='0',
 VER='1',
 VALUE='15.0PF',
 PACK_TYPE='0402LF',
 PART_NUMBER='A36095-047',
 LOCATION='C8F19',
 ROOM='SB',
 SEC='1',
 CDS_LIB='mstr_discrete',
 CDS_PART_NAME='CAP_0402LF-15.0PF,50V,5%,COG,AA',
 VOLTAGE='50V',
 PRIM_FILE='./archive_libs/mstr_discrete/cap/chips/chips.prt';

PART_NAME
 C8G1 'CAP_0402-0.22UF,16V,10%,X7R,A3A':
 ROOM='OCP_STEERING';

SECTION_NUMBER 1
 '@BASEBOARD_FAB2_LIB.BASEBOARD_FAB2(SCH_1):PAGE105_I70@MSTR_DISCRETE.CAP(CHIPS)':
 C_PATH='@baseboard_fab2_lib.baseboard_fab2(sch_1):page105_i70@mstr_discrete.cap~
(chips)',
 P_PATH='@baseboard_fab2_lib.baseboard_fab2(sch_1):page105_i70@mstr_discrete.cap~
(chips)',
 PATH='I70',
 DRAWING='@BASEBOARD_FAB2_LIB.BASEBOARD_FAB2(SCH_1):PAGE105',
 TOLERANCE='10%',
 SEC_TYPE='0402',
 MATERIAL='X7R',
 PHYS_PAGE='105',
 XY='(1475,4650)',
 ROT='2',
 VER='1',
 VALUE='0.22UF',
 PACK_TYPE='0402',
 PART_NUMBER='A36096-155',
 LOCATION='C8G1',
 ROOM='OCP_STEERING',
 SEC='1',
 CDS_LIB='mstr_discrete',
 CDS_PART_NAME='CAP_0402-0.22UF,16V,10%,X7R,A3A',
 VOLTAGE='16V',
 PRIM_FILE='./archive_libs/mstr_discrete/cap/chips/chips.prt';

PART_NAME
 C8G2 'CAP_0402-0.22UF,16V,10%,X7R,A3A':
 ROOM='OCP_STEERING';

SECTION_NUMBER 1
 '@BASEBOARD_FAB2_LIB.BASEBOARD_FAB2(SCH_1):PAGE105_I58@MSTR_DISCRETE.CAP(CHIPS)':
 C_PATH='@baseboard_fab2_lib.baseboard_fab2(sch_1):page105_i58@mstr_discrete.cap~
(chips)',
 P_PATH='@baseboard_fab2_lib.baseboard_fab2(sch_1):page105_i58@mstr_discrete.cap~
(chips)',
 PATH='I58',
 DRAWING='@BASEBOARD_FAB2_LIB.BASEBOARD_FAB2(SCH_1):PAGE105',
 TOLERANCE='10%',
 SEC_TYPE='0402',
 MATERIAL='X7R',
 PHYS_PAGE='105',
 XY='(1525,3650)',
 ROT='2',
 VER='1',
 VALUE='0.22UF',
 PACK_TYPE='0402',
 PART_NUMBER='A36096-155',
 LOCATION='C8G2',
 ROOM='OCP_STEERING',
 SEC='1',
 CDS_LIB='mstr_discrete',
 CDS_PART_NAME='CAP_0402-0.22UF,16V,10%,X7R,A3A',
 VOLTAGE='16V',
 PRIM_FILE='./archive_libs/mstr_discrete/cap/chips/chips.prt';

PART_NAME
 C8G3 'CAP_0402-0.22UF,16V,10%,X7R,A3A':
 ROOM='OCP_STEERING';

SECTION_NUMBER 1
 '@BASEBOARD_FAB2_LIB.BASEBOARD_FAB2(SCH_1):PAGE105_I71@MSTR_DISCRETE.CAP(CHIPS)':
 C_PATH='@baseboard_fab2_lib.baseboard_fab2(sch_1):page105_i71@mstr_discrete.cap~
(chips)',
 P_PATH='@baseboard_fab2_lib.baseboard_fab2(sch_1):page105_i71@mstr_discrete.cap~
(chips)',
 PATH='I71',
 DRAWING='@BASEBOARD_FAB2_LIB.BASEBOARD_FAB2(SCH_1):PAGE105',
 TOLERANCE='10%',
 SEC_TYPE='0402',
 MATERIAL='X7R',
 PHYS_PAGE='105',
 XY='(1675,4350)',
 ROT='2',
 VER='1',
 VALUE='0.22UF',
 PACK_TYPE='0402',
 PART_NUMBER='A36096-155',
 LOCATION='C8G3',
 ROOM='OCP_STEERING',
 SEC='1',
 CDS_LIB='mstr_discrete',
 CDS_PART_NAME='CAP_0402-0.22UF,16V,10%,X7R,A3A',
 VOLTAGE='16V',
 PRIM_FILE='./archive_libs/mstr_discrete/cap/chips/chips.prt';

PART_NAME
 C8G4 'CAP_0402-0.22UF,16V,10%,X7R,A3A':
 ROOM='OCP_STEERING';

SECTION_NUMBER 1
 '@BASEBOARD_FAB2_LIB.BASEBOARD_FAB2(SCH_1):PAGE105_I56@MSTR_DISCRETE.CAP(CHIPS)':
 C_PATH='@baseboard_fab2_lib.baseboard_fab2(sch_1):page105_i56@mstr_discrete.cap~
(chips)',
 P_PATH='@baseboard_fab2_lib.baseboard_fab2(sch_1):page105_i56@mstr_discrete.cap~
(chips)',
 PATH='I56',
 DRAWING='@BASEBOARD_FAB2_LIB.BASEBOARD_FAB2(SCH_1):PAGE105',
 TOLERANCE='10%',
 SEC_TYPE='0402',
 MATERIAL='X7R',
 PHYS_PAGE='105',
 XY='(1725,3350)',
 ROT='2',
 VER='1',
 VALUE='0.22UF',
 PACK_TYPE='0402',
 PART_NUMBER='A36096-155',
 LOCATION='C8G4',
 ROOM='OCP_STEERING',
 SEC='1',
 CDS_LIB='mstr_discrete',
 CDS_PART_NAME='CAP_0402-0.22UF,16V,10%,X7R,A3A',
 VOLTAGE='16V',
 PRIM_FILE='./archive_libs/mstr_discrete/cap/chips/chips.prt';

PART_NAME
 C8G5 'CAP_0402-0.22UF,16V,10%,X7R,A3A':
 ROOM='OCP_STEERING';

SECTION_NUMBER 1
 '@BASEBOARD_FAB2_LIB.BASEBOARD_FAB2(SCH_1):PAGE105_I75@MSTR_DISCRETE.CAP(CHIPS)':
 C_PATH='@baseboard_fab2_lib.baseboard_fab2(sch_1):page105_i75@mstr_discrete.cap~
(chips)',
 P_PATH='@baseboard_fab2_lib.baseboard_fab2(sch_1):page105_i75@mstr_discrete.cap~
(chips)',
 PATH='I75',
 DRAWING='@BASEBOARD_FAB2_LIB.BASEBOARD_FAB2(SCH_1):PAGE105',
 TOLERANCE='10%',
 SEC_TYPE='0402',
 MATERIAL='X7R',
 PHYS_PAGE='105',
 XY='(1875,4650)',
 ROT='2',
 VER='1',
 VALUE='0.22UF',
 PACK_TYPE='0402',
 PART_NUMBER='A36096-155',
 LOCATION='C8G5',
 ROOM='OCP_STEERING',
 SEC='1',
 CDS_LIB='mstr_discrete',
 CDS_PART_NAME='CAP_0402-0.22UF,16V,10%,X7R,A3A',
 VOLTAGE='16V',
 PRIM_FILE='./archive_libs/mstr_discrete/cap/chips/chips.prt';

PART_NAME
 C8G6 'CAP_0402-0.22UF,16V,10%,X7R,A3A':
 ROOM='OCP_STEERING';

SECTION_NUMBER 1
 '@BASEBOARD_FAB2_LIB.BASEBOARD_FAB2(SCH_1):PAGE105_I61@MSTR_DISCRETE.CAP(CHIPS)':
 C_PATH='@baseboard_fab2_lib.baseboard_fab2(sch_1):page105_i61@mstr_discrete.cap~
(chips)',
 P_PATH='@baseboard_fab2_lib.baseboard_fab2(sch_1):page105_i61@mstr_discrete.cap~
(chips)',
 PATH='I61',
 DRAWING='@BASEBOARD_FAB2_LIB.BASEBOARD_FAB2(SCH_1):PAGE105',
 TOLERANCE='10%',
 SEC_TYPE='0402',
 MATERIAL='X7R',
 PHYS_PAGE='105',
 XY='(1925,3650)',
 ROT='2',
 VER='1',
 VALUE='0.22UF',
 PACK_TYPE='0402',
 PART_NUMBER='A36096-155',
 LOCATION='C8G6',
 ROOM='OCP_STEERING',
 SEC='1',
 CDS_LIB='mstr_discrete',
 CDS_PART_NAME='CAP_0402-0.22UF,16V,10%,X7R,A3A',
 VOLTAGE='16V',
 PRIM_FILE='./archive_libs/mstr_discrete/cap/chips/chips.prt';

PART_NAME
 C8G7 'CAP_0402-0.22UF,16V,10%,X7R,A3A':
 ROOM='OCP_STEERING';

SECTION_NUMBER 1
 '@BASEBOARD_FAB2_LIB.BASEBOARD_FAB2(SCH_1):PAGE105_I62@MSTR_DISCRETE.CAP(CHIPS)':
 C_PATH='@baseboard_fab2_lib.baseboard_fab2(sch_1):page105_i62@mstr_discrete.cap~
(chips)',
 P_PATH='@baseboard_fab2_lib.baseboard_fab2(sch_1):page105_i62@mstr_discrete.cap~
(chips)',
 PATH='I62',
 DRAWING='@BASEBOARD_FAB2_LIB.BASEBOARD_FAB2(SCH_1):PAGE105',
 TOLERANCE='10%',
 SEC_TYPE='0402',
 MATERIAL='X7R',
 PHYS_PAGE='105',
 XY='(2125,3350)',
 ROT='2',
 VER='1',
 VALUE='0.22UF',
 PACK_TYPE='0402',
 PART_NUMBER='A36096-155',
 LOCATION='C8G7',
 ROOM='OCP_STEERING',
 SEC='1',
 CDS_LIB='mstr_discrete',
 CDS_PART_NAME='CAP_0402-0.22UF,16V,10%,X7R,A3A',
 VOLTAGE='16V',
 PRIM_FILE='./archive_libs/mstr_discrete/cap/chips/chips.prt';

PART_NAME
 C8G8 'CAP_0402-0.22UF,16V,10%,X7R,A3A':
 ROOM='OCP_STEERING';

SECTION_NUMBER 1
 '@BASEBOARD_FAB2_LIB.BASEBOARD_FAB2(SCH_1):PAGE105_I76@MSTR_DISCRETE.CAP(CHIPS)':
 C_PATH='@baseboard_fab2_lib.baseboard_fab2(sch_1):page105_i76@mstr_discrete.cap~
(chips)',
 P_PATH='@baseboard_fab2_lib.baseboard_fab2(sch_1):page105_i76@mstr_discrete.cap~
(chips)',
 PATH='I76',
 DRAWING='@BASEBOARD_FAB2_LIB.BASEBOARD_FAB2(SCH_1):PAGE105',
 TOLERANCE='10%',
 SEC_TYPE='0402',
 MATERIAL='X7R',
 PHYS_PAGE='105',
 XY='(2075,4350)',
 ROT='2',
 VER='1',
 VALUE='0.22UF',
 PACK_TYPE='0402',
 PART_NUMBER='A36096-155',
 LOCATION='C8G8',
 ROOM='OCP_STEERING',
 SEC='1',
 CDS_LIB='mstr_discrete',
 CDS_PART_NAME='CAP_0402-0.22UF,16V,10%,X7R,A3A',
 VOLTAGE='16V',
 PRIM_FILE='./archive_libs/mstr_discrete/cap/chips/chips.prt';

PART_NAME
 C8G9 'CAP_0402-0.22UF,16V,10%,X7R,A3A':
 ROOM='OCP_STEERING';

SECTION_NUMBER 1
 '@BASEBOARD_FAB2_LIB.BASEBOARD_FAB2(SCH_1):PAGE105_I93@MSTR_DISCRETE.CAP(CHIPS)':
 C_PATH='@baseboard_fab2_lib.baseboard_fab2(sch_1):page105_i93@mstr_discrete.cap~
(chips)',
 P_PATH='@baseboard_fab2_lib.baseboard_fab2(sch_1):page105_i93@mstr_discrete.cap~
(chips)',
 PATH='I93',
 DRAWING='@BASEBOARD_FAB2_LIB.BASEBOARD_FAB2(SCH_1):PAGE105',
 TOLERANCE='10%',
 SEC_TYPE='0402',
 MATERIAL='X7R',
 PHYS_PAGE='105',
 XY='(2275,4650)',
 ROT='2',
 VER='1',
 VALUE='0.22UF',
 PACK_TYPE='0402',
 PART_NUMBER='A36096-155',
 LOCATION='C8G9',
 ROOM='OCP_STEERING',
 SEC='1',
 CDS_LIB='mstr_discrete',
 CDS_PART_NAME='CAP_0402-0.22UF,16V,10%,X7R,A3A',
 VOLTAGE='16V',
 PRIM_FILE='./archive_libs/mstr_discrete/cap/chips/chips.prt';

PART_NAME
 C8G10 'CAP_0402-0.22UF,16V,10%,X7R,A3A':
 ROOM='OCP_STEERING';

SECTION_NUMBER 1
 '@BASEBOARD_FAB2_LIB.BASEBOARD_FAB2(SCH_1):PAGE105_I96@MSTR_DISCRETE.CAP(CHIPS)':
 C_PATH='@baseboard_fab2_lib.baseboard_fab2(sch_1):page105_i96@mstr_discrete.cap~
(chips)',
 P_PATH='@baseboard_fab2_lib.baseboard_fab2(sch_1):page105_i96@mstr_discrete.cap~
(chips)',
 PATH='I96',
 DRAWING='@BASEBOARD_FAB2_LIB.BASEBOARD_FAB2(SCH_1):PAGE105',
 TOLERANCE='10%',
 SEC_TYPE='0402',
 MATERIAL='X7R',
 PHYS_PAGE='105',
 XY='(2325,3650)',
 ROT='2',
 VER='1',
 VALUE='0.22UF',
 PACK_TYPE='0402',
 PART_NUMBER='A36096-155',
 LOCATION='C8G10',
 ROOM='OCP_STEERING',
 SEC='1',
 CDS_LIB='mstr_discrete',
 CDS_PART_NAME='CAP_0402-0.22UF,16V,10%,X7R,A3A',
 VOLTAGE='16V',
 PRIM_FILE='./archive_libs/mstr_discrete/cap/chips/chips.prt';

PART_NAME
 C8L1 'CAP_0805-100UF,4V,20%,X5R,6024A':
 GROUP='PWR_MLCC_CAP',
 ROOM='VDDQ_ABC_PWR_VR';

SECTION_NUMBER 1
 '@BASEBOARD_FAB2_LIB.BASEBOARD_FAB2(SCH_1):PAGE228_I301@MSTR_DISCRETE.CAP(CHIPS)':
 C_PATH='@baseboard_fab2_lib.baseboard_fab2(sch_1):page228_i301@mstr_discrete.ca~
p(chips)',
 P_PATH='@baseboard_fab2_lib.baseboard_fab2(sch_1):page228_i301@mstr_discrete.ca~
p(chips)',
 PATH='I301',
 DRAWING='@BASEBOARD_FAB2_LIB.BASEBOARD_FAB2(SCH_1):PAGE228',
 NEW_PN='078.1071T.M002',
 NEW_MATERIAL='X6S',
 BOM_SS='NOPOP',
 TOLERANCE='20%',
 SEC_TYPE='0805',
 MATERIAL='X5R',
 BOM_COST='MEM_VRD_PVDDQ_CD',
 PHYS_PAGE='228',
 XY='(2400,2825)',
 ROT='0',
 VER='1',
 VALUE='100UF',
 PACK_TYPE='0805',
 PART_NUMBER='602433-112',
 LOCATION='C8L1',
 ROOM='VDDQ_ABC_PWR_VR',
 GROUP='PWR_MLCC_CAP',
 SEC='1',
 CDS_LIB='mstr_discrete',
 CDS_PART_NAME='CAP_0805-100UF,4V,20%,X5R,6024A',
 VOLTAGE='4V',
 PRIM_FILE='./archive_libs/mstr_discrete/cap/chips/chips.prt';

PART_NAME
 C8L2 'CAP_0805-100UF,4V,20%,X5R,6024A':
 GROUP='PWR_MLCC_CAP',
 ROOM='VDDQ_ABC_PWR_VR';

SECTION_NUMBER 1
 '@BASEBOARD_FAB2_LIB.BASEBOARD_FAB2(SCH_1):PAGE228_I310@MSTR_DISCRETE.CAP(CHIPS)':
 C_PATH='@baseboard_fab2_lib.baseboard_fab2(sch_1):page228_i310@mstr_discrete.ca~
p(chips)',
 P_PATH='@baseboard_fab2_lib.baseboard_fab2(sch_1):page228_i310@mstr_discrete.ca~
p(chips)',
 PATH='I310',
 DRAWING='@BASEBOARD_FAB2_LIB.BASEBOARD_FAB2(SCH_1):PAGE228',
 NEW_PN='078.1071T.M002',
 NEW_MATERIAL='X6S',
 BOM_SS='NOPOP',
 TOLERANCE='20%',
 SEC_TYPE='0805',
 MATERIAL='X5R',
 BOM_COST='MEM_VRD_PVDDQ_CD',
 PHYS_PAGE='228',
 XY='(4600,2825)',
 ROT='0',
 VER='1',
 VALUE='100UF',
 PACK_TYPE='0805',
 PART_NUMBER='602433-112',
 LOCATION='C8L2',
 ROOM='VDDQ_ABC_PWR_VR',
 GROUP='PWR_MLCC_CAP',
 SEC='1',
 CDS_LIB='mstr_discrete',
 CDS_PART_NAME='CAP_0805-100UF,4V,20%,X5R,6024A',
 VOLTAGE='4V',
 PRIM_FILE='./archive_libs/mstr_discrete/cap/chips/chips.prt';

PART_NAME
 C8L3 'CAP_0805-100UF,4V,20%,X5R,6024A':
 GROUP='PWR_MLCC_CAP',
 ROOM='VDDQ_ABC_PWR_VR';

SECTION_NUMBER 1
 '@BASEBOARD_FAB2_LIB.BASEBOARD_FAB2(SCH_1):PAGE230_I41@MSTR_DISCRETE.CAP(CHIPS)':
 C_PATH='@baseboard_fab2_lib.baseboard_fab2(sch_1):page230_i41@mstr_discrete.cap~
(chips)',
 P_PATH='@baseboard_fab2_lib.baseboard_fab2(sch_1):page230_i41@mstr_discrete.cap~
(chips)',
 PATH='I41',
 DRAWING='@BASEBOARD_FAB2_LIB.BASEBOARD_FAB2(SCH_1):PAGE230',
 NEW_PN='078.1071T.M002',
 NEW_MATERIAL='X6S',
 TOLERANCE='20%',
 SEC_TYPE='0805',
 MATERIAL='X5R',
 BOM_COST='MEM_VRD_PVDDQ_CD',
 PHYS_PAGE='230',
 XY='(1750,2675)',
 ROT='0',
 VER='1',
 VALUE='100UF',
 PACK_TYPE='0805',
 PART_NUMBER='602433-112',
 LOCATION='C8L3',
 ROOM='VDDQ_ABC_PWR_VR',
 GROUP='PWR_MLCC_CAP',
 SEC='1',
 CDS_LIB='mstr_discrete',
 CDS_PART_NAME='CAP_0805-100UF,4V,20%,X5R,6024A',
 VOLTAGE='4V',
 PRIM_FILE='./archive_libs/mstr_discrete/cap/chips/chips.prt';

PART_NAME
 C8L4 'CAP_0805-100UF,4V,20%,X5R,6024A':
 GROUP='PWR_MLCC_CAP',
 ROOM='VDDQ_ABC_PWR_VR';

SECTION_NUMBER 1
 '@BASEBOARD_FAB2_LIB.BASEBOARD_FAB2(SCH_1):PAGE230_I42@MSTR_DISCRETE.CAP(CHIPS)':
 C_PATH='@baseboard_fab2_lib.baseboard_fab2(sch_1):page230_i42@mstr_discrete.cap~
(chips)',
 P_PATH='@baseboard_fab2_lib.baseboard_fab2(sch_1):page230_i42@mstr_discrete.cap~
(chips)',
 PATH='I42',
 DRAWING='@BASEBOARD_FAB2_LIB.BASEBOARD_FAB2(SCH_1):PAGE230',
 NEW_PN='078.1071T.M002',
 NEW_MATERIAL='X6S',
 TOLERANCE='20%',
 SEC_TYPE='0805',
 MATERIAL='X5R',
 BOM_COST='MEM_VRD_PVDDQ_CD',
 PHYS_PAGE='230',
 XY='(2150,2675)',
 ROT='0',
 VER='1',
 VALUE='100UF',
 PACK_TYPE='0805',
 PART_NUMBER='602433-112',
 LOCATION='C8L4',
 ROOM='VDDQ_ABC_PWR_VR',
 GROUP='PWR_MLCC_CAP',
 SEC='1',
 CDS_LIB='mstr_discrete',
 CDS_PART_NAME='CAP_0805-100UF,4V,20%,X5R,6024A',
 VOLTAGE='4V',
 PRIM_FILE='./archive_libs/mstr_discrete/cap/chips/chips.prt';

PART_NAME
 C8L5 'CAP_A_0603V-47UF,4V,20%,X5R,60A':
 GROUP='PWR_MLCC_CAP';

SECTION_NUMBER 1
 '@BASEBOARD_FAB2_LIB.BASEBOARD_FAB2(SCH_1):PAGE228_I285@DEV_DISCRETE.CAP_A(CHIPS)':
 C_PATH='@baseboard_fab2_lib.baseboard_fab2(sch_1):page228_i285@dev_discrete.cap~
_a(chips)',
 P_PATH='@baseboard_fab2_lib.baseboard_fab2(sch_1):page228_i285@dev_discrete.cap~
_a(chips)',
 PATH='I285',
 DRAWING='@BASEBOARD_FAB2_LIB.BASEBOARD_FAB2(SCH_1):PAGE228',
 BOM_SS='E15431-004',
 TOLERANCE='20%',
 SEC_TYPE='0603V',
 MATERIAL='X5R',
 PHYS_PAGE='228',
 XY='(-1925,-775)',
 ROT='0',
 VER='1',
 VALUE='47UF',
 PACK_TYPE='0603V',
 PART_NUMBER='602433-106',
 LOCATION='C8L5',
 GROUP='PWR_MLCC_CAP',
 SEC='1',
 CDS_LIB='dev_discrete',
 CDS_PART_NAME='CAP_A_0603V-47UF,4V,20%,X5R,60A',
 VOLTAGE='4V',
 PRIM_FILE='./archive_libs/discrete/cap_a/chips/chips.prt';

PART_NAME
 C8L6 'CAP_A_0603V-47UF,4V,20%,X5R,60A':
 GROUP='PWR_MLCC_CAP';

SECTION_NUMBER 1
 '@BASEBOARD_FAB2_LIB.BASEBOARD_FAB2(SCH_1):PAGE228_I286@DEV_DISCRETE.CAP_A(CHIPS)':
 C_PATH='@baseboard_fab2_lib.baseboard_fab2(sch_1):page228_i286@dev_discrete.cap~
_a(chips)',
 P_PATH='@baseboard_fab2_lib.baseboard_fab2(sch_1):page228_i286@dev_discrete.cap~
_a(chips)',
 PATH='I286',
 DRAWING='@BASEBOARD_FAB2_LIB.BASEBOARD_FAB2(SCH_1):PAGE228',
 BOM_SS='E15431-004',
 TOLERANCE='20%',
 SEC_TYPE='0603V',
 MATERIAL='X5R',
 PHYS_PAGE='228',
 XY='(-1625,-775)',
 ROT='0',
 VER='1',
 VALUE='47UF',
 PACK_TYPE='0603V',
 PART_NUMBER='602433-106',
 LOCATION='C8L6',
 GROUP='PWR_MLCC_CAP',
 SEC='1',
 CDS_LIB='dev_discrete',
 CDS_PART_NAME='CAP_A_0603V-47UF,4V,20%,X5R,60A',
 VOLTAGE='4V',
 PRIM_FILE='./archive_libs/discrete/cap_a/chips/chips.prt';

PART_NAME
 C8L7 'CAP_A_0603V-47UF,4V,20%,X5R,60A':
 GROUP='PWR_MLCC_CAP';

SECTION_NUMBER 1
 '@BASEBOARD_FAB2_LIB.BASEBOARD_FAB2(SCH_1):PAGE228_I287@DEV_DISCRETE.CAP_A(CHIPS)':
 C_PATH='@baseboard_fab2_lib.baseboard_fab2(sch_1):page228_i287@dev_discrete.cap~
_a(chips)',
 P_PATH='@baseboard_fab2_lib.baseboard_fab2(sch_1):page228_i287@dev_discrete.cap~
_a(chips)',
 PATH='I287',
 DRAWING='@BASEBOARD_FAB2_LIB.BASEBOARD_FAB2(SCH_1):PAGE228',
 BOM_SS='E15431-004',
 TOLERANCE='20%',
 SEC_TYPE='0603V',
 MATERIAL='X5R',
 PHYS_PAGE='228',
 XY='(-1350,-775)',
 ROT='0',
 VER='1',
 VALUE='47UF',
 PACK_TYPE='0603V',
 PART_NUMBER='602433-106',
 LOCATION='C8L7',
 GROUP='PWR_MLCC_CAP',
 SEC='1',
 CDS_LIB='dev_discrete',
 CDS_PART_NAME='CAP_A_0603V-47UF,4V,20%,X5R,60A',
 VOLTAGE='4V',
 PRIM_FILE='./archive_libs/discrete/cap_a/chips/chips.prt';

PART_NAME
 C8L8 'CAP_A_0603V-47UF,4V,20%,X5R,60A':
 GROUP='PWR_MLCC_CAP';

SECTION_NUMBER 1
 '@BASEBOARD_FAB2_LIB.BASEBOARD_FAB2(SCH_1):PAGE228_I289@DEV_DISCRETE.CAP_A(CHIPS)':
 C_PATH='@baseboard_fab2_lib.baseboard_fab2(sch_1):page228_i289@dev_discrete.cap~
_a(chips)',
 P_PATH='@baseboard_fab2_lib.baseboard_fab2(sch_1):page228_i289@dev_discrete.cap~
_a(chips)',
 PATH='I289',
 DRAWING='@BASEBOARD_FAB2_LIB.BASEBOARD_FAB2(SCH_1):PAGE228',
 BOM_SS='E15431-004',
 TOLERANCE='20%',
 SEC_TYPE='0603V',
 MATERIAL='X5R',
 PHYS_PAGE='228',
 XY='(-775,-775)',
 ROT='0',
 VER='1',
 VALUE='47UF',
 PACK_TYPE='0603V',
 PART_NUMBER='602433-106',
 LOCATION='C8L8',
 GROUP='PWR_MLCC_CAP',
 SEC='1',
 CDS_LIB='dev_discrete',
 CDS_PART_NAME='CAP_A_0603V-47UF,4V,20%,X5R,60A',
 VOLTAGE='4V',
 PRIM_FILE='./archive_libs/discrete/cap_a/chips/chips.prt';

PART_NAME
 C8L9 'CAP_A_0603V-47UF,4V,20%,X5R,60A':
 GROUP='PWR_MLCC_CAP';

SECTION_NUMBER 1
 '@BASEBOARD_FAB2_LIB.BASEBOARD_FAB2(SCH_1):PAGE228_I290@DEV_DISCRETE.CAP_A(CHIPS)':
 C_PATH='@baseboard_fab2_lib.baseboard_fab2(sch_1):page228_i290@dev_discrete.cap~
_a(chips)',
 P_PATH='@baseboard_fab2_lib.baseboard_fab2(sch_1):page228_i290@dev_discrete.cap~
_a(chips)',
 PATH='I290',
 DRAWING='@BASEBOARD_FAB2_LIB.BASEBOARD_FAB2(SCH_1):PAGE228',
 BOM_SS='E15431-004',
 TOLERANCE='20%',
 SEC_TYPE='0603V',
 MATERIAL='X5R',
 PHYS_PAGE='228',
 XY='(-475,-775)',
 ROT='0',
 VER='1',
 VALUE='47UF',
 PACK_TYPE='0603V',
 PART_NUMBER='602433-106',
 LOCATION='C8L9',
 GROUP='PWR_MLCC_CAP',
 SEC='1',
 CDS_LIB='dev_discrete',
 CDS_PART_NAME='CAP_A_0603V-47UF,4V,20%,X5R,60A',
 VOLTAGE='4V',
 PRIM_FILE='./archive_libs/discrete/cap_a/chips/chips.prt';

PART_NAME
 C8L10 'CAP_A_0603V-47UF,4V,20%,X5R,60A':
 GROUP='PWR_MLCC_CAP';

SECTION_NUMBER 1
 '@BASEBOARD_FAB2_LIB.BASEBOARD_FAB2(SCH_1):PAGE228_I297@DEV_DISCRETE.CAP_A(CHIPS)':
 C_PATH='@baseboard_fab2_lib.baseboard_fab2(sch_1):page228_i297@dev_discrete.cap~
_a(chips)',
 P_PATH='@baseboard_fab2_lib.baseboard_fab2(sch_1):page228_i297@dev_discrete.cap~
_a(chips)',
 PATH='I297',
 DRAWING='@BASEBOARD_FAB2_LIB.BASEBOARD_FAB2(SCH_1):PAGE228',
 BOM_SS='E15431-004',
 TOLERANCE='20%',
 SEC_TYPE='0603V',
 MATERIAL='X5R',
 PHYS_PAGE='228',
 XY='(1575,-775)',
 ROT='0',
 VER='1',
 VALUE='47UF',
 PACK_TYPE='0603V',
 PART_NUMBER='602433-106',
 LOCATION='C8L10',
 GROUP='PWR_MLCC_CAP',
 SEC='1',
 CDS_LIB='dev_discrete',
 CDS_PART_NAME='CAP_A_0603V-47UF,4V,20%,X5R,60A',
 VOLTAGE='4V',
 PRIM_FILE='./archive_libs/discrete/cap_a/chips/chips.prt';

PART_NAME
 C8L11 'CAP_0805-100UF,4V,20%,X5R,6024A':
 GROUP='PWR_MLCC_CAP',
 ROOM='VDDQ_ABC_PWR_VR';

SECTION_NUMBER 1
 '@BASEBOARD_FAB2_LIB.BASEBOARD_FAB2(SCH_1):PAGE228_I302@MSTR_DISCRETE.CAP(CHIPS)':
 C_PATH='@baseboard_fab2_lib.baseboard_fab2(sch_1):page228_i302@mstr_discrete.ca~
p(chips)',
 P_PATH='@baseboard_fab2_lib.baseboard_fab2(sch_1):page228_i302@mstr_discrete.ca~
p(chips)',
 PATH='I302',
 DRAWING='@BASEBOARD_FAB2_LIB.BASEBOARD_FAB2(SCH_1):PAGE228',
 NEW_PN='078.1071T.M002',
 NEW_MATERIAL='X6S',
 BOM_SS='NOPOP',
 TOLERANCE='20%',
 SEC_TYPE='0805',
 MATERIAL='X5R',
 BOM_COST='MEM_VRD_PVDDQ_CD',
 PHYS_PAGE='228',
 XY='(4250,2825)',
 ROT='0',
 VER='1',
 VALUE='100UF',
 PACK_TYPE='0805',
 PART_NUMBER='602433-112',
 LOCATION='C8L11',
 ROOM='VDDQ_ABC_PWR_VR',
 GROUP='PWR_MLCC_CAP',
 SEC='1',
 CDS_LIB='mstr_discrete',
 CDS_PART_NAME='CAP_0805-100UF,4V,20%,X5R,6024A',
 VOLTAGE='4V',
 PRIM_FILE='./archive_libs/mstr_discrete/cap/chips/chips.prt';

PART_NAME
 C8L12 'CAP_A_0603V-47UF,4V,20%,X5R,60A':
 GROUP='PWR_MLCC_CAP';

SECTION_NUMBER 1
 '@BASEBOARD_FAB2_LIB.BASEBOARD_FAB2(SCH_1):PAGE228_I201@DEV_DISCRETE.CAP_A(CHIPS)':
 C_PATH='@baseboard_fab2_lib.baseboard_fab2(sch_1):page228_i201@dev_discrete.cap~
_a(chips)',
 P_PATH='@baseboard_fab2_lib.baseboard_fab2(sch_1):page228_i201@dev_discrete.cap~
_a(chips)',
 PATH='I201',
 DRAWING='@BASEBOARD_FAB2_LIB.BASEBOARD_FAB2(SCH_1):PAGE228',
 BOM_SS='NOPOP',
 TOLERANCE='20%',
 SEC_TYPE='0603V',
 MATERIAL='X5R',
 PHYS_PAGE='228',
 XY='(2525,1425)',
 ROT='0',
 VER='1',
 VALUE='47UF',
 PACK_TYPE='0603V',
 PART_NUMBER='602433-106',
 LOCATION='C8L12',
 GROUP='PWR_MLCC_CAP',
 SEC='1',
 CDS_LIB='dev_discrete',
 CDS_PART_NAME='CAP_A_0603V-47UF,4V,20%,X5R,60A',
 VOLTAGE='4V',
 PRIM_FILE='./archive_libs/discrete/cap_a/chips/chips.prt';

PART_NAME
 C8M1 'CAP_A_0603V-47UF,4V,20%,X5R,60A':
 GROUP='PWR_MLCC_CAP';

SECTION_NUMBER 1
 '@BASEBOARD_FAB2_LIB.BASEBOARD_FAB2(SCH_1):PAGE228_I284@DEV_DISCRETE.CAP_A(CHIPS)':
 C_PATH='@baseboard_fab2_lib.baseboard_fab2(sch_1):page228_i284@dev_discrete.cap~
_a(chips)',
 P_PATH='@baseboard_fab2_lib.baseboard_fab2(sch_1):page228_i284@dev_discrete.cap~
_a(chips)',
 PATH='I284',
 DRAWING='@BASEBOARD_FAB2_LIB.BASEBOARD_FAB2(SCH_1):PAGE228',
 BOM_SS='E15431-004',
 TOLERANCE='20%',
 SEC_TYPE='0603V',
 MATERIAL='X5R',
 PHYS_PAGE='228',
 XY='(-2225,-775)',
 ROT='0',
 VER='1',
 VALUE='47UF',
 PACK_TYPE='0603V',
 PART_NUMBER='602433-106',
 LOCATION='C8M1',
 GROUP='PWR_MLCC_CAP',
 SEC='1',
 CDS_LIB='dev_discrete',
 CDS_PART_NAME='CAP_A_0603V-47UF,4V,20%,X5R,60A',
 VOLTAGE='4V',
 PRIM_FILE='./archive_libs/discrete/cap_a/chips/chips.prt';

PART_NAME
 C8M2 'CAP_A_0603V-47UF,4V,20%,X5R,60A':
 GROUP='PWR_MLCC_CAP';

SECTION_NUMBER 1
 '@BASEBOARD_FAB2_LIB.BASEBOARD_FAB2(SCH_1):PAGE228_I206@DEV_DISCRETE.CAP_A(CHIPS)':
 C_PATH='@baseboard_fab2_lib.baseboard_fab2(sch_1):page228_i206@dev_discrete.cap~
_a(chips)',
 P_PATH='@baseboard_fab2_lib.baseboard_fab2(sch_1):page228_i206@dev_discrete.cap~
_a(chips)',
 PATH='I206',
 DRAWING='@BASEBOARD_FAB2_LIB.BASEBOARD_FAB2(SCH_1):PAGE228',
 BOM_SS='NOPOP',
 TOLERANCE='20%',
 SEC_TYPE='0603V',
 MATERIAL='X5R',
 PHYS_PAGE='228',
 XY='(4375,1425)',
 ROT='0',
 VER='1',
 VALUE='47UF',
 PACK_TYPE='0603V',
 PART_NUMBER='602433-106',
 LOCATION='C8M2',
 GROUP='PWR_MLCC_CAP',
 SEC='1',
 CDS_LIB='dev_discrete',
 CDS_PART_NAME='CAP_A_0603V-47UF,4V,20%,X5R,60A',
 VOLTAGE='4V',
 PRIM_FILE='./archive_libs/discrete/cap_a/chips/chips.prt';

PART_NAME
 C8M3 'CAP_A_0603V-47UF,4V,20%,X5R,60A':
 GROUP='PWR_MLCC_CAP';

SECTION_NUMBER 1
 '@BASEBOARD_FAB2_LIB.BASEBOARD_FAB2(SCH_1):PAGE228_I299@DEV_DISCRETE.CAP_A(CHIPS)':
 C_PATH='@baseboard_fab2_lib.baseboard_fab2(sch_1):page228_i299@dev_discrete.cap~
_a(chips)',
 P_PATH='@baseboard_fab2_lib.baseboard_fab2(sch_1):page228_i299@dev_discrete.cap~
_a(chips)',
 PATH='I299',
 DRAWING='@BASEBOARD_FAB2_LIB.BASEBOARD_FAB2(SCH_1):PAGE228',
 BOM_SS='E15431-004',
 TOLERANCE='20%',
 SEC_TYPE='0603V',
 MATERIAL='X5R',
 PHYS_PAGE='228',
 XY='(2150,-775)',
 ROT='0',
 VER='1',
 VALUE='47UF',
 PACK_TYPE='0603V',
 PART_NUMBER='602433-106',
 LOCATION='C8M3',
 GROUP='PWR_MLCC_CAP',
 SEC='1',
 CDS_LIB='dev_discrete',
 CDS_PART_NAME='CAP_A_0603V-47UF,4V,20%,X5R,60A',
 VOLTAGE='4V',
 PRIM_FILE='./archive_libs/discrete/cap_a/chips/chips.prt';

PART_NAME
 C8M4 'CAP_A_0603V-47UF,4V,20%,X5R,60A':
 GROUP='PWR_MLCC_CAP';

SECTION_NUMBER 1
 '@BASEBOARD_FAB2_LIB.BASEBOARD_FAB2(SCH_1):PAGE228_I293@DEV_DISCRETE.CAP_A(CHIPS)':
 C_PATH='@baseboard_fab2_lib.baseboard_fab2(sch_1):page228_i293@dev_discrete.cap~
_a(chips)',
 P_PATH='@baseboard_fab2_lib.baseboard_fab2(sch_1):page228_i293@dev_discrete.cap~
_a(chips)',
 PATH='I293',
 DRAWING='@BASEBOARD_FAB2_LIB.BASEBOARD_FAB2(SCH_1):PAGE228',
 BOM_SS='E15431-004',
 TOLERANCE='20%',
 SEC_TYPE='0603V',
 MATERIAL='X5R',
 PHYS_PAGE='228',
 XY='(425,-775)',
 ROT='0',
 VER='1',
 VALUE='47UF',
 PACK_TYPE='0603V',
 PART_NUMBER='602433-106',
 LOCATION='C8M4',
 GROUP='PWR_MLCC_CAP',
 SEC='1',
 CDS_LIB='dev_discrete',
 CDS_PART_NAME='CAP_A_0603V-47UF,4V,20%,X5R,60A',
 VOLTAGE='4V',
 PRIM_FILE='./archive_libs/discrete/cap_a/chips/chips.prt';

PART_NAME
 C8M5 'CAP_A_0603V-47UF,4V,20%,X5R,60A':
 GROUP='PWR_MLCC_CAP';

SECTION_NUMBER 1
 '@BASEBOARD_FAB2_LIB.BASEBOARD_FAB2(SCH_1):PAGE228_I298@DEV_DISCRETE.CAP_A(CHIPS)':
 C_PATH='@baseboard_fab2_lib.baseboard_fab2(sch_1):page228_i298@dev_discrete.cap~
_a(chips)',
 P_PATH='@baseboard_fab2_lib.baseboard_fab2(sch_1):page228_i298@dev_discrete.cap~
_a(chips)',
 PATH='I298',
 DRAWING='@BASEBOARD_FAB2_LIB.BASEBOARD_FAB2(SCH_1):PAGE228',
 BOM_SS='E15431-004',
 TOLERANCE='20%',
 SEC_TYPE='0603V',
 MATERIAL='X5R',
 PHYS_PAGE='228',
 XY='(1875,-775)',
 ROT='0',
 VER='1',
 VALUE='47UF',
 PACK_TYPE='0603V',
 PART_NUMBER='602433-106',
 LOCATION='C8M5',
 GROUP='PWR_MLCC_CAP',
 SEC='1',
 CDS_LIB='dev_discrete',
 CDS_PART_NAME='CAP_A_0603V-47UF,4V,20%,X5R,60A',
 VOLTAGE='4V',
 PRIM_FILE='./archive_libs/discrete/cap_a/chips/chips.prt';

PART_NAME
 C8M6 'CAP_A_0603V-47UF,4V,20%,X5R,60A':
 GROUP='PWR_MLCC_CAP';

SECTION_NUMBER 1
 '@BASEBOARD_FAB2_LIB.BASEBOARD_FAB2(SCH_1):PAGE228_I291@DEV_DISCRETE.CAP_A(CHIPS)':
 C_PATH='@baseboard_fab2_lib.baseboard_fab2(sch_1):page228_i291@dev_discrete.cap~
_a(chips)',
 P_PATH='@baseboard_fab2_lib.baseboard_fab2(sch_1):page228_i291@dev_discrete.cap~
_a(chips)',
 PATH='I291',
 DRAWING='@BASEBOARD_FAB2_LIB.BASEBOARD_FAB2(SCH_1):PAGE228',
 BOM_SS='E15431-004',
 TOLERANCE='20%',
 SEC_TYPE='0603V',
 MATERIAL='X5R',
 PHYS_PAGE='228',
 XY='(-200,-775)',
 ROT='0',
 VER='1',
 VALUE='47UF',
 PACK_TYPE='0603V',
 PART_NUMBER='602433-106',
 LOCATION='C8M6',
 GROUP='PWR_MLCC_CAP',
 SEC='1',
 CDS_LIB='dev_discrete',
 CDS_PART_NAME='CAP_A_0603V-47UF,4V,20%,X5R,60A',
 VOLTAGE='4V',
 PRIM_FILE='./archive_libs/discrete/cap_a/chips/chips.prt';

PART_NAME
 C8M7 'CAP_0805-100UF,4V,20%,X5R,6024A':
 GROUP='PWR_MLCC_CAP',
 ROOM='VDDQ_ABC_PWR_VR';

SECTION_NUMBER 1
 '@BASEBOARD_FAB2_LIB.BASEBOARD_FAB2(SCH_1):PAGE228_I312@MSTR_DISCRETE.CAP(CHIPS)':
 C_PATH='@baseboard_fab2_lib.baseboard_fab2(sch_1):page228_i312@mstr_discrete.ca~
p(chips)',
 P_PATH='@baseboard_fab2_lib.baseboard_fab2(sch_1):page228_i312@mstr_discrete.ca~
p(chips)',
 PATH='I312',
 DRAWING='@BASEBOARD_FAB2_LIB.BASEBOARD_FAB2(SCH_1):PAGE228',
 NEW_PN='078.1071T.M002',
 NEW_MATERIAL='X6S',
 BOM_SS='NOPOP',
 TOLERANCE='20%',
 SEC_TYPE='0805',
 MATERIAL='X5R',
 BOM_COST='MEM_VRD_PVDDQ_CD',
 PHYS_PAGE='228',
 XY='(3500,2825)',
 ROT='0',
 VER='1',
 VALUE='100UF',
 PACK_TYPE='0805',
 PART_NUMBER='602433-112',
 LOCATION='C8M7',
 ROOM='VDDQ_ABC_PWR_VR',
 GROUP='PWR_MLCC_CAP',
 SEC='1',
 CDS_LIB='mstr_discrete',
 CDS_PART_NAME='CAP_0805-100UF,4V,20%,X5R,6024A',
 VOLTAGE='4V',
 PRIM_FILE='./archive_libs/mstr_discrete/cap/chips/chips.prt';

PART_NAME
 C8M8 'CAP_A_0603V-47UF,4V,20%,X5R,60A':
 GROUP='PWR_MLCC_CAP';

SECTION_NUMBER 1
 '@BASEBOARD_FAB2_LIB.BASEBOARD_FAB2(SCH_1):PAGE228_I198@DEV_DISCRETE.CAP_A(CHIPS)':
 C_PATH='@baseboard_fab2_lib.baseboard_fab2(sch_1):page228_i198@dev_discrete.cap~
_a(chips)',
 P_PATH='@baseboard_fab2_lib.baseboard_fab2(sch_1):page228_i198@dev_discrete.cap~
_a(chips)',
 PATH='I198',
 DRAWING='@BASEBOARD_FAB2_LIB.BASEBOARD_FAB2(SCH_1):PAGE228',
 BOM_SS='NOPOP',
 TOLERANCE='20%',
 SEC_TYPE='0603V',
 MATERIAL='X5R',
 PHYS_PAGE='228',
 XY='(2550,725)',
 ROT='0',
 VER='1',
 VALUE='47UF',
 PACK_TYPE='0603V',
 PART_NUMBER='602433-106',
 LOCATION='C8M8',
 GROUP='PWR_MLCC_CAP',
 SEC='1',
 CDS_LIB='dev_discrete',
 CDS_PART_NAME='CAP_A_0603V-47UF,4V,20%,X5R,60A',
 VOLTAGE='4V',
 PRIM_FILE='./archive_libs/discrete/cap_a/chips/chips.prt';

PART_NAME
 C8M9 'CAP_A_0603V-47UF,4V,20%,X5R,60A':
 GROUP='PWR_MLCC_CAP';

SECTION_NUMBER 1
 '@BASEBOARD_FAB2_LIB.BASEBOARD_FAB2(SCH_1):PAGE228_I205@DEV_DISCRETE.CAP_A(CHIPS)':
 C_PATH='@baseboard_fab2_lib.baseboard_fab2(sch_1):page228_i205@dev_discrete.cap~
_a(chips)',
 P_PATH='@baseboard_fab2_lib.baseboard_fab2(sch_1):page228_i205@dev_discrete.cap~
_a(chips)',
 PATH='I205',
 DRAWING='@BASEBOARD_FAB2_LIB.BASEBOARD_FAB2(SCH_1):PAGE228',
 BOM_SS='NOPOP',
 TOLERANCE='20%',
 SEC_TYPE='0603V',
 MATERIAL='X5R',
 PHYS_PAGE='228',
 XY='(3975,1425)',
 ROT='0',
 VER='1',
 VALUE='47UF',
 PACK_TYPE='0603V',
 PART_NUMBER='602433-106',
 LOCATION='C8M9',
 GROUP='PWR_MLCC_CAP',
 SEC='1',
 CDS_LIB='dev_discrete',
 CDS_PART_NAME='CAP_A_0603V-47UF,4V,20%,X5R,60A',
 VOLTAGE='4V',
 PRIM_FILE='./archive_libs/discrete/cap_a/chips/chips.prt';

PART_NAME
 C8M10 'CAP_A_0603V-47UF,4V,20%,X5R,60A':
 GROUP='PWR_MLCC_CAP';

SECTION_NUMBER 1
 '@BASEBOARD_FAB2_LIB.BASEBOARD_FAB2(SCH_1):PAGE228_I203@DEV_DISCRETE.CAP_A(CHIPS)':
 C_PATH='@baseboard_fab2_lib.baseboard_fab2(sch_1):page228_i203@dev_discrete.cap~
_a(chips)',
 P_PATH='@baseboard_fab2_lib.baseboard_fab2(sch_1):page228_i203@dev_discrete.cap~
_a(chips)',
 PATH='I203',
 DRAWING='@BASEBOARD_FAB2_LIB.BASEBOARD_FAB2(SCH_1):PAGE228',
 BOM_SS='078.1061T.M001',
 TOLERANCE='20%',
 SEC_TYPE='0603V',
 MATERIAL='X5R',
 PHYS_PAGE='228',
 XY='(3275,1425)',
 ROT='0',
 VER='1',
 VALUE='47UF',
 PACK_TYPE='0603V',
 PART_NUMBER='602433-106',
 LOCATION='C8M10',
 GROUP='PWR_MLCC_CAP',
 SEC='1',
 CDS_LIB='dev_discrete',
 CDS_PART_NAME='CAP_A_0603V-47UF,4V,20%,X5R,60A',
 VOLTAGE='4V',
 PRIM_FILE='./archive_libs/discrete/cap_a/chips/chips.prt';

PART_NAME
 C8M11 'CAP_0805-100UF,4V,20%,X5R,6024A':
 GROUP='PWR_MLCC_CAP',
 ROOM='VDDQ_ABC_PWR_VR';

SECTION_NUMBER 1
 '@BASEBOARD_FAB2_LIB.BASEBOARD_FAB2(SCH_1):PAGE228_I311@MSTR_DISCRETE.CAP(CHIPS)':
 C_PATH='@baseboard_fab2_lib.baseboard_fab2(sch_1):page228_i311@mstr_discrete.ca~
p(chips)',
 P_PATH='@baseboard_fab2_lib.baseboard_fab2(sch_1):page228_i311@mstr_discrete.ca~
p(chips)',
 PATH='I311',
 DRAWING='@BASEBOARD_FAB2_LIB.BASEBOARD_FAB2(SCH_1):PAGE228',
 NEW_PN='078.1071T.M002',
 NEW_MATERIAL='X6S',
 BOM_SS='NOPOP',
 TOLERANCE='20%',
 SEC_TYPE='0805',
 MATERIAL='X5R',
 BOM_COST='MEM_VRD_PVDDQ_CD',
 PHYS_PAGE='228',
 XY='(3150,2825)',
 ROT='0',
 VER='1',
 VALUE='100UF',
 PACK_TYPE='0805',
 PART_NUMBER='602433-112',
 LOCATION='C8M11',
 ROOM='VDDQ_ABC_PWR_VR',
 GROUP='PWR_MLCC_CAP',
 SEC='1',
 CDS_LIB='mstr_discrete',
 CDS_PART_NAME='CAP_0805-100UF,4V,20%,X5R,6024A',
 VOLTAGE='4V',
 PRIM_FILE='./archive_libs/mstr_discrete/cap/chips/chips.prt';

PART_NAME
 C8M12 'CAP_A_0603V-47UF,4V,20%,X5R,60A':
 GROUP='PWR_MLCC_CAP';

SECTION_NUMBER 1
 '@BASEBOARD_FAB2_LIB.BASEBOARD_FAB2(SCH_1):PAGE230_I24@DEV_DISCRETE.CAP_A(CHIPS)':
 C_PATH='@baseboard_fab2_lib.baseboard_fab2(sch_1):page230_i24@dev_discrete.cap_~
a(chips)',
 P_PATH='@baseboard_fab2_lib.baseboard_fab2(sch_1):page230_i24@dev_discrete.cap_~
a(chips)',
 PATH='I24',
 DRAWING='@BASEBOARD_FAB2_LIB.BASEBOARD_FAB2(SCH_1):PAGE230',
 TOLERANCE='20%',
 SEC_TYPE='0603V',
 MATERIAL='X5R',
 PHYS_PAGE='230',
 XY='(1350,2675)',
 ROT='0',
 VER='1',
 VALUE='47UF',
 PACK_TYPE='0603V',
 PART_NUMBER='602433-106',
 LOCATION='C8M12',
 GROUP='PWR_MLCC_CAP',
 SEC='1',
 CDS_LIB='dev_discrete',
 CDS_PART_NAME='CAP_A_0603V-47UF,4V,20%,X5R,60A',
 VOLTAGE='4V',
 PRIM_FILE='./archive_libs/discrete/cap_a/chips/chips.prt';

PART_NAME
 C8P1 'CAP_0805-100UF,4V,20%,X5R,6024A':
 GROUP='PWR_MLCC_CAP',
 ROOM='VDDQ_ABC_PWR_VR';

SECTION_NUMBER 1
 '@BASEBOARD_FAB2_LIB.BASEBOARD_FAB2(SCH_1):PAGE228_I304@MSTR_DISCRETE.CAP(CHIPS)':
 C_PATH='@baseboard_fab2_lib.baseboard_fab2(sch_1):page228_i304@mstr_discrete.ca~
p(chips)',
 P_PATH='@baseboard_fab2_lib.baseboard_fab2(sch_1):page228_i304@mstr_discrete.ca~
p(chips)',
 PATH='I304',
 DRAWING='@BASEBOARD_FAB2_LIB.BASEBOARD_FAB2(SCH_1):PAGE228',
 NEW_PN='078.1071T.M002',
 NEW_MATERIAL='X6S',
 BOM_SS='NOPOP',
 TOLERANCE='20%',
 SEC_TYPE='0805',
 MATERIAL='X5R',
 BOM_COST='MEM_VRD_PVDDQ_CD',
 PHYS_PAGE='228',
 XY='(-1925,2975)',
 ROT='0',
 VER='1',
 VALUE='100UF',
 PACK_TYPE='0805',
 PART_NUMBER='602433-112',
 LOCATION='C8P1',
 ROOM='VDDQ_ABC_PWR_VR',
 GROUP='PWR_MLCC_CAP',
 SEC='1',
 CDS_LIB='mstr_discrete',
 CDS_PART_NAME='CAP_0805-100UF,4V,20%,X5R,6024A',
 VOLTAGE='4V',
 PRIM_FILE='./archive_libs/mstr_discrete/cap/chips/chips.prt';

PART_NAME
 C8P2 'CAP_0805-100UF,4V,20%,X5R,6024A':
 GROUP='PWR_MLCC_CAP',
 ROOM='VDDQ_ABC_PWR_VR';

SECTION_NUMBER 1
 '@BASEBOARD_FAB2_LIB.BASEBOARD_FAB2(SCH_1):PAGE228_I303@MSTR_DISCRETE.CAP(CHIPS)':
 C_PATH='@baseboard_fab2_lib.baseboard_fab2(sch_1):page228_i303@mstr_discrete.ca~
p(chips)',
 P_PATH='@baseboard_fab2_lib.baseboard_fab2(sch_1):page228_i303@mstr_discrete.ca~
p(chips)',
 PATH='I303',
 DRAWING='@BASEBOARD_FAB2_LIB.BASEBOARD_FAB2(SCH_1):PAGE228',
 NEW_PN='078.1071T.M002',
 NEW_MATERIAL='X6S',
 BOM_SS='NOPOP',
 TOLERANCE='20%',
 SEC_TYPE='0805',
 MATERIAL='X5R',
 BOM_COST='MEM_VRD_PVDDQ_CD',
 PHYS_PAGE='228',
 XY='(-2325,2975)',
 ROT='0',
 VER='1',
 VALUE='100UF',
 PACK_TYPE='0805',
 PART_NUMBER='602433-112',
 LOCATION='C8P2',
 ROOM='VDDQ_ABC_PWR_VR',
 GROUP='PWR_MLCC_CAP',
 SEC='1',
 CDS_LIB='mstr_discrete',
 CDS_PART_NAME='CAP_0805-100UF,4V,20%,X5R,6024A',
 VOLTAGE='4V',
 PRIM_FILE='./archive_libs/mstr_discrete/cap/chips/chips.prt';

PART_NAME
 C8P3 'CAP_0805-100UF,4V,20%,X5R,6024A':
 GROUP='PWR_MLCC_CAP',
 ROOM='VDDQ_ABC_PWR_VR';

SECTION_NUMBER 1
 '@BASEBOARD_FAB2_LIB.BASEBOARD_FAB2(SCH_1):PAGE228_I306@MSTR_DISCRETE.CAP(CHIPS)':
 C_PATH='@baseboard_fab2_lib.baseboard_fab2(sch_1):page228_i306@mstr_discrete.ca~
p(chips)',
 P_PATH='@baseboard_fab2_lib.baseboard_fab2(sch_1):page228_i306@mstr_discrete.ca~
p(chips)',
 PATH='I306',
 DRAWING='@BASEBOARD_FAB2_LIB.BASEBOARD_FAB2(SCH_1):PAGE228',
 NEW_PN='078.1071T.M002',
 NEW_MATERIAL='X6S',
 BOM_SS='NOPOP',
 TOLERANCE='20%',
 SEC_TYPE='0805',
 MATERIAL='X5R',
 BOM_COST='MEM_VRD_PVDDQ_CD',
 PHYS_PAGE='228',
 XY='(1125,2775)',
 ROT='0',
 VER='1',
 VALUE='100UF',
 PACK_TYPE='0805',
 PART_NUMBER='602433-112',
 LOCATION='C8P3',
 ROOM='VDDQ_ABC_PWR_VR',
 GROUP='PWR_MLCC_CAP',
 SEC='1',
 CDS_LIB='mstr_discrete',
 CDS_PART_NAME='CAP_0805-100UF,4V,20%,X5R,6024A',
 VOLTAGE='4V',
 PRIM_FILE='./archive_libs/mstr_discrete/cap/chips/chips.prt';

PART_NAME
 C8P4 'CAP_0805-100UF,4V,20%,X5R,6024A':
 GROUP='PWR_MLCC_CAP',
 ROOM='VDDQ_ABC_PWR_VR';

SECTION_NUMBER 1
 '@BASEBOARD_FAB2_LIB.BASEBOARD_FAB2(SCH_1):PAGE228_I307@MSTR_DISCRETE.CAP(CHIPS)':
 C_PATH='@baseboard_fab2_lib.baseboard_fab2(sch_1):page228_i307@mstr_discrete.ca~
p(chips)',
 P_PATH='@baseboard_fab2_lib.baseboard_fab2(sch_1):page228_i307@mstr_discrete.ca~
p(chips)',
 PATH='I307',
 DRAWING='@BASEBOARD_FAB2_LIB.BASEBOARD_FAB2(SCH_1):PAGE228',
 NEW_PN='078.1071T.M002',
 NEW_MATERIAL='X6S',
 BOM_SS='NOPOP',
 TOLERANCE='20%',
 SEC_TYPE='0805',
 MATERIAL='X5R',
 BOM_COST='MEM_VRD_PVDDQ_CD',
 PHYS_PAGE='228',
 XY='(650,2775)',
 ROT='0',
 VER='1',
 VALUE='100UF',
 PACK_TYPE='0805',
 PART_NUMBER='602433-112',
 LOCATION='C8P4',
 ROOM='VDDQ_ABC_PWR_VR',
 GROUP='PWR_MLCC_CAP',
 SEC='1',
 CDS_LIB='mstr_discrete',
 CDS_PART_NAME='CAP_0805-100UF,4V,20%,X5R,6024A',
 VOLTAGE='4V',
 PRIM_FILE='./archive_libs/mstr_discrete/cap/chips/chips.prt';

PART_NAME
 C8P5 'CAP_0805LF-22UF,4V,20%,X6S,C95A':
 GROUP='PWR_MLCC_CAP',
 ROOM='PVCCIN_CPU0_DECAP_VR';

SECTION_NUMBER 1
 '@BASEBOARD_FAB2_LIB.BASEBOARD_FAB2(SCH_1):PAGE76_I246@MSTR_DISCRETE.CAP(CHIPS)':
 C_PATH='@baseboard_fab2_lib.baseboard_fab2(sch_1):page76_i246@mstr_discrete.cap~
(chips)',
 P_PATH='@baseboard_fab2_lib.baseboard_fab2(sch_1):page76_i246@mstr_discrete.cap~
(chips)',
 PATH='I246',
 DRAWING='@BASEBOARD_FAB2_LIB.BASEBOARD_FAB2(SCH_1):PAGE76',
 TOLERANCE='20%',
 MATERIAL='X6S',
 BOM_COST='PROC_SOCKET',
 PHYS_PAGE='76',
 XY='(-4550,1150)',
 ROT='0',
 VER='1',
 VALUE='22UF',
 PACK_TYPE='0805LF',
 PART_NUMBER='C95333-002',
 LOCATION='C8P5',
 ROOM='PVCCIN_CPU0_DECAP_VR',
 GROUP='PWR_MLCC_CAP',
 CDS_LIB='mstr_discrete',
 CDS_PART_NAME='CAP_0805LF-22UF,4V,20%,X6S,C95A',
 VOLTAGE='4V',
 PRIM_FILE='./archive_libs/mstr_discrete/cap/chips/chips.prt';

PART_NAME
 C8P6 'CAP_0805LF-22UF,4V,20%,X6S,C95A':
 GROUP='PWR_MLCC_CAP',
 ROOM='PVCCIN_CPU0_DECAP_VR';

SECTION_NUMBER 1
 '@BASEBOARD_FAB2_LIB.BASEBOARD_FAB2(SCH_1):PAGE76_I247@MSTR_DISCRETE.CAP(CHIPS)':
 C_PATH='@baseboard_fab2_lib.baseboard_fab2(sch_1):page76_i247@mstr_discrete.cap~
(chips)',
 P_PATH='@baseboard_fab2_lib.baseboard_fab2(sch_1):page76_i247@mstr_discrete.cap~
(chips)',
 PATH='I247',
 DRAWING='@BASEBOARD_FAB2_LIB.BASEBOARD_FAB2(SCH_1):PAGE76',
 TOLERANCE='20%',
 MATERIAL='X6S',
 BOM_COST='PROC_SOCKET',
 PHYS_PAGE='76',
 XY='(-4250,1150)',
 ROT='0',
 VER='1',
 VALUE='22UF',
 PACK_TYPE='0805LF',
 PART_NUMBER='C95333-002',
 LOCATION='C8P6',
 ROOM='PVCCIN_CPU0_DECAP_VR',
 GROUP='PWR_MLCC_CAP',
 CDS_LIB='mstr_discrete',
 CDS_PART_NAME='CAP_0805LF-22UF,4V,20%,X6S,C95A',
 VOLTAGE='4V',
 PRIM_FILE='./archive_libs/mstr_discrete/cap/chips/chips.prt';

PART_NAME
 C8P7 'CAP_0805LF-22UF,4V,20%,X6S,C95A':
 GROUP='PWR_MLCC_CAP',
 ROOM='PVCCIN_CPU0_DECAP_VR';

SECTION_NUMBER 1
 '@BASEBOARD_FAB2_LIB.BASEBOARD_FAB2(SCH_1):PAGE76_I248@MSTR_DISCRETE.CAP(CHIPS)':
 C_PATH='@baseboard_fab2_lib.baseboard_fab2(sch_1):page76_i248@mstr_discrete.cap~
(chips)',
 P_PATH='@baseboard_fab2_lib.baseboard_fab2(sch_1):page76_i248@mstr_discrete.cap~
(chips)',
 PATH='I248',
 DRAWING='@BASEBOARD_FAB2_LIB.BASEBOARD_FAB2(SCH_1):PAGE76',
 TOLERANCE='20%',
 MATERIAL='X6S',
 BOM_COST='PROC_SOCKET',
 PHYS_PAGE='76',
 XY='(-3950,1150)',
 ROT='0',
 VER='1',
 VALUE='22UF',
 PACK_TYPE='0805LF',
 PART_NUMBER='C95333-002',
 LOCATION='C8P7',
 ROOM='PVCCIN_CPU0_DECAP_VR',
 GROUP='PWR_MLCC_CAP',
 CDS_LIB='mstr_discrete',
 CDS_PART_NAME='CAP_0805LF-22UF,4V,20%,X6S,C95A',
 VOLTAGE='4V',
 PRIM_FILE='./archive_libs/mstr_discrete/cap/chips/chips.prt';

PART_NAME
 C8P8 'CAP_0805-100UF,4V,20%,X5R,6024A':
 GROUP='PWR_MCP_CAP',
 ROOM='VDDQ_ABC_PWR_VR';

SECTION_NUMBER 1
 '@BASEBOARD_FAB2_LIB.BASEBOARD_FAB2(SCH_1):PAGE76_I274@MSTR_DISCRETE.CAP(CHIPS)':
 C_PATH='@baseboard_fab2_lib.baseboard_fab2(sch_1):page76_i274@mstr_discrete.cap~
(chips)',
 P_PATH='@baseboard_fab2_lib.baseboard_fab2(sch_1):page76_i274@mstr_discrete.cap~
(chips)',
 PATH='I274',
 DRAWING='@BASEBOARD_FAB2_LIB.BASEBOARD_FAB2(SCH_1):PAGE76',
 NEW_PN='078.1071T.M002',
 NEW_MATERIAL='X6S',
 TOLERANCE='20%',
 SEC_TYPE='0805',
 MATERIAL='X5R',
 BOM_COST='MEM_VRD_PVDDQ_CD',
 PHYS_PAGE='76',
 XY='(-600,2200)',
 ROT='0',
 VER='1',
 VALUE='100UF',
 PACK_TYPE='0805',
 PART_NUMBER='602433-112',
 LOCATION='C8P8',
 ROOM='VDDQ_ABC_PWR_VR',
 GROUP='PWR_MCP_CAP',
 SEC='1',
 CDS_LIB='mstr_discrete',
 CDS_PART_NAME='CAP_0805-100UF,4V,20%,X5R,6024A',
 VOLTAGE='4V',
 PRIM_FILE='./archive_libs/mstr_discrete/cap/chips/chips.prt';

PART_NAME
 C8P9 'CAP_0805-100UF,4V,20%,X5R,6024A':
 GROUP='PWR_MCP_CAP',
 ROOM='VDDQ_ABC_PWR_VR';

SECTION_NUMBER 1
 '@BASEBOARD_FAB2_LIB.BASEBOARD_FAB2(SCH_1):PAGE76_I273@MSTR_DISCRETE.CAP(CHIPS)':
 C_PATH='@baseboard_fab2_lib.baseboard_fab2(sch_1):page76_i273@mstr_discrete.cap~
(chips)',
 P_PATH='@baseboard_fab2_lib.baseboard_fab2(sch_1):page76_i273@mstr_discrete.cap~
(chips)',
 PATH='I273',
 DRAWING='@BASEBOARD_FAB2_LIB.BASEBOARD_FAB2(SCH_1):PAGE76',
 NEW_PN='078.1071T.M002',
 NEW_MATERIAL='X6S',
 TOLERANCE='20%',
 SEC_TYPE='0805',
 MATERIAL='X5R',
 BOM_COST='MEM_VRD_PVDDQ_CD',
 PHYS_PAGE='76',
 XY='(-850,2200)',
 ROT='0',
 VER='1',
 VALUE='100UF',
 PACK_TYPE='0805',
 PART_NUMBER='602433-112',
 LOCATION='C8P9',
 ROOM='VDDQ_ABC_PWR_VR',
 GROUP='PWR_MCP_CAP',
 SEC='1',
 CDS_LIB='mstr_discrete',
 CDS_PART_NAME='CAP_0805-100UF,4V,20%,X5R,6024A',
 VOLTAGE='4V',
 PRIM_FILE='./archive_libs/mstr_discrete/cap/chips/chips.prt';

PART_NAME
 C8P10 'CAP_0805-47UF,4V,20%,X6S,C9533A':
 GROUP='PWR_MLCC_CAP',
 ROOM='PVCCIN_CPU1_DECAP_VR';

SECTION_NUMBER 1
 '@BASEBOARD_FAB2_LIB.BASEBOARD_FAB2(SCH_1):PAGE76_I127@MSTR_DISCRETE.CAP(CHIPS)':
 C_PATH='@baseboard_fab2_lib.baseboard_fab2(sch_1):page76_i127@mstr_discrete.cap~
(chips)',
 P_PATH='@baseboard_fab2_lib.baseboard_fab2(sch_1):page76_i127@mstr_discrete.cap~
(chips)',
 PATH='I127',
 DRAWING='@BASEBOARD_FAB2_LIB.BASEBOARD_FAB2(SCH_1):PAGE76',
 TOLERANCE='20%',
 MATERIAL='X6S',
 BOM_COST='PROC',
 PHYS_PAGE='76',
 XY='(-7750,2200)',
 ROT='0',
 VER='1',
 VALUE='47UF',
 PACK_TYPE='0805',
 PART_NUMBER='C95333-006',
 LOCATION='C8P10',
 ROOM='PVCCIN_CPU1_DECAP_VR',
 GROUP='PWR_MLCC_CAP',
 CDS_LIB='mstr_discrete',
 CDS_PART_NAME='CAP_0805-47UF,4V,20%,X6S,C9533A',
 VOLTAGE='4V',
 PRIM_FILE='./archive_libs/mstr_discrete/cap/chips/chips.prt';

PART_NAME
 C8P11 'CAP_0805-47UF,4V,20%,X6S,C9533A':
 GROUP='PWR_MLCC_CAP',
 ROOM='PVCCIN_CPU1_DECAP_VR';

SECTION_NUMBER 1
 '@BASEBOARD_FAB2_LIB.BASEBOARD_FAB2(SCH_1):PAGE76_I139@MSTR_DISCRETE.CAP(CHIPS)':
 C_PATH='@baseboard_fab2_lib.baseboard_fab2(sch_1):page76_i139@mstr_discrete.cap~
(chips)',
 P_PATH='@baseboard_fab2_lib.baseboard_fab2(sch_1):page76_i139@mstr_discrete.cap~
(chips)',
 PATH='I139',
 DRAWING='@BASEBOARD_FAB2_LIB.BASEBOARD_FAB2(SCH_1):PAGE76',
 TOLERANCE='20%',
 MATERIAL='X6S',
 BOM_COST='PROC',
 PHYS_PAGE='76',
 XY='(-7750,1500)',
 ROT='0',
 VER='1',
 VALUE='47UF',
 PACK_TYPE='0805',
 PART_NUMBER='C95333-006',
 LOCATION='C8P11',
 ROOM='PVCCIN_CPU1_DECAP_VR',
 GROUP='PWR_MLCC_CAP',
 CDS_LIB='mstr_discrete',
 CDS_PART_NAME='CAP_0805-47UF,4V,20%,X6S,C9533A',
 VOLTAGE='4V',
 PRIM_FILE='./archive_libs/mstr_discrete/cap/chips/chips.prt';

PART_NAME
 C8P12 'CAP_0805-47UF,4V,20%,X6S,C9533A':
 GROUP='PWR_MLCC_CAP',
 ROOM='PVCCIN_CPU1_DECAP_VR';

SECTION_NUMBER 1
 '@BASEBOARD_FAB2_LIB.BASEBOARD_FAB2(SCH_1):PAGE76_I107@MSTR_DISCRETE.CAP(CHIPS)':
 C_PATH='@baseboard_fab2_lib.baseboard_fab2(sch_1):page76_i107@mstr_discrete.cap~
(chips)',
 P_PATH='@baseboard_fab2_lib.baseboard_fab2(sch_1):page76_i107@mstr_discrete.cap~
(chips)',
 PATH='I107',
 DRAWING='@BASEBOARD_FAB2_LIB.BASEBOARD_FAB2(SCH_1):PAGE76',
 TOLERANCE='20%',
 MATERIAL='X6S',
 BOM_COST='PROC',
 PHYS_PAGE='76',
 XY='(-5950,800)',
 ROT='0',
 VER='1',
 VALUE='47UF',
 PACK_TYPE='0805',
 PART_NUMBER='C95333-006',
 LOCATION='C8P12',
 ROOM='PVCCIN_CPU1_DECAP_VR',
 GROUP='PWR_MLCC_CAP',
 CDS_LIB='mstr_discrete',
 CDS_PART_NAME='CAP_0805-47UF,4V,20%,X6S,C9533A',
 VOLTAGE='4V',
 PRIM_FILE='./archive_libs/mstr_discrete/cap/chips/chips.prt';

PART_NAME
 C8P13 'CAP_0805-47UF,4V,20%,X6S,C9533A':
 GROUP='PWR_MLCC_CAP',
 ROOM='PVCCIN_CPU1_DECAP_VR';

SECTION_NUMBER 1
 '@BASEBOARD_FAB2_LIB.BASEBOARD_FAB2(SCH_1):PAGE76_I132@MSTR_DISCRETE.CAP(CHIPS)':
 C_PATH='@baseboard_fab2_lib.baseboard_fab2(sch_1):page76_i132@mstr_discrete.cap~
(chips)',
 P_PATH='@baseboard_fab2_lib.baseboard_fab2(sch_1):page76_i132@mstr_discrete.cap~
(chips)',
 PATH='I132',
 DRAWING='@BASEBOARD_FAB2_LIB.BASEBOARD_FAB2(SCH_1):PAGE76',
 TOLERANCE='20%',
 MATERIAL='X6S',
 BOM_COST='PROC',
 PHYS_PAGE='76',
 XY='(-7150,1500)',
 ROT='0',
 VER='1',
 VALUE='47UF',
 PACK_TYPE='0805',
 PART_NUMBER='C95333-006',
 LOCATION='C8P13',
 ROOM='PVCCIN_CPU1_DECAP_VR',
 GROUP='PWR_MLCC_CAP',
 CDS_LIB='mstr_discrete',
 CDS_PART_NAME='CAP_0805-47UF,4V,20%,X6S,C9533A',
 VOLTAGE='4V',
 PRIM_FILE='./archive_libs/mstr_discrete/cap/chips/chips.prt';

PART_NAME
 C8P14 'CAP_0805-100UF,4V,20%,X5R,6024A':
 GROUP='PWR_MCP_CAP',
 ROOM='VDDQ_ABC_PWR_VR';

SECTION_NUMBER 1
 '@BASEBOARD_FAB2_LIB.BASEBOARD_FAB2(SCH_1):PAGE76_I272@MSTR_DISCRETE.CAP(CHIPS)':
 C_PATH='@baseboard_fab2_lib.baseboard_fab2(sch_1):page76_i272@mstr_discrete.cap~
(chips)',
 P_PATH='@baseboard_fab2_lib.baseboard_fab2(sch_1):page76_i272@mstr_discrete.cap~
(chips)',
 PATH='I272',
 DRAWING='@BASEBOARD_FAB2_LIB.BASEBOARD_FAB2(SCH_1):PAGE76',
 NEW_PN='078.1071T.M002',
 NEW_MATERIAL='X6S',
 TOLERANCE='20%',
 SEC_TYPE='0805',
 MATERIAL='X5R',
 BOM_COST='MEM_VRD_PVDDQ_CD',
 PHYS_PAGE='76',
 XY='(-1100,2200)',
 ROT='0',
 VER='1',
 VALUE='100UF',
 PACK_TYPE='0805',
 PART_NUMBER='602433-112',
 LOCATION='C8P14',
 ROOM='VDDQ_ABC_PWR_VR',
 GROUP='PWR_MCP_CAP',
 SEC='1',
 CDS_LIB='mstr_discrete',
 CDS_PART_NAME='CAP_0805-100UF,4V,20%,X5R,6024A',
 VOLTAGE='4V',
 PRIM_FILE='./archive_libs/mstr_discrete/cap/chips/chips.prt';

PART_NAME
 C8P15 'CAP_0805-100UF,4V,20%,X5R,6024A':
 GROUP='PWR_MCP_CAP',
 ROOM='VDDQ_ABC_PWR_VR';

SECTION_NUMBER 1
 '@BASEBOARD_FAB2_LIB.BASEBOARD_FAB2(SCH_1):PAGE76_I270@MSTR_DISCRETE.CAP(CHIPS)':
 C_PATH='@baseboard_fab2_lib.baseboard_fab2(sch_1):page76_i270@mstr_discrete.cap~
(chips)',
 P_PATH='@baseboard_fab2_lib.baseboard_fab2(sch_1):page76_i270@mstr_discrete.cap~
(chips)',
 PATH='I270',
 DRAWING='@BASEBOARD_FAB2_LIB.BASEBOARD_FAB2(SCH_1):PAGE76',
 NEW_PN='078.1071T.M002',
 NEW_MATERIAL='X6S',
 TOLERANCE='20%',
 SEC_TYPE='0805',
 MATERIAL='X5R',
 BOM_COST='MEM_VRD_PVDDQ_CD',
 PHYS_PAGE='76',
 XY='(-1350,2200)',
 ROT='0',
 VER='1',
 VALUE='100UF',
 PACK_TYPE='0805',
 PART_NUMBER='602433-112',
 LOCATION='C8P15',
 ROOM='VDDQ_ABC_PWR_VR',
 GROUP='PWR_MCP_CAP',
 SEC='1',
 CDS_LIB='mstr_discrete',
 CDS_PART_NAME='CAP_0805-100UF,4V,20%,X5R,6024A',
 VOLTAGE='4V',
 PRIM_FILE='./archive_libs/mstr_discrete/cap/chips/chips.prt';

PART_NAME
 C8P16 'CAP_0805-47UF,4V,20%,X6S,C9533A':
 GROUP='PWR_MLCC_CAP',
 ROOM='PVCCIN_CPU1_DECAP_VR';

SECTION_NUMBER 1
 '@BASEBOARD_FAB2_LIB.BASEBOARD_FAB2(SCH_1):PAGE76_I129@MSTR_DISCRETE.CAP(CHIPS)':
 C_PATH='@baseboard_fab2_lib.baseboard_fab2(sch_1):page76_i129@mstr_discrete.cap~
(chips)',
 P_PATH='@baseboard_fab2_lib.baseboard_fab2(sch_1):page76_i129@mstr_discrete.cap~
(chips)',
 PATH='I129',
 DRAWING='@BASEBOARD_FAB2_LIB.BASEBOARD_FAB2(SCH_1):PAGE76',
 TOLERANCE='20%',
 MATERIAL='X6S',
 BOM_COST='PROC',
 PHYS_PAGE='76',
 XY='(-6550,1500)',
 ROT='0',
 VER='1',
 VALUE='47UF',
 PACK_TYPE='0805',
 PART_NUMBER='C95333-006',
 LOCATION='C8P16',
 ROOM='PVCCIN_CPU1_DECAP_VR',
 GROUP='PWR_MLCC_CAP',
 CDS_LIB='mstr_discrete',
 CDS_PART_NAME='CAP_0805-47UF,4V,20%,X6S,C9533A',
 VOLTAGE='4V',
 PRIM_FILE='./archive_libs/mstr_discrete/cap/chips/chips.prt';

PART_NAME
 C8P17 'CAP_0805-47UF,4V,20%,X6S,C9533A':
 GROUP='PWR_MLCC_CAP',
 ROOM='PVCCIN_CPU1_DECAP_VR';

SECTION_NUMBER 1
 '@BASEBOARD_FAB2_LIB.BASEBOARD_FAB2(SCH_1):PAGE76_I252@MSTR_DISCRETE.CAP(CHIPS)':
 C_PATH='@baseboard_fab2_lib.baseboard_fab2(sch_1):page76_i252@mstr_discrete.cap~
(chips)',
 P_PATH='@baseboard_fab2_lib.baseboard_fab2(sch_1):page76_i252@mstr_discrete.cap~
(chips)',
 PATH='I252',
 DRAWING='@BASEBOARD_FAB2_LIB.BASEBOARD_FAB2(SCH_1):PAGE76',
 TOLERANCE='20%',
 SEC_TYPE='0805',
 MATERIAL='X6S',
 BOM_COST='PROC',
 PHYS_PAGE='76',
 XY='(-6550,800)',
 ROT='0',
 VER='1',
 VALUE='47UF',
 PACK_TYPE='0805',
 PART_NUMBER='C95333-006',
 LOCATION='C8P17',
 ROOM='PVCCIN_CPU1_DECAP_VR',
 GROUP='PWR_MLCC_CAP',
 SEC='1',
 CDS_LIB='mstr_discrete',
 CDS_PART_NAME='CAP_0805-47UF,4V,20%,X6S,C9533A',
 VOLTAGE='4V',
 PRIM_FILE='./archive_libs/mstr_discrete/cap/chips/chips.prt';

PART_NAME
 C8P18 'CAP_0805-47UF,4V,20%,X6S,C9533A':
 GROUP='PWR_MLCC_CAP',
 ROOM='PVCCIN_CPU1_DECAP_VR';

SECTION_NUMBER 1
 '@BASEBOARD_FAB2_LIB.BASEBOARD_FAB2(SCH_1):PAGE76_I92@MSTR_DISCRETE.CAP(CHIPS)':
 C_PATH='@baseboard_fab2_lib.baseboard_fab2(sch_1):page76_i92@mstr_discrete.cap(~
chips)',
 P_PATH='@baseboard_fab2_lib.baseboard_fab2(sch_1):page76_i92@mstr_discrete.cap(~
chips)',
 PATH='I92',
 DRAWING='@BASEBOARD_FAB2_LIB.BASEBOARD_FAB2(SCH_1):PAGE76',
 TOLERANCE='20%',
 MATERIAL='X6S',
 BOM_COST='PROC',
 PHYS_PAGE='76',
 XY='(-5950,2200)',
 ROT='0',
 VER='1',
 VALUE='47UF',
 PACK_TYPE='0805',
 PART_NUMBER='C95333-006',
 LOCATION='C8P18',
 ROOM='PVCCIN_CPU1_DECAP_VR',
 GROUP='PWR_MLCC_CAP',
 CDS_LIB='mstr_discrete',
 CDS_PART_NAME='CAP_0805-47UF,4V,20%,X6S,C9533A',
 VOLTAGE='4V',
 PRIM_FILE='./archive_libs/mstr_discrete/cap/chips/chips.prt';

PART_NAME
 C8P19 'CAP_0805-47UF,4V,20%,X6S,C9533A':
 GROUP='PWR_MLCC_CAP',
 ROOM='PVCCIN_CPU1_DECAP_VR';

SECTION_NUMBER 1
 '@BASEBOARD_FAB2_LIB.BASEBOARD_FAB2(SCH_1):PAGE76_I103@MSTR_DISCRETE.CAP(CHIPS)':
 C_PATH='@baseboard_fab2_lib.baseboard_fab2(sch_1):page76_i103@mstr_discrete.cap~
(chips)',
 P_PATH='@baseboard_fab2_lib.baseboard_fab2(sch_1):page76_i103@mstr_discrete.cap~
(chips)',
 PATH='I103',
 DRAWING='@BASEBOARD_FAB2_LIB.BASEBOARD_FAB2(SCH_1):PAGE76',
 TOLERANCE='20%',
 MATERIAL='X6S',
 BOM_COST='PROC',
 PHYS_PAGE='76',
 XY='(-5950,1500)',
 ROT='0',
 VER='1',
 VALUE='47UF',
 PACK_TYPE='0805',
 PART_NUMBER='C95333-006',
 LOCATION='C8P19',
 ROOM='PVCCIN_CPU1_DECAP_VR',
 GROUP='PWR_MLCC_CAP',
 CDS_LIB='mstr_discrete',
 CDS_PART_NAME='CAP_0805-47UF,4V,20%,X6S,C9533A',
 VOLTAGE='4V',
 PRIM_FILE='./archive_libs/mstr_discrete/cap/chips/chips.prt';

PART_NAME
 C8P20 'CAP_0805-47UF,4V,20%,X6S,C9533A':
 GROUP='PWR_MLCC_CAP',
 ROOM='PVCCIN_CPU1_DECAP_VR';

SECTION_NUMBER 1
 '@BASEBOARD_FAB2_LIB.BASEBOARD_FAB2(SCH_1):PAGE76_I89@MSTR_DISCRETE.CAP(CHIPS)':
 C_PATH='@baseboard_fab2_lib.baseboard_fab2(sch_1):page76_i89@mstr_discrete.cap(~
chips)',
 P_PATH='@baseboard_fab2_lib.baseboard_fab2(sch_1):page76_i89@mstr_discrete.cap(~
chips)',
 PATH='I89',
 DRAWING='@BASEBOARD_FAB2_LIB.BASEBOARD_FAB2(SCH_1):PAGE76',
 TOLERANCE='20%',
 MATERIAL='X6S',
 BOM_COST='PROC',
 PHYS_PAGE='76',
 XY='(-5650,2200)',
 ROT='0',
 VER='1',
 VALUE='47UF',
 PACK_TYPE='0805',
 PART_NUMBER='C95333-006',
 LOCATION='C8P20',
 ROOM='PVCCIN_CPU1_DECAP_VR',
 GROUP='PWR_MLCC_CAP',
 CDS_LIB='mstr_discrete',
 CDS_PART_NAME='CAP_0805-47UF,4V,20%,X6S,C9533A',
 VOLTAGE='4V',
 PRIM_FILE='./archive_libs/mstr_discrete/cap/chips/chips.prt';

PART_NAME
 C8P21 'CAP_0805-47UF,4V,20%,X6S,C9533A':
 GROUP='PWR_MLCC_CAP',
 ROOM='PVCCIN_CPU1_DECAP_VR';

SECTION_NUMBER 1
 '@BASEBOARD_FAB2_LIB.BASEBOARD_FAB2(SCH_1):PAGE76_I249@MSTR_DISCRETE.CAP(CHIPS)':
 C_PATH='@baseboard_fab2_lib.baseboard_fab2(sch_1):page76_i249@mstr_discrete.cap~
(chips)',
 P_PATH='@baseboard_fab2_lib.baseboard_fab2(sch_1):page76_i249@mstr_discrete.cap~
(chips)',
 PATH='I249',
 DRAWING='@BASEBOARD_FAB2_LIB.BASEBOARD_FAB2(SCH_1):PAGE76',
 TOLERANCE='20%',
 SEC_TYPE='0805',
 MATERIAL='X6S',
 BOM_COST='PROC',
 PHYS_PAGE='76',
 XY='(-6850,800)',
 ROT='0',
 VER='1',
 VALUE='47UF',
 PACK_TYPE='0805',
 PART_NUMBER='C95333-006',
 LOCATION='C8P21',
 ROOM='PVCCIN_CPU1_DECAP_VR',
 GROUP='PWR_MLCC_CAP',
 SEC='1',
 CDS_LIB='mstr_discrete',
 CDS_PART_NAME='CAP_0805-47UF,4V,20%,X6S,C9533A',
 VOLTAGE='4V',
 PRIM_FILE='./archive_libs/mstr_discrete/cap/chips/chips.prt';

PART_NAME
 C8P22 'CAP_0805-100UF,4V,20%,X5R,6024A':
 GROUP='PWR_MCP_CAP',
 ROOM='VDDQ_ABC_PWR_VR';

SECTION_NUMBER 1
 '@BASEBOARD_FAB2_LIB.BASEBOARD_FAB2(SCH_1):PAGE76_I264@MSTR_DISCRETE.CAP(CHIPS)':
 C_PATH='@baseboard_fab2_lib.baseboard_fab2(sch_1):page76_i264@mstr_discrete.cap~
(chips)',
 P_PATH='@baseboard_fab2_lib.baseboard_fab2(sch_1):page76_i264@mstr_discrete.cap~
(chips)',
 PATH='I264',
 DRAWING='@BASEBOARD_FAB2_LIB.BASEBOARD_FAB2(SCH_1):PAGE76',
 NEW_PN='078.1071T.M002',
 NEW_MATERIAL='X6S',
 TOLERANCE='20%',
 SEC_TYPE='0805',
 MATERIAL='X5R',
 BOM_COST='MEM_VRD_PVDDQ_CD',
 PHYS_PAGE='76',
 XY='(-2850,2200)',
 ROT='0',
 VER='1',
 VALUE='100UF',
 PACK_TYPE='0805',
 PART_NUMBER='602433-112',
 LOCATION='C8P22',
 ROOM='VDDQ_ABC_PWR_VR',
 GROUP='PWR_MCP_CAP',
 SEC='1',
 CDS_LIB='mstr_discrete',
 CDS_PART_NAME='CAP_0805-100UF,4V,20%,X5R,6024A',
 VOLTAGE='4V',
 PRIM_FILE='./archive_libs/mstr_discrete/cap/chips/chips.prt';

PART_NAME
 C8P23 'CAP_0805-100UF,4V,20%,X5R,6024A':
 GROUP='PWR_MCP_CAP',
 ROOM='VDDQ_ABC_PWR_VR';

SECTION_NUMBER 1
 '@BASEBOARD_FAB2_LIB.BASEBOARD_FAB2(SCH_1):PAGE76_I260@MSTR_DISCRETE.CAP(CHIPS)':
 C_PATH='@baseboard_fab2_lib.baseboard_fab2(sch_1):page76_i260@mstr_discrete.cap~
(chips)',
 P_PATH='@baseboard_fab2_lib.baseboard_fab2(sch_1):page76_i260@mstr_discrete.cap~
(chips)',
 PATH='I260',
 DRAWING='@BASEBOARD_FAB2_LIB.BASEBOARD_FAB2(SCH_1):PAGE76',
 NEW_PN='078.1071T.M002',
 NEW_MATERIAL='X6S',
 TOLERANCE='20%',
 SEC_TYPE='0805',
 MATERIAL='X5R',
 BOM_COST='MEM_VRD_PVDDQ_CD',
 PHYS_PAGE='76',
 XY='(-3850,2200)',
 ROT='0',
 VER='1',
 VALUE='100UF',
 PACK_TYPE='0805',
 PART_NUMBER='602433-112',
 LOCATION='C8P23',
 ROOM='VDDQ_ABC_PWR_VR',
 GROUP='PWR_MCP_CAP',
 SEC='1',
 CDS_LIB='mstr_discrete',
 CDS_PART_NAME='CAP_0805-100UF,4V,20%,X5R,6024A',
 VOLTAGE='4V',
 PRIM_FILE='./archive_libs/mstr_discrete/cap/chips/chips.prt';

PART_NAME
 C8P24 'CAP_0805-47UF,4V,20%,X6S,C9533A':
 GROUP='PWR_MLCC_CAP',
 ROOM='PVCCIN_CPU1_DECAP_VR';

SECTION_NUMBER 1
 '@BASEBOARD_FAB2_LIB.BASEBOARD_FAB2(SCH_1):PAGE76_I217@MSTR_DISCRETE.CAP(CHIPS)':
 C_PATH='@baseboard_fab2_lib.baseboard_fab2(sch_1):page76_i217@mstr_discrete.cap~
(chips)',
 P_PATH='@baseboard_fab2_lib.baseboard_fab2(sch_1):page76_i217@mstr_discrete.cap~
(chips)',
 PATH='I217',
 DRAWING='@BASEBOARD_FAB2_LIB.BASEBOARD_FAB2(SCH_1):PAGE76',
 TOLERANCE='20%',
 SEC_TYPE='0805',
 MATERIAL='X6S',
 BOM_COST='PROC',
 PHYS_PAGE='76',
 XY='(-7750,800)',
 ROT='0',
 VER='1',
 VALUE='47UF',
 PACK_TYPE='0805',
 PART_NUMBER='C95333-006',
 LOCATION='C8P24',
 ROOM='PVCCIN_CPU1_DECAP_VR',
 GROUP='PWR_MLCC_CAP',
 SEC='1',
 CDS_LIB='mstr_discrete',
 CDS_PART_NAME='CAP_0805-47UF,4V,20%,X6S,C9533A',
 VOLTAGE='4V',
 PRIM_FILE='./archive_libs/mstr_discrete/cap/chips/chips.prt';

PART_NAME
 C8P25 'CAP_0805-47UF,4V,20%,X6S,C9533A':
 GROUP='PWR_MLCC_CAP',
 ROOM='PVCCIN_CPU1_DECAP_VR';

SECTION_NUMBER 1
 '@BASEBOARD_FAB2_LIB.BASEBOARD_FAB2(SCH_1):PAGE76_I251@MSTR_DISCRETE.CAP(CHIPS)':
 C_PATH='@baseboard_fab2_lib.baseboard_fab2(sch_1):page76_i251@mstr_discrete.cap~
(chips)',
 P_PATH='@baseboard_fab2_lib.baseboard_fab2(sch_1):page76_i251@mstr_discrete.cap~
(chips)',
 PATH='I251',
 DRAWING='@BASEBOARD_FAB2_LIB.BASEBOARD_FAB2(SCH_1):PAGE76',
 TOLERANCE='20%',
 SEC_TYPE='0805',
 MATERIAL='X6S',
 BOM_COST='PROC',
 PHYS_PAGE='76',
 XY='(-7150,800)',
 ROT='0',
 VER='1',
 VALUE='47UF',
 PACK_TYPE='0805',
 PART_NUMBER='C95333-006',
 LOCATION='C8P25',
 ROOM='PVCCIN_CPU1_DECAP_VR',
 GROUP='PWR_MLCC_CAP',
 SEC='1',
 CDS_LIB='mstr_discrete',
 CDS_PART_NAME='CAP_0805-47UF,4V,20%,X6S,C9533A',
 VOLTAGE='4V',
 PRIM_FILE='./archive_libs/mstr_discrete/cap/chips/chips.prt';

PART_NAME
 C8P26 'CAP_0805-47UF,4V,20%,X6S,C9533A':
 GROUP='PWR_MLCC_CAP',
 ROOM='PVCCIN_CPU1_DECAP_VR';

SECTION_NUMBER 1
 '@BASEBOARD_FAB2_LIB.BASEBOARD_FAB2(SCH_1):PAGE76_I118@MSTR_DISCRETE.CAP(CHIPS)':
 C_PATH='@baseboard_fab2_lib.baseboard_fab2(sch_1):page76_i118@mstr_discrete.cap~
(chips)',
 P_PATH='@baseboard_fab2_lib.baseboard_fab2(sch_1):page76_i118@mstr_discrete.cap~
(chips)',
 PATH='I118',
 DRAWING='@BASEBOARD_FAB2_LIB.BASEBOARD_FAB2(SCH_1):PAGE76',
 TOLERANCE='20%',
 MATERIAL='X6S',
 BOM_COST='PROC',
 PHYS_PAGE='76',
 XY='(-7150,2200)',
 ROT='0',
 VER='1',
 VALUE='47UF',
 PACK_TYPE='0805',
 PART_NUMBER='C95333-006',
 LOCATION='C8P26',
 ROOM='PVCCIN_CPU1_DECAP_VR',
 GROUP='PWR_MLCC_CAP',
 CDS_LIB='mstr_discrete',
 CDS_PART_NAME='CAP_0805-47UF,4V,20%,X6S,C9533A',
 VOLTAGE='4V',
 PRIM_FILE='./archive_libs/mstr_discrete/cap/chips/chips.prt';

PART_NAME
 C8P27 'CAP_0805-47UF,4V,20%,X6S,C9533A':
 GROUP='PWR_MLCC_CAP',
 ROOM='PVCCIN_CPU1_DECAP_VR';

SECTION_NUMBER 1
 '@BASEBOARD_FAB2_LIB.BASEBOARD_FAB2(SCH_1):PAGE76_I250@MSTR_DISCRETE.CAP(CHIPS)':
 C_PATH='@baseboard_fab2_lib.baseboard_fab2(sch_1):page76_i250@mstr_discrete.cap~
(chips)',
 P_PATH='@baseboard_fab2_lib.baseboard_fab2(sch_1):page76_i250@mstr_discrete.cap~
(chips)',
 PATH='I250',
 DRAWING='@BASEBOARD_FAB2_LIB.BASEBOARD_FAB2(SCH_1):PAGE76',
 TOLERANCE='20%',
 SEC_TYPE='0805',
 MATERIAL='X6S',
 BOM_COST='PROC',
 PHYS_PAGE='76',
 XY='(-7450,800)',
 ROT='0',
 VER='1',
 VALUE='47UF',
 PACK_TYPE='0805',
 PART_NUMBER='C95333-006',
 LOCATION='C8P27',
 ROOM='PVCCIN_CPU1_DECAP_VR',
 GROUP='PWR_MLCC_CAP',
 SEC='1',
 CDS_LIB='mstr_discrete',
 CDS_PART_NAME='CAP_0805-47UF,4V,20%,X6S,C9533A',
 VOLTAGE='4V',
 PRIM_FILE='./archive_libs/mstr_discrete/cap/chips/chips.prt';

PART_NAME
 C8P28 'CAP_0805-47UF,4V,20%,X6S,C9533A':
 GROUP='PWR_MLCC_CAP',
 ROOM='PVCCIN_CPU1_DECAP_VR';

SECTION_NUMBER 1
 '@BASEBOARD_FAB2_LIB.BASEBOARD_FAB2(SCH_1):PAGE76_I137@MSTR_DISCRETE.CAP(CHIPS)':
 C_PATH='@baseboard_fab2_lib.baseboard_fab2(sch_1):page76_i137@mstr_discrete.cap~
(chips)',
 P_PATH='@baseboard_fab2_lib.baseboard_fab2(sch_1):page76_i137@mstr_discrete.cap~
(chips)',
 PATH='I137',
 DRAWING='@BASEBOARD_FAB2_LIB.BASEBOARD_FAB2(SCH_1):PAGE76',
 TOLERANCE='20%',
 MATERIAL='X6S',
 BOM_COST='PROC',
 PHYS_PAGE='76',
 XY='(-7450,1500)',
 ROT='0',
 VER='1',
 VALUE='47UF',
 PACK_TYPE='0805',
 PART_NUMBER='C95333-006',
 LOCATION='C8P28',
 ROOM='PVCCIN_CPU1_DECAP_VR',
 GROUP='PWR_MLCC_CAP',
 CDS_LIB='mstr_discrete',
 CDS_PART_NAME='CAP_0805-47UF,4V,20%,X6S,C9533A',
 VOLTAGE='4V',
 PRIM_FILE='./archive_libs/mstr_discrete/cap/chips/chips.prt';

PART_NAME
 C8P29 'CAP_0805-47UF,4V,20%,X6S,C9533A':
 GROUP='PWR_MLCC_CAP',
 ROOM='PVCCIN_CPU1_DECAP_VR';

SECTION_NUMBER 1
 '@BASEBOARD_FAB2_LIB.BASEBOARD_FAB2(SCH_1):PAGE76_I125@MSTR_DISCRETE.CAP(CHIPS)':
 C_PATH='@baseboard_fab2_lib.baseboard_fab2(sch_1):page76_i125@mstr_discrete.cap~
(chips)',
 P_PATH='@baseboard_fab2_lib.baseboard_fab2(sch_1):page76_i125@mstr_discrete.cap~
(chips)',
 PATH='I125',
 DRAWING='@BASEBOARD_FAB2_LIB.BASEBOARD_FAB2(SCH_1):PAGE76',
 TOLERANCE='20%',
 MATERIAL='X6S',
 BOM_COST='PROC',
 PHYS_PAGE='76',
 XY='(-7450,2200)',
 ROT='0',
 VER='1',
 VALUE='47UF',
 PACK_TYPE='0805',
 PART_NUMBER='C95333-006',
 LOCATION='C8P29',
 ROOM='PVCCIN_CPU1_DECAP_VR',
 GROUP='PWR_MLCC_CAP',
 CDS_LIB='mstr_discrete',
 CDS_PART_NAME='CAP_0805-47UF,4V,20%,X6S,C9533A',
 VOLTAGE='4V',
 PRIM_FILE='./archive_libs/mstr_discrete/cap/chips/chips.prt';

PART_NAME
 C8P30 'CAP_0805-100UF,4V,20%,X5R,6024A':
 GROUP='PWR_MLCC_CAP',
 ROOM='VDDQ_ABC_PWR_VR';

SECTION_NUMBER 1
 '@BASEBOARD_FAB2_LIB.BASEBOARD_FAB2(SCH_1):PAGE225_I313@MSTR_DISCRETE.CAP(CHIPS)':
 C_PATH='@baseboard_fab2_lib.baseboard_fab2(sch_1):page225_i313@mstr_discrete.ca~
p(chips)',
 P_PATH='@baseboard_fab2_lib.baseboard_fab2(sch_1):page225_i313@mstr_discrete.ca~
p(chips)',
 PATH='I313',
 DRAWING='@BASEBOARD_FAB2_LIB.BASEBOARD_FAB2(SCH_1):PAGE225',
 NEW_PN='078.1071T.M002',
 NEW_MATERIAL='X6S',
 BOM_SS='NOPOP',
 TOLERANCE='20%',
 SEC_TYPE='0805',
 MATERIAL='X5R',
 BOM_COST='MEM_VRD_PVDDQ_CD',
 PHYS_PAGE='225',
 XY='(-2325,3100)',
 ROT='0',
 VER='1',
 VALUE='100UF',
 PACK_TYPE='0805',
 PART_NUMBER='602433-112',
 LOCATION='C8P30',
 ROOM='VDDQ_ABC_PWR_VR',
 GROUP='PWR_MLCC_CAP',
 SEC='1',
 CDS_LIB='mstr_discrete',
 CDS_PART_NAME='CAP_0805-100UF,4V,20%,X5R,6024A',
 VOLTAGE='4V',
 PRIM_FILE='./archive_libs/mstr_discrete/cap/chips/chips.prt';

PART_NAME
 C8P31 'CAP_0805-100UF,4V,20%,X5R,6024A':
 GROUP='PWR_MLCC_CAP',
 ROOM='VDDQ_ABC_PWR_VR';

SECTION_NUMBER 1
 '@BASEBOARD_FAB2_LIB.BASEBOARD_FAB2(SCH_1):PAGE225_I314@MSTR_DISCRETE.CAP(CHIPS)':
 C_PATH='@baseboard_fab2_lib.baseboard_fab2(sch_1):page225_i314@mstr_discrete.ca~
p(chips)',
 P_PATH='@baseboard_fab2_lib.baseboard_fab2(sch_1):page225_i314@mstr_discrete.ca~
p(chips)',
 PATH='I314',
 DRAWING='@BASEBOARD_FAB2_LIB.BASEBOARD_FAB2(SCH_1):PAGE225',
 NEW_PN='078.1071T.M002',
 NEW_MATERIAL='X6S',
 BOM_SS='NOPOP',
 TOLERANCE='20%',
 SEC_TYPE='0805',
 MATERIAL='X5R',
 BOM_COST='MEM_VRD_PVDDQ_CD',
 PHYS_PAGE='225',
 XY='(-1975,3100)',
 ROT='0',
 VER='1',
 VALUE='100UF',
 PACK_TYPE='0805',
 PART_NUMBER='602433-112',
 LOCATION='C8P31',
 ROOM='VDDQ_ABC_PWR_VR',
 GROUP='PWR_MLCC_CAP',
 SEC='1',
 CDS_LIB='mstr_discrete',
 CDS_PART_NAME='CAP_0805-100UF,4V,20%,X5R,6024A',
 VOLTAGE='4V',
 PRIM_FILE='./archive_libs/mstr_discrete/cap/chips/chips.prt';

PART_NAME
 C8P32 'CAP_0805-100UF,4V,20%,X5R,6024A':
 GROUP='PWR_MLCC_CAP',
 ROOM='VDDQ_ABC_PWR_VR';

SECTION_NUMBER 1
 '@BASEBOARD_FAB2_LIB.BASEBOARD_FAB2(SCH_1):PAGE225_I317@MSTR_DISCRETE.CAP(CHIPS)':
 C_PATH='@baseboard_fab2_lib.baseboard_fab2(sch_1):page225_i317@mstr_discrete.ca~
p(chips)',
 P_PATH='@baseboard_fab2_lib.baseboard_fab2(sch_1):page225_i317@mstr_discrete.ca~
p(chips)',
 PATH='I317',
 DRAWING='@BASEBOARD_FAB2_LIB.BASEBOARD_FAB2(SCH_1):PAGE225',
 NEW_PN='078.1071T.M002',
 NEW_MATERIAL='X6S',
 BOM_SS='NOPOP',
 TOLERANCE='20%',
 SEC_TYPE='0805',
 MATERIAL='X5R',
 BOM_COST='MEM_VRD_PVDDQ_CD',
 PHYS_PAGE='225',
 XY='(800,3025)',
 ROT='0',
 VER='1',
 VALUE='100UF',
 PACK_TYPE='0805',
 PART_NUMBER='602433-112',
 LOCATION='C8P32',
 ROOM='VDDQ_ABC_PWR_VR',
 GROUP='PWR_MLCC_CAP',
 SEC='1',
 CDS_LIB='mstr_discrete',
 CDS_PART_NAME='CAP_0805-100UF,4V,20%,X5R,6024A',
 VOLTAGE='4V',
 PRIM_FILE='./archive_libs/mstr_discrete/cap/chips/chips.prt';

PART_NAME
 C8P33 'CAP_0805-100UF,4V,20%,X5R,6024A':
 GROUP='PWR_MLCC_CAP',
 ROOM='VDDQ_ABC_PWR_VR';

SECTION_NUMBER 1
 '@BASEBOARD_FAB2_LIB.BASEBOARD_FAB2(SCH_1):PAGE225_I316@MSTR_DISCRETE.CAP(CHIPS)':
 C_PATH='@baseboard_fab2_lib.baseboard_fab2(sch_1):page225_i316@mstr_discrete.ca~
p(chips)',
 P_PATH='@baseboard_fab2_lib.baseboard_fab2(sch_1):page225_i316@mstr_discrete.ca~
p(chips)',
 PATH='I316',
 DRAWING='@BASEBOARD_FAB2_LIB.BASEBOARD_FAB2(SCH_1):PAGE225',
 NEW_PN='078.1071T.M002',
 NEW_MATERIAL='X6S',
 BOM_SS='NOPOP',
 TOLERANCE='20%',
 SEC_TYPE='0805',
 MATERIAL='X5R',
 BOM_COST='MEM_VRD_PVDDQ_CD',
 PHYS_PAGE='225',
 XY='(450,3025)',
 ROT='0',
 VER='1',
 VALUE='100UF',
 PACK_TYPE='0805',
 PART_NUMBER='602433-112',
 LOCATION='C8P33',
 ROOM='VDDQ_ABC_PWR_VR',
 GROUP='PWR_MLCC_CAP',
 SEC='1',
 CDS_LIB='mstr_discrete',
 CDS_PART_NAME='CAP_0805-100UF,4V,20%,X5R,6024A',
 VOLTAGE='4V',
 PRIM_FILE='./archive_libs/mstr_discrete/cap/chips/chips.prt';

PART_NAME
 C8P34 'CAP_0805-100UF,4V,20%,X5R,6024A':
 GROUP='PWR_MLCC_CAP',
 ROOM='VDDQ_ABC_PWR_VR';

SECTION_NUMBER 1
 '@BASEBOARD_FAB2_LIB.BASEBOARD_FAB2(SCH_1):PAGE225_I315@MSTR_DISCRETE.CAP(CHIPS)':
 C_PATH='@baseboard_fab2_lib.baseboard_fab2(sch_1):page225_i315@mstr_discrete.ca~
p(chips)',
 P_PATH='@baseboard_fab2_lib.baseboard_fab2(sch_1):page225_i315@mstr_discrete.ca~
p(chips)',
 PATH='I315',
 DRAWING='@BASEBOARD_FAB2_LIB.BASEBOARD_FAB2(SCH_1):PAGE225',
 NEW_PN='078.1071T.M002',
 NEW_MATERIAL='X6S',
 BOM_SS='NOPOP',
 TOLERANCE='20%',
 SEC_TYPE='0805',
 MATERIAL='X5R',
 BOM_COST='MEM_VRD_PVDDQ_CD',
 PHYS_PAGE='225',
 XY='(100,3025)',
 ROT='0',
 VER='1',
 VALUE='100UF',
 PACK_TYPE='0805',
 PART_NUMBER='602433-112',
 LOCATION='C8P34',
 ROOM='VDDQ_ABC_PWR_VR',
 GROUP='PWR_MLCC_CAP',
 SEC='1',
 CDS_LIB='mstr_discrete',
 CDS_PART_NAME='CAP_0805-100UF,4V,20%,X5R,6024A',
 VOLTAGE='4V',
 PRIM_FILE='./archive_libs/mstr_discrete/cap/chips/chips.prt';

PART_NAME
 C8T1 'CAP_A_0603V-47UF,4V,20%,X5R,60A':
 GROUP='PWR_MLCC_CAP';

SECTION_NUMBER 1
 '@BASEBOARD_FAB2_LIB.BASEBOARD_FAB2(SCH_1):PAGE225_I202@DEV_DISCRETE.CAP_A(CHIPS)':
 C_PATH='@baseboard_fab2_lib.baseboard_fab2(sch_1):page225_i202@dev_discrete.cap~
_a(chips)',
 P_PATH='@baseboard_fab2_lib.baseboard_fab2(sch_1):page225_i202@dev_discrete.cap~
_a(chips)',
 PATH='I202',
 DRAWING='@BASEBOARD_FAB2_LIB.BASEBOARD_FAB2(SCH_1):PAGE225',
 BOM_SS='NOPOP',
 TOLERANCE='20%',
 SEC_TYPE='0603V',
 MATERIAL='X5R',
 PHYS_PAGE='225',
 XY='(3650,1725)',
 ROT='0',
 VER='1',
 VALUE='47UF',
 PACK_TYPE='0603V',
 PART_NUMBER='602433-106',
 LOCATION='C8T1',
 GROUP='PWR_MLCC_CAP',
 SEC='1',
 CDS_LIB='dev_discrete',
 CDS_PART_NAME='CAP_A_0603V-47UF,4V,20%,X5R,60A',
 VOLTAGE='4V',
 PRIM_FILE='./archive_libs/discrete/cap_a/chips/chips.prt';

PART_NAME
 C8T2 'CAP_A_0603V-47UF,4V,20%,X5R,60A':
 GROUP='PWR_MLCC_CAP';

SECTION_NUMBER 1
 '@BASEBOARD_FAB2_LIB.BASEBOARD_FAB2(SCH_1):PAGE225_I198@DEV_DISCRETE.CAP_A(CHIPS)':
 C_PATH='@baseboard_fab2_lib.baseboard_fab2(sch_1):page225_i198@dev_discrete.cap~
_a(chips)',
 P_PATH='@baseboard_fab2_lib.baseboard_fab2(sch_1):page225_i198@dev_discrete.cap~
_a(chips)',
 PATH='I198',
 DRAWING='@BASEBOARD_FAB2_LIB.BASEBOARD_FAB2(SCH_1):PAGE225',
 BOM_SS='NOPOP',
 TOLERANCE='20%',
 SEC_TYPE='0603V',
 MATERIAL='X5R',
 PHYS_PAGE='225',
 XY='(3350,975)',
 ROT='0',
 VER='1',
 VALUE='47UF',
 PACK_TYPE='0603V',
 PART_NUMBER='602433-106',
 LOCATION='C8T2',
 GROUP='PWR_MLCC_CAP',
 SEC='1',
 CDS_LIB='dev_discrete',
 CDS_PART_NAME='CAP_A_0603V-47UF,4V,20%,X5R,60A',
 VOLTAGE='4V',
 PRIM_FILE='./archive_libs/discrete/cap_a/chips/chips.prt';

PART_NAME
 C8T3 'CAP_0805-100UF,4V,20%,X5R,6024A':
 GROUP='PWR_MLCC_CAP',
 ROOM='VDDQ_ABC_PWR_VR';

SECTION_NUMBER 1
 '@BASEBOARD_FAB2_LIB.BASEBOARD_FAB2(SCH_1):PAGE229_I41@MSTR_DISCRETE.CAP(CHIPS)':
 C_PATH='@baseboard_fab2_lib.baseboard_fab2(sch_1):page229_i41@mstr_discrete.cap~
(chips)',
 P_PATH='@baseboard_fab2_lib.baseboard_fab2(sch_1):page229_i41@mstr_discrete.cap~
(chips)',
 PATH='I41',
 DRAWING='@BASEBOARD_FAB2_LIB.BASEBOARD_FAB2(SCH_1):PAGE229',
 NEW_PN='078.1071T.M002',
 NEW_MATERIAL='X6S',
 TOLERANCE='20%',
 SEC_TYPE='0805',
 MATERIAL='X5R',
 BOM_COST='MEM_VRD_PVDDQ_CD',
 PHYS_PAGE='229',
 XY='(3800,3200)',
 ROT='0',
 VER='1',
 VALUE='100UF',
 PACK_TYPE='0805',
 PART_NUMBER='602433-112',
 LOCATION='C8T3',
 ROOM='VDDQ_ABC_PWR_VR',
 GROUP='PWR_MLCC_CAP',
 SEC='1',
 CDS_LIB='mstr_discrete',
 CDS_PART_NAME='CAP_0805-100UF,4V,20%,X5R,6024A',
 VOLTAGE='4V',
 PRIM_FILE='./archive_libs/mstr_discrete/cap/chips/chips.prt';

PART_NAME
 C8T4 'CAP_A_0603V-47UF,4V,20%,X5R,60A':
 GROUP='PWR_MLCC_CAP';

SECTION_NUMBER 1
 '@BASEBOARD_FAB2_LIB.BASEBOARD_FAB2(SCH_1):PAGE225_I196@DEV_DISCRETE.CAP_A(CHIPS)':
 C_PATH='@baseboard_fab2_lib.baseboard_fab2(sch_1):page225_i196@dev_discrete.cap~
_a(chips)',
 P_PATH='@baseboard_fab2_lib.baseboard_fab2(sch_1):page225_i196@dev_discrete.cap~
_a(chips)',
 PATH='I196',
 DRAWING='@BASEBOARD_FAB2_LIB.BASEBOARD_FAB2(SCH_1):PAGE225',
 BOM_SS='078.1061T.M001',
 TOLERANCE='20%',
 SEC_TYPE='0603V',
 MATERIAL='X5R',
 PHYS_PAGE='225',
 XY='(2600,975)',
 ROT='0',
 VER='1',
 VALUE='47UF',
 PACK_TYPE='0603V',
 PART_NUMBER='602433-106',
 LOCATION='C8T4',
 GROUP='PWR_MLCC_CAP',
 SEC='1',
 CDS_LIB='dev_discrete',
 CDS_PART_NAME='CAP_A_0603V-47UF,4V,20%,X5R,60A',
 VOLTAGE='4V',
 PRIM_FILE='./archive_libs/discrete/cap_a/chips/chips.prt';

PART_NAME
 C8T5 'CAP_A_0603V-47UF,4V,20%,X5R,60A':
 GROUP='PWR_MLCC_CAP';

SECTION_NUMBER 1
 '@BASEBOARD_FAB2_LIB.BASEBOARD_FAB2(SCH_1):PAGE225_I297@DEV_DISCRETE.CAP_A(CHIPS)':
 C_PATH='@baseboard_fab2_lib.baseboard_fab2(sch_1):page225_i297@dev_discrete.cap~
_a(chips)',
 P_PATH='@baseboard_fab2_lib.baseboard_fab2(sch_1):page225_i297@dev_discrete.cap~
_a(chips)',
 PATH='I297',
 DRAWING='@BASEBOARD_FAB2_LIB.BASEBOARD_FAB2(SCH_1):PAGE225',
 BOM_SS='E15431-004',
 TOLERANCE='20%',
 SEC_TYPE='0603V',
 MATERIAL='X5R',
 PHYS_PAGE='225',
 XY='(-225,-450)',
 ROT='0',
 VER='1',
 VALUE='47UF',
 PACK_TYPE='0603V',
 PART_NUMBER='602433-106',
 LOCATION='C8T5',
 GROUP='PWR_MLCC_CAP',
 SEC='1',
 CDS_LIB='dev_discrete',
 CDS_PART_NAME='CAP_A_0603V-47UF,4V,20%,X5R,60A',
 VOLTAGE='4V',
 PRIM_FILE='./archive_libs/discrete/cap_a/chips/chips.prt';

PART_NAME
 C8T6 'CAP_A_0603V-47UF,4V,20%,X5R,60A':
 GROUP='PWR_MLCC_CAP';

SECTION_NUMBER 1
 '@BASEBOARD_FAB2_LIB.BASEBOARD_FAB2(SCH_1):PAGE225_I299@DEV_DISCRETE.CAP_A(CHIPS)':
 C_PATH='@baseboard_fab2_lib.baseboard_fab2(sch_1):page225_i299@dev_discrete.cap~
_a(chips)',
 P_PATH='@baseboard_fab2_lib.baseboard_fab2(sch_1):page225_i299@dev_discrete.cap~
_a(chips)',
 PATH='I299',
 DRAWING='@BASEBOARD_FAB2_LIB.BASEBOARD_FAB2(SCH_1):PAGE225',
 BOM_SS='E15431-004',
 TOLERANCE='20%',
 SEC_TYPE='0603V',
 MATERIAL='X5R',
 PHYS_PAGE='225',
 XY='(400,-450)',
 ROT='0',
 VER='1',
 VALUE='47UF',
 PACK_TYPE='0603V',
 PART_NUMBER='602433-106',
 LOCATION='C8T6',
 GROUP='PWR_MLCC_CAP',
 SEC='1',
 CDS_LIB='dev_discrete',
 CDS_PART_NAME='CAP_A_0603V-47UF,4V,20%,X5R,60A',
 VOLTAGE='4V',
 PRIM_FILE='./archive_libs/discrete/cap_a/chips/chips.prt';

PART_NAME
 C8T7 'CAP_A_0603V-47UF,4V,20%,X5R,60A':
 GROUP='PWR_MLCC_CAP';

SECTION_NUMBER 1
 '@BASEBOARD_FAB2_LIB.BASEBOARD_FAB2(SCH_1):PAGE225_I300@DEV_DISCRETE.CAP_A(CHIPS)':
 C_PATH='@baseboard_fab2_lib.baseboard_fab2(sch_1):page225_i300@dev_discrete.cap~
_a(chips)',
 P_PATH='@baseboard_fab2_lib.baseboard_fab2(sch_1):page225_i300@dev_discrete.cap~
_a(chips)',
 PATH='I300',
 DRAWING='@BASEBOARD_FAB2_LIB.BASEBOARD_FAB2(SCH_1):PAGE225',
 BOM_SS='E15431-004',
 TOLERANCE='20%',
 SEC_TYPE='0603V',
 MATERIAL='X5R',
 PHYS_PAGE='225',
 XY='(700,-450)',
 ROT='0',
 VER='1',
 VALUE='47UF',
 PACK_TYPE='0603V',
 PART_NUMBER='602433-106',
 LOCATION='C8T7',
 GROUP='PWR_MLCC_CAP',
 SEC='1',
 CDS_LIB='dev_discrete',
 CDS_PART_NAME='CAP_A_0603V-47UF,4V,20%,X5R,60A',
 VOLTAGE='4V',
 PRIM_FILE='./archive_libs/discrete/cap_a/chips/chips.prt';

PART_NAME
 C8T8 'CAP_A_0603V-47UF,4V,20%,X5R,60A':
 GROUP='PWR_MLCC_CAP';

SECTION_NUMBER 1
 '@BASEBOARD_FAB2_LIB.BASEBOARD_FAB2(SCH_1):PAGE225_I301@DEV_DISCRETE.CAP_A(CHIPS)':
 C_PATH='@baseboard_fab2_lib.baseboard_fab2(sch_1):page225_i301@dev_discrete.cap~
_a(chips)',
 P_PATH='@baseboard_fab2_lib.baseboard_fab2(sch_1):page225_i301@dev_discrete.cap~
_a(chips)',
 PATH='I301',
 DRAWING='@BASEBOARD_FAB2_LIB.BASEBOARD_FAB2(SCH_1):PAGE225',
 BOM_SS='E15431-004',
 TOLERANCE='20%',
 SEC_TYPE='0603V',
 MATERIAL='X5R',
 PHYS_PAGE='225',
 XY='(975,-450)',
 ROT='0',
 VER='1',
 VALUE='47UF',
 PACK_TYPE='0603V',
 PART_NUMBER='602433-106',
 LOCATION='C8T8',
 GROUP='PWR_MLCC_CAP',
 SEC='1',
 CDS_LIB='dev_discrete',
 CDS_PART_NAME='CAP_A_0603V-47UF,4V,20%,X5R,60A',
 VOLTAGE='4V',
 PRIM_FILE='./archive_libs/discrete/cap_a/chips/chips.prt';

PART_NAME
 C8T9 'CAP_A_0603V-47UF,4V,20%,X5R,60A':
 GROUP='PWR_MLCC_CAP';

SECTION_NUMBER 1
 '@BASEBOARD_FAB2_LIB.BASEBOARD_FAB2(SCH_1):PAGE225_I303@DEV_DISCRETE.CAP_A(CHIPS)':
 C_PATH='@baseboard_fab2_lib.baseboard_fab2(sch_1):page225_i303@dev_discrete.cap~
_a(chips)',
 P_PATH='@baseboard_fab2_lib.baseboard_fab2(sch_1):page225_i303@dev_discrete.cap~
_a(chips)',
 PATH='I303',
 DRAWING='@BASEBOARD_FAB2_LIB.BASEBOARD_FAB2(SCH_1):PAGE225',
 BOM_SS='E15431-004',
 TOLERANCE='20%',
 SEC_TYPE='0603V',
 MATERIAL='X5R',
 PHYS_PAGE='225',
 XY='(1550,-450)',
 ROT='0',
 VER='1',
 VALUE='47UF',
 PACK_TYPE='0603V',
 PART_NUMBER='602433-106',
 LOCATION='C8T9',
 GROUP='PWR_MLCC_CAP',
 SEC='1',
 CDS_LIB='dev_discrete',
 CDS_PART_NAME='CAP_A_0603V-47UF,4V,20%,X5R,60A',
 VOLTAGE='4V',
 PRIM_FILE='./archive_libs/discrete/cap_a/chips/chips.prt';

PART_NAME
 C8T10 'CAP_A_0603V-47UF,4V,20%,X5R,60A':
 GROUP='PWR_MLCC_CAP';

SECTION_NUMBER 1
 '@BASEBOARD_FAB2_LIB.BASEBOARD_FAB2(SCH_1):PAGE225_I304@DEV_DISCRETE.CAP_A(CHIPS)':
 C_PATH='@baseboard_fab2_lib.baseboard_fab2(sch_1):page225_i304@dev_discrete.cap~
_a(chips)',
 P_PATH='@baseboard_fab2_lib.baseboard_fab2(sch_1):page225_i304@dev_discrete.cap~
_a(chips)',
 PATH='I304',
 DRAWING='@BASEBOARD_FAB2_LIB.BASEBOARD_FAB2(SCH_1):PAGE225',
 BOM_SS='E15431-004',
 TOLERANCE='20%',
 SEC_TYPE='0603V',
 MATERIAL='X5R',
 PHYS_PAGE='225',
 XY='(1850,-450)',
 ROT='0',
 VER='1',
 VALUE='47UF',
 PACK_TYPE='0603V',
 PART_NUMBER='602433-106',
 LOCATION='C8T10',
 GROUP='PWR_MLCC_CAP',
 SEC='1',
 CDS_LIB='dev_discrete',
 CDS_PART_NAME='CAP_A_0603V-47UF,4V,20%,X5R,60A',
 VOLTAGE='4V',
 PRIM_FILE='./archive_libs/discrete/cap_a/chips/chips.prt';

PART_NAME
 C8T11 'CAP_A_0603V-47UF,4V,20%,X5R,60A':
 GROUP='PWR_MLCC_CAP';

SECTION_NUMBER 1
 '@BASEBOARD_FAB2_LIB.BASEBOARD_FAB2(SCH_1):PAGE225_I204@DEV_DISCRETE.CAP_A(CHIPS)':
 C_PATH='@baseboard_fab2_lib.baseboard_fab2(sch_1):page225_i204@dev_discrete.cap~
_a(chips)',
 P_PATH='@baseboard_fab2_lib.baseboard_fab2(sch_1):page225_i204@dev_discrete.cap~
_a(chips)',
 PATH='I204',
 DRAWING='@BASEBOARD_FAB2_LIB.BASEBOARD_FAB2(SCH_1):PAGE225',
 BOM_SS='NOPOP',
 TOLERANCE='20%',
 SEC_TYPE='0603V',
 MATERIAL='X5R',
 PHYS_PAGE='225',
 XY='(4400,1725)',
 ROT='0',
 VER='1',
 VALUE='47UF',
 PACK_TYPE='0603V',
 PART_NUMBER='602433-106',
 LOCATION='C8T11',
 GROUP='PWR_MLCC_CAP',
 SEC='1',
 CDS_LIB='dev_discrete',
 CDS_PART_NAME='CAP_A_0603V-47UF,4V,20%,X5R,60A',
 VOLTAGE='4V',
 PRIM_FILE='./archive_libs/discrete/cap_a/chips/chips.prt';

PART_NAME
 C8U1 'CAP_0805-100UF,4V,20%,X5R,6024A':
 GROUP='PWR_MLCC_CAP',
 ROOM='VDDQ_ABC_PWR_VR';

SECTION_NUMBER 1
 '@BASEBOARD_FAB2_LIB.BASEBOARD_FAB2(SCH_1):PAGE225_I319@MSTR_DISCRETE.CAP(CHIPS)':
 C_PATH='@baseboard_fab2_lib.baseboard_fab2(sch_1):page225_i319@mstr_discrete.ca~
p(chips)',
 P_PATH='@baseboard_fab2_lib.baseboard_fab2(sch_1):page225_i319@mstr_discrete.ca~
p(chips)',
 PATH='I319',
 DRAWING='@BASEBOARD_FAB2_LIB.BASEBOARD_FAB2(SCH_1):PAGE225',
 NEW_PN='078.1071T.M002',
 NEW_MATERIAL='X6S',
 BOM_SS='NOPOP',
 TOLERANCE='20%',
 SEC_TYPE='0805',
 MATERIAL='X5R',
 BOM_COST='MEM_VRD_PVDDQ_CD',
 PHYS_PAGE='225',
 XY='(5000,2825)',
 ROT='0',
 VER='1',
 VALUE='100UF',
 PACK_TYPE='0805',
 PART_NUMBER='602433-112',
 LOCATION='C8U1',
 ROOM='VDDQ_ABC_PWR_VR',
 GROUP='PWR_MLCC_CAP',
 SEC='1',
 CDS_LIB='mstr_discrete',
 CDS_PART_NAME='CAP_0805-100UF,4V,20%,X5R,6024A',
 VOLTAGE='4V',
 PRIM_FILE='./archive_libs/mstr_discrete/cap/chips/chips.prt';

PART_NAME
 C8U2 'CAP_A_0603V-47UF,4V,20%,X5R,60A':
 GROUP='PWR_MLCC_CAP';

SECTION_NUMBER 1
 '@BASEBOARD_FAB2_LIB.BASEBOARD_FAB2(SCH_1):PAGE225_I291@DEV_DISCRETE.CAP_A(CHIPS)':
 C_PATH='@baseboard_fab2_lib.baseboard_fab2(sch_1):page225_i291@dev_discrete.cap~
_a(chips)',
 P_PATH='@baseboard_fab2_lib.baseboard_fab2(sch_1):page225_i291@dev_discrete.cap~
_a(chips)',
 PATH='I291',
 DRAWING='@BASEBOARD_FAB2_LIB.BASEBOARD_FAB2(SCH_1):PAGE225',
 BOM_SS='E15431-004',
 TOLERANCE='20%',
 SEC_TYPE='0603V',
 MATERIAL='X5R',
 PHYS_PAGE='225',
 XY='(-1950,-450)',
 ROT='0',
 VER='1',
 VALUE='47UF',
 PACK_TYPE='0603V',
 PART_NUMBER='602433-106',
 LOCATION='C8U2',
 GROUP='PWR_MLCC_CAP',
 SEC='1',
 CDS_LIB='dev_discrete',
 CDS_PART_NAME='CAP_A_0603V-47UF,4V,20%,X5R,60A',
 VOLTAGE='4V',
 PRIM_FILE='./archive_libs/discrete/cap_a/chips/chips.prt';

PART_NAME
 C8U3 'CAP_A_0603V-47UF,4V,20%,X5R,60A':
 GROUP='PWR_MLCC_CAP';

SECTION_NUMBER 1
 '@BASEBOARD_FAB2_LIB.BASEBOARD_FAB2(SCH_1):PAGE225_I294@DEV_DISCRETE.CAP_A(CHIPS)':
 C_PATH='@baseboard_fab2_lib.baseboard_fab2(sch_1):page225_i294@dev_discrete.cap~
_a(chips)',
 P_PATH='@baseboard_fab2_lib.baseboard_fab2(sch_1):page225_i294@dev_discrete.cap~
_a(chips)',
 PATH='I294',
 DRAWING='@BASEBOARD_FAB2_LIB.BASEBOARD_FAB2(SCH_1):PAGE225',
 BOM_SS='E15431-004',
 TOLERANCE='20%',
 SEC_TYPE='0603V',
 MATERIAL='X5R',
 PHYS_PAGE='225',
 XY='(-1100,-450)',
 ROT='0',
 VER='1',
 VALUE='47UF',
 PACK_TYPE='0603V',
 PART_NUMBER='602433-106',
 LOCATION='C8U3',
 GROUP='PWR_MLCC_CAP',
 SEC='1',
 CDS_LIB='dev_discrete',
 CDS_PART_NAME='CAP_A_0603V-47UF,4V,20%,X5R,60A',
 VOLTAGE='4V',
 PRIM_FILE='./archive_libs/discrete/cap_a/chips/chips.prt';

PART_NAME
 C8U4 'CAP_A_0603V-47UF,4V,20%,X5R,60A':
 GROUP='PWR_MLCC_CAP';

SECTION_NUMBER 1
 '@BASEBOARD_FAB2_LIB.BASEBOARD_FAB2(SCH_1):PAGE225_I305@DEV_DISCRETE.CAP_A(CHIPS)':
 C_PATH='@baseboard_fab2_lib.baseboard_fab2(sch_1):page225_i305@dev_discrete.cap~
_a(chips)',
 P_PATH='@baseboard_fab2_lib.baseboard_fab2(sch_1):page225_i305@dev_discrete.cap~
_a(chips)',
 PATH='I305',
 DRAWING='@BASEBOARD_FAB2_LIB.BASEBOARD_FAB2(SCH_1):PAGE225',
 BOM_SS='E15431-004',
 TOLERANCE='20%',
 SEC_TYPE='0603V',
 MATERIAL='X5R',
 PHYS_PAGE='225',
 XY='(2125,-450)',
 ROT='0',
 VER='1',
 VALUE='47UF',
 PACK_TYPE='0603V',
 PART_NUMBER='602433-106',
 LOCATION='C8U4',
 GROUP='PWR_MLCC_CAP',
 SEC='1',
 CDS_LIB='dev_discrete',
 CDS_PART_NAME='CAP_A_0603V-47UF,4V,20%,X5R,60A',
 VOLTAGE='4V',
 PRIM_FILE='./archive_libs/discrete/cap_a/chips/chips.prt';

PART_NAME
 C8U5 'CAP_A_0603V-47UF,4V,20%,X5R,60A':
 GROUP='PWR_MLCC_CAP';

SECTION_NUMBER 1
 '@BASEBOARD_FAB2_LIB.BASEBOARD_FAB2(SCH_1):PAGE225_I302@DEV_DISCRETE.CAP_A(CHIPS)':
 C_PATH='@baseboard_fab2_lib.baseboard_fab2(sch_1):page225_i302@dev_discrete.cap~
_a(chips)',
 P_PATH='@baseboard_fab2_lib.baseboard_fab2(sch_1):page225_i302@dev_discrete.cap~
_a(chips)',
 PATH='I302',
 DRAWING='@BASEBOARD_FAB2_LIB.BASEBOARD_FAB2(SCH_1):PAGE225',
 BOM_SS='E15431-004',
 TOLERANCE='20%',
 SEC_TYPE='0603V',
 MATERIAL='X5R',
 PHYS_PAGE='225',
 XY='(1250,-450)',
 ROT='0',
 VER='1',
 VALUE='47UF',
 PACK_TYPE='0603V',
 PART_NUMBER='602433-106',
 LOCATION='C8U5',
 GROUP='PWR_MLCC_CAP',
 SEC='1',
 CDS_LIB='dev_discrete',
 CDS_PART_NAME='CAP_A_0603V-47UF,4V,20%,X5R,60A',
 VOLTAGE='4V',
 PRIM_FILE='./archive_libs/discrete/cap_a/chips/chips.prt';

PART_NAME
 C8U6 'CAP_A_0603V-47UF,4V,20%,X5R,60A':
 GROUP='PWR_MLCC_CAP';

SECTION_NUMBER 1
 '@BASEBOARD_FAB2_LIB.BASEBOARD_FAB2(SCH_1):PAGE225_I298@DEV_DISCRETE.CAP_A(CHIPS)':
 C_PATH='@baseboard_fab2_lib.baseboard_fab2(sch_1):page225_i298@dev_discrete.cap~
_a(chips)',
 P_PATH='@baseboard_fab2_lib.baseboard_fab2(sch_1):page225_i298@dev_discrete.cap~
_a(chips)',
 PATH='I298',
 DRAWING='@BASEBOARD_FAB2_LIB.BASEBOARD_FAB2(SCH_1):PAGE225',
 BOM_SS='E15431-004',
 TOLERANCE='20%',
 SEC_TYPE='0603V',
 MATERIAL='X5R',
 PHYS_PAGE='225',
 XY='(100,-450)',
 ROT='0',
 VER='1',
 VALUE='47UF',
 PACK_TYPE='0603V',
 PART_NUMBER='602433-106',
 LOCATION='C8U6',
 GROUP='PWR_MLCC_CAP',
 SEC='1',
 CDS_LIB='dev_discrete',
 CDS_PART_NAME='CAP_A_0603V-47UF,4V,20%,X5R,60A',
 VOLTAGE='4V',
 PRIM_FILE='./archive_libs/discrete/cap_a/chips/chips.prt';

PART_NAME
 C8U7 'CAP_A_0603V-47UF,4V,20%,X5R,60A':
 GROUP='PWR_MLCC_CAP';

SECTION_NUMBER 1
 '@BASEBOARD_FAB2_LIB.BASEBOARD_FAB2(SCH_1):PAGE225_I290@DEV_DISCRETE.CAP_A(CHIPS)':
 C_PATH='@baseboard_fab2_lib.baseboard_fab2(sch_1):page225_i290@dev_discrete.cap~
_a(chips)',
 P_PATH='@baseboard_fab2_lib.baseboard_fab2(sch_1):page225_i290@dev_discrete.cap~
_a(chips)',
 PATH='I290',
 DRAWING='@BASEBOARD_FAB2_LIB.BASEBOARD_FAB2(SCH_1):PAGE225',
 BOM_SS='E15431-004',
 TOLERANCE='20%',
 SEC_TYPE='0603V',
 MATERIAL='X5R',
 PHYS_PAGE='225',
 XY='(-2250,-450)',
 ROT='0',
 VER='1',
 VALUE='47UF',
 PACK_TYPE='0603V',
 PART_NUMBER='602433-106',
 LOCATION='C8U7',
 GROUP='PWR_MLCC_CAP',
 SEC='1',
 CDS_LIB='dev_discrete',
 CDS_PART_NAME='CAP_A_0603V-47UF,4V,20%,X5R,60A',
 VOLTAGE='4V',
 PRIM_FILE='./archive_libs/discrete/cap_a/chips/chips.prt';

PART_NAME
 C8U8 'CAP_0805-100UF,4V,20%,X5R,6024A':
 GROUP='PWR_MLCC_CAP',
 ROOM='VDDQ_ABC_PWR_VR';

SECTION_NUMBER 1
 '@BASEBOARD_FAB2_LIB.BASEBOARD_FAB2(SCH_1):PAGE225_I320@MSTR_DISCRETE.CAP(CHIPS)':
 C_PATH='@baseboard_fab2_lib.baseboard_fab2(sch_1):page225_i320@mstr_discrete.ca~
p(chips)',
 P_PATH='@baseboard_fab2_lib.baseboard_fab2(sch_1):page225_i320@mstr_discrete.ca~
p(chips)',
 PATH='I320',
 DRAWING='@BASEBOARD_FAB2_LIB.BASEBOARD_FAB2(SCH_1):PAGE225',
 NEW_PN='078.1071T.M002',
 NEW_MATERIAL='X6S',
 BOM_SS='NOPOP',
 TOLERANCE='20%',
 SEC_TYPE='0805',
 MATERIAL='X5R',
 BOM_COST='MEM_VRD_PVDDQ_CD',
 PHYS_PAGE='225',
 XY='(4600,2825)',
 ROT='0',
 VER='1',
 VALUE='100UF',
 PACK_TYPE='0805',
 PART_NUMBER='602433-112',
 LOCATION='C8U8',
 ROOM='VDDQ_ABC_PWR_VR',
 GROUP='PWR_MLCC_CAP',
 SEC='1',
 CDS_LIB='mstr_discrete',
 CDS_PART_NAME='CAP_0805-100UF,4V,20%,X5R,6024A',
 VOLTAGE='4V',
 PRIM_FILE='./archive_libs/mstr_discrete/cap/chips/chips.prt';

PART_NAME
 C8U9 'CAP_A_0603V-47UF,4V,20%,X5R,60A':
 GROUP='PWR_MLCC_CAP';

SECTION_NUMBER 1
 '@BASEBOARD_FAB2_LIB.BASEBOARD_FAB2(SCH_1):PAGE225_I203@DEV_DISCRETE.CAP_A(CHIPS)':
 C_PATH='@baseboard_fab2_lib.baseboard_fab2(sch_1):page225_i203@dev_discrete.cap~
_a(chips)',
 P_PATH='@baseboard_fab2_lib.baseboard_fab2(sch_1):page225_i203@dev_discrete.cap~
_a(chips)',
 PATH='I203',
 DRAWING='@BASEBOARD_FAB2_LIB.BASEBOARD_FAB2(SCH_1):PAGE225',
 BOM_SS='NOPOP',
 TOLERANCE='20%',
 SEC_TYPE='0603V',
 MATERIAL='X5R',
 PHYS_PAGE='225',
 XY='(4000,1725)',
 ROT='0',
 VER='1',
 VALUE='47UF',
 PACK_TYPE='0603V',
 PART_NUMBER='602433-106',
 LOCATION='C8U9',
 GROUP='PWR_MLCC_CAP',
 SEC='1',
 CDS_LIB='dev_discrete',
 CDS_PART_NAME='CAP_A_0603V-47UF,4V,20%,X5R,60A',
 VOLTAGE='4V',
 PRIM_FILE='./archive_libs/discrete/cap_a/chips/chips.prt';

PART_NAME
 C8U10 'CAP_0805-100UF,4V,20%,X5R,6024A':
 GROUP='PWR_MLCC_CAP',
 ROOM='VDDQ_ABC_PWR_VR';

SECTION_NUMBER 1
 '@BASEBOARD_FAB2_LIB.BASEBOARD_FAB2(SCH_1):PAGE229_I42@MSTR_DISCRETE.CAP(CHIPS)':
 C_PATH='@baseboard_fab2_lib.baseboard_fab2(sch_1):page229_i42@mstr_discrete.cap~
(chips)',
 P_PATH='@baseboard_fab2_lib.baseboard_fab2(sch_1):page229_i42@mstr_discrete.cap~
(chips)',
 PATH='I42',
 DRAWING='@BASEBOARD_FAB2_LIB.BASEBOARD_FAB2(SCH_1):PAGE229',
 NEW_PN='078.1071T.M002',
 NEW_MATERIAL='X6S',
 TOLERANCE='20%',
 SEC_TYPE='0805',
 MATERIAL='X5R',
 BOM_COST='MEM_VRD_PVDDQ_CD',
 PHYS_PAGE='229',
 XY='(4150,3200)',
 ROT='0',
 VER='1',
 VALUE='100UF',
 PACK_TYPE='0805',
 PART_NUMBER='602433-112',
 LOCATION='C8U10',
 ROOM='VDDQ_ABC_PWR_VR',
 GROUP='PWR_MLCC_CAP',
 SEC='1',
 CDS_LIB='mstr_discrete',
 CDS_PART_NAME='CAP_0805-100UF,4V,20%,X5R,6024A',
 VOLTAGE='4V',
 PRIM_FILE='./archive_libs/mstr_discrete/cap/chips/chips.prt';

PART_NAME
 C8U11 'CAP_0805-100UF,4V,20%,X5R,6024A':
 GROUP='PWR_MLCC_CAP',
 ROOM='VDDQ_ABC_PWR_VR';

SECTION_NUMBER 1
 '@BASEBOARD_FAB2_LIB.BASEBOARD_FAB2(SCH_1):PAGE225_I307@MSTR_DISCRETE.CAP(CHIPS)':
 C_PATH='@baseboard_fab2_lib.baseboard_fab2(sch_1):page225_i307@mstr_discrete.ca~
p(chips)',
 P_PATH='@baseboard_fab2_lib.baseboard_fab2(sch_1):page225_i307@mstr_discrete.ca~
p(chips)',
 PATH='I307',
 DRAWING='@BASEBOARD_FAB2_LIB.BASEBOARD_FAB2(SCH_1):PAGE225',
 NEW_PN='078.1071T.M002',
 NEW_MATERIAL='X6S',
 BOM_SS='NOPOP',
 TOLERANCE='20%',
 SEC_TYPE='0805',
 MATERIAL='X5R',
 BOM_COST='MEM_VRD_PVDDQ_CD',
 PHYS_PAGE='225',
 XY='(3850,2825)',
 ROT='0',
 VER='1',
 VALUE='100UF',
 PACK_TYPE='0805',
 PART_NUMBER='602433-112',
 LOCATION='C8U11',
 ROOM='VDDQ_ABC_PWR_VR',
 GROUP='PWR_MLCC_CAP',
 SEC='1',
 CDS_LIB='mstr_discrete',
 CDS_PART_NAME='CAP_0805-100UF,4V,20%,X5R,6024A',
 VOLTAGE='4V',
 PRIM_FILE='./archive_libs/mstr_discrete/cap/chips/chips.prt';

PART_NAME
 C8U12 'CAP_0805-100UF,4V,20%,X5R,6024A':
 GROUP='PWR_MLCC_CAP',
 ROOM='VDDQ_ABC_PWR_VR';

SECTION_NUMBER 1
 '@BASEBOARD_FAB2_LIB.BASEBOARD_FAB2(SCH_1):PAGE225_I310@MSTR_DISCRETE.CAP(CHIPS)':
 C_PATH='@baseboard_fab2_lib.baseboard_fab2(sch_1):page225_i310@mstr_discrete.ca~
p(chips)',
 P_PATH='@baseboard_fab2_lib.baseboard_fab2(sch_1):page225_i310@mstr_discrete.ca~
p(chips)',
 PATH='I310',
 DRAWING='@BASEBOARD_FAB2_LIB.BASEBOARD_FAB2(SCH_1):PAGE225',
 NEW_PN='078.1071T.M002',
 NEW_MATERIAL='X6S',
 BOM_SS='NOPOP',
 TOLERANCE='20%',
 SEC_TYPE='0805',
 MATERIAL='X5R',
 BOM_COST='MEM_VRD_PVDDQ_CD',
 PHYS_PAGE='225',
 XY='(4250,2825)',
 ROT='0',
 VER='1',
 VALUE='100UF',
 PACK_TYPE='0805',
 PART_NUMBER='602433-112',
 LOCATION='C8U12',
 ROOM='VDDQ_ABC_PWR_VR',
 GROUP='PWR_MLCC_CAP',
 SEC='1',
 CDS_LIB='mstr_discrete',
 CDS_PART_NAME='CAP_0805-100UF,4V,20%,X5R,6024A',
 VOLTAGE='4V',
 PRIM_FILE='./archive_libs/mstr_discrete/cap/chips/chips.prt';

PART_NAME
 C8U13 'CAP_A_0603V-47UF,4V,20%,X5R,60A':
 GROUP='PWR_MLCC_CAP';

SECTION_NUMBER 1
 '@BASEBOARD_FAB2_LIB.BASEBOARD_FAB2(SCH_1):PAGE225_I199@DEV_DISCRETE.CAP_A(CHIPS)':
 C_PATH='@baseboard_fab2_lib.baseboard_fab2(sch_1):page225_i199@dev_discrete.cap~
_a(chips)',
 P_PATH='@baseboard_fab2_lib.baseboard_fab2(sch_1):page225_i199@dev_discrete.cap~
_a(chips)',
 PATH='I199',
 DRAWING='@BASEBOARD_FAB2_LIB.BASEBOARD_FAB2(SCH_1):PAGE225',
 BOM_SS='NOPOP',
 TOLERANCE='20%',
 SEC_TYPE='0603V',
 MATERIAL='X5R',
 PHYS_PAGE='225',
 XY='(2550,1725)',
 ROT='0',
 VER='1',
 VALUE='47UF',
 PACK_TYPE='0603V',
 PART_NUMBER='602433-106',
 LOCATION='C8U13',
 GROUP='PWR_MLCC_CAP',
 SEC='1',
 CDS_LIB='dev_discrete',
 CDS_PART_NAME='CAP_A_0603V-47UF,4V,20%,X5R,60A',
 VOLTAGE='4V',
 PRIM_FILE='./archive_libs/discrete/cap_a/chips/chips.prt';

PART_NAME
 C8W1 'SC1U16V3KX-2GP_SMD-BCG-SC1U16VA':;

SECTION_NUMBER 1
 '@BASEBOARD_FAB2_LIB.BASEBOARD_FAB2(SCH_1):PAGE249_I52@W_HDL.SC1U16V3KX-2GP(CHIPS)':
 C_PATH='@baseboard_fab2_lib.baseboard_fab2(sch_1):page249_i52@w_hdl.\sc1u16v3kx~
-2gp\(chips)',
 P_PATH='@baseboard_fab2_lib.baseboard_fab2(sch_1):page249_i52@w_hdl.\sc1u16v3kx~
-2gp\(chips)',
 PATH='I52',
 DRAWING='@BASEBOARD_FAB2_LIB.BASEBOARD_FAB2(SCH_1):PAGE249',
 TYPE='X5R',
 PACK_SIZE='0603',
 RATED='16V',
 ATTRIBUTE='1UF',
 TOLERANCE='10%',
 PHYS_PAGE='249',
 XY='(-6625,2150)',
 ROT='1',
 VER='1',
 VALUE='SC1U16V3KX-2GP',
 PACK_TYPE='SMD-BCG',
 PART_NUMBER='78.10521.5BL',
 LOCATION='C8W1',
 CDS_LIB='w_hdl',
 CDS_PART_NAME='SC1U16V3KX-2GP_SMD-BCG-SC1U16VA',
 PRIM_FILE='C:/<user>/w_hdl/sc1u16v3kx#2d2gp/chips/chips.prt';

PART_NAME
 C8W2 'CAP_A_0402V-0.1UF,16V,10%,X7R,A':
 ROOM='VDDQ_KLM_PWR_VR';

SECTION_NUMBER 1
 '@BASEBOARD_FAB2_LIB.BASEBOARD_FAB2(SCH_1):PAGE249_I37@DEV_DISCRETE.CAP_A(CHIPS)':
 C_PATH='@baseboard_fab2_lib.baseboard_fab2(sch_1):page249_i37@dev_discrete.cap_~
a(chips)',
 P_PATH='@baseboard_fab2_lib.baseboard_fab2(sch_1):page249_i37@dev_discrete.cap_~
a(chips)',
 PATH='I37',
 DRAWING='@BASEBOARD_FAB2_LIB.BASEBOARD_FAB2(SCH_1):PAGE249',
 TOLERANCE='10%',
 SEC_TYPE='0402V',
 MATERIAL='X7R',
 PHYS_PAGE='249',
 XY='(-2050,3000)',
 ROT='0',
 VER='1',
 VALUE='0.1UF',
 PACK_TYPE='0402V',
 PART_NUMBER='A36096-030',
 LOCATION='C8W2',
 ROOM='VDDQ_KLM_PWR_VR',
 SEC='1',
 CDS_LIB='dev_discrete',
 CDS_PART_NAME='CAP_A_0402V-0.1UF,16V,10%,X7R,A',
 VOLTAGE='16V',
 PRIM_FILE='./archive_libs/discrete/cap_a/chips/chips.prt';

PART_NAME
 C8W3 'CAP_0805-100UF,4V,20%,X5R,6024A':
 GROUP='PWR_MLCC_CAP',
 ROOM='VDDQ_ABC_PWR_VR';

SECTION_NUMBER 1
 '@BASEBOARD_FAB2_LIB.BASEBOARD_FAB2(SCH_1):PAGE42_I211@MSTR_DISCRETE.CAP(CHIPS)':
 C_PATH='@baseboard_fab2_lib.baseboard_fab2(sch_1):page42_i211@mstr_discrete.cap~
(chips)',
 P_PATH='@baseboard_fab2_lib.baseboard_fab2(sch_1):page42_i211@mstr_discrete.cap~
(chips)',
 PATH='I211',
 DRAWING='@BASEBOARD_FAB2_LIB.BASEBOARD_FAB2(SCH_1):PAGE42',
 NEW_PN='078.1071T.M002',
 NEW_MATERIAL='X6S',
 TOLERANCE='20%',
 SEC_TYPE='0805',
 MATERIAL='X5R',
 BOM_COST='MEM_VRD_PVDDQ_CD',
 PHYS_PAGE='42',
 XY='(-1150,1250)',
 ROT='0',
 VER='1',
 VALUE='100UF',
 PACK_TYPE='0805',
 PART_NUMBER='602433-112',
 LOCATION='C8W3',
 ROOM='VDDQ_ABC_PWR_VR',
 GROUP='PWR_MLCC_CAP',
 SEC='1',
 CDS_LIB='mstr_discrete',
 CDS_PART_NAME='CAP_0805-100UF,4V,20%,X5R,6024A',
 VOLTAGE='4V',
 PRIM_FILE='./archive_libs/mstr_discrete/cap/chips/chips.prt';

PART_NAME
 C8W4 'CAP_0805-100UF,4V,20%,X5R,6024A':
 GROUP='PWR_MLCC_CAP',
 ROOM='VDDQ_ABC_PWR_VR';

SECTION_NUMBER 1
 '@BASEBOARD_FAB2_LIB.BASEBOARD_FAB2(SCH_1):PAGE76_I245@MSTR_DISCRETE.CAP(CHIPS)':
 C_PATH='@baseboard_fab2_lib.baseboard_fab2(sch_1):page76_i245@mstr_discrete.cap~
(chips)',
 P_PATH='@baseboard_fab2_lib.baseboard_fab2(sch_1):page76_i245@mstr_discrete.cap~
(chips)',
 PATH='I245',
 DRAWING='@BASEBOARD_FAB2_LIB.BASEBOARD_FAB2(SCH_1):PAGE76',
 NEW_PN='078.1071T.M002',
 NEW_MATERIAL='X6S',
 TOLERANCE='20%',
 SEC_TYPE='0805',
 MATERIAL='X5R',
 BOM_COST='MEM_VRD_PVDDQ_CD',
 PHYS_PAGE='76',
 XY='(-1200,1300)',
 ROT='0',
 VER='1',
 VALUE='100UF',
 PACK_TYPE='0805',
 PART_NUMBER='602433-112',
 LOCATION='C8W4',
 ROOM='VDDQ_ABC_PWR_VR',
 GROUP='PWR_MLCC_CAP',
 SEC='1',
 CDS_LIB='mstr_discrete',
 CDS_PART_NAME='CAP_0805-100UF,4V,20%,X5R,6024A',
 VOLTAGE='4V',
 PRIM_FILE='./archive_libs/mstr_discrete/cap/chips/chips.prt';

PART_NAME
 C8W5 'CAP_A_0402V-1.0UF,6.3V,10%,X6SA':
 ROOM='DEBUG';

SECTION_NUMBER 1
 '@BASEBOARD_FAB2_LIB.BASEBOARD_FAB2(SCH_1):PAGE245_I74@DEV_DISCRETE.CAP_A(CHIPS)':
 C_PATH='@baseboard_fab2_lib.baseboard_fab2(sch_1):page245_i74@dev_discrete.cap_~
a(chips)',
 P_PATH='@baseboard_fab2_lib.baseboard_fab2(sch_1):page245_i74@dev_discrete.cap_~
a(chips)',
 PATH='I74',
 DRAWING='@BASEBOARD_FAB2_LIB.BASEBOARD_FAB2(SCH_1):PAGE245',
 TOLERANCE='10%',
 MATERIAL='X6S',
 BOM_COST='DEBUG',
 PHYS_PAGE='245',
 XY='(-5850,825)',
 ROT='2',
 VER='1',
 VALUE='1.0UF',
 PACK_TYPE='0402V',
 PART_NUMBER='D97712-004',
 LOCATION='C8W5',
 ROOM='DEBUG',
 CDS_LIB='dev_discrete',
 CDS_PART_NAME='CAP_A_0402V-1.0UF,6.3V,10%,X6SA',
 VOLTAGE='6.3V',
 PRIM_FILE='./archive_libs/discrete/cap_a/chips/chips.prt';

PART_NAME
 C8W6 'CAP_A_0402V-0.01UF,25V,10%,X7RA':
 ROOM='DEBUG';

SECTION_NUMBER 1
 '@BASEBOARD_FAB2_LIB.BASEBOARD_FAB2(SCH_1):PAGE245_I71@DEV_DISCRETE.CAP_A(CHIPS)':
 C_PATH='@baseboard_fab2_lib.baseboard_fab2(sch_1):page245_i71@dev_discrete.cap_~
a(chips)',
 P_PATH='@baseboard_fab2_lib.baseboard_fab2(sch_1):page245_i71@dev_discrete.cap_~
a(chips)',
 PATH='I71',
 DRAWING='@BASEBOARD_FAB2_LIB.BASEBOARD_FAB2(SCH_1):PAGE245',
 TOLERANCE='10%',
 SEC_TYPE='0402V',
 MATERIAL='X7R',
 BOM_COST='DEBUG',
 PHYS_PAGE='245',
 XY='(-5450,825)',
 ROT='2',
 VER='1',
 VALUE='0.01UF',
 PACK_TYPE='0402V',
 PART_NUMBER='A36096-045',
 LOCATION='C8W6',
 ROOM='DEBUG',
 SEC='1',
 CDS_LIB='dev_discrete',
 CDS_PART_NAME='CAP_A_0402V-0.01UF,25V,10%,X7RA',
 VOLTAGE='25V',
 PRIM_FILE='./archive_libs/discrete/cap_a/chips/chips.prt';

PART_NAME
 C9A1 'CAP_A_0402V-0.1UF,16V,10%,X7R,A':
 ROOM='BMC_DEBUG_HEADER';

SECTION_NUMBER 1
 '@BASEBOARD_FAB2_LIB.BASEBOARD_FAB2(SCH_1):PAGE155_I127@DEV_DISCRETE.CAP_A(CHIPS)':
 C_PATH='@baseboard_fab2_lib.baseboard_fab2(sch_1):page155_i127@dev_discrete.cap~
_a(chips)',
 P_PATH='@baseboard_fab2_lib.baseboard_fab2(sch_1):page155_i127@dev_discrete.cap~
_a(chips)',
 PATH='I127',
 DRAWING='@BASEBOARD_FAB2_LIB.BASEBOARD_FAB2(SCH_1):PAGE155',
 TOLERANCE='10%',
 MATERIAL='X7R',
 BOM_COST='DEBUG',
 PHYS_PAGE='155',
 XY='(-4100,1050)',
 ROT='0',
 VER='1',
 VALUE='0.1UF',
 PACK_TYPE='0402V',
 PART_NUMBER='A36096-030',
 LOCATION='C9A1',
 ROOM='BMC_DEBUG_HEADER',
 CDS_LIB='dev_discrete',
 CDS_PART_NAME='CAP_A_0402V-0.1UF,16V,10%,X7R,A',
 VOLTAGE='16V',
 PRIM_FILE='./archive_libs/discrete/cap_a/chips/chips.prt';

PART_NAME
 C9A2 'CAP_A_0402V-0.1UF,16V,10%,X7R,A':
 ROOM='DEBUG';

SECTION_NUMBER 1
 '@BASEBOARD_FAB2_LIB.BASEBOARD_FAB2(SCH_1):PAGE111_I10@DEV_DISCRETE.CAP_A(CHIPS)':
 C_PATH='@baseboard_fab2_lib.baseboard_fab2(sch_1):page111_i10@dev_discrete.cap_~
a(chips)',
 P_PATH='@baseboard_fab2_lib.baseboard_fab2(sch_1):page111_i10@dev_discrete.cap_~
a(chips)',
 PATH='I10',
 DRAWING='@BASEBOARD_FAB2_LIB.BASEBOARD_FAB2(SCH_1):PAGE111',
 TOLERANCE='10%',
 SEC_TYPE='0402V',
 MATERIAL='X7R',
 BOM_COST='DEBUG',
 PHYS_PAGE='111',
 XY='(2750,1900)',
 ROT='1',
 VER='1',
 VALUE='0.1UF',
 PACK_TYPE='0402V',
 PART_NUMBER='A36096-030',
 LOCATION='C9A2',
 ROOM='DEBUG',
 SEC='1',
 CDS_LIB='dev_discrete',
 CDS_PART_NAME='CAP_A_0402V-0.1UF,16V,10%,X7R,A',
 VOLTAGE='16V',
 PRIM_FILE='./archive_libs/discrete/cap_a/chips/chips.prt';

PART_NAME
 C9A3 'CAP_A_0402V-0.1UF,16V,10%,X7R,A':
 ROOM='MIO_CHASSIS';

SECTION_NUMBER 1
 '@BASEBOARD_FAB2_LIB.BASEBOARD_FAB2(SCH_1):PAGE175_I40@DEV_DISCRETE.CAP_A(CHIPS)':
 C_PATH='@baseboard_fab2_lib.baseboard_fab2(sch_1):page175_i40@dev_discrete.cap_~
a(chips)',
 P_PATH='@baseboard_fab2_lib.baseboard_fab2(sch_1):page175_i40@dev_discrete.cap_~
a(chips)',
 PATH='I40',
 DRAWING='@BASEBOARD_FAB2_LIB.BASEBOARD_FAB2(SCH_1):PAGE175',
 TOLERANCE='10%',
 SEC_TYPE='0402V',
 MATERIAL='X7R',
 BOM_COST='MIO_CHASSIS',
 PHYS_PAGE='175',
 XY='(-575,3500)',
 ROT='0',
 VER='1',
 VALUE='0.1UF',
 PACK_TYPE='0402V',
 PART_NUMBER='A36096-030',
 LOCATION='C9A3',
 ROOM='MIO_CHASSIS',
 SEC='1',
 CDS_LIB='dev_discrete',
 CDS_PART_NAME='CAP_A_0402V-0.1UF,16V,10%,X7R,A',
 VOLTAGE='16V',
 PRIM_FILE='./archive_libs/discrete/cap_a/chips/chips.prt';

PART_NAME
 C9A4 'CAP_A_0402V-0.1UF,16V,10%,X7R,A':
 ROOM='DEBUG';

SECTION_NUMBER 1
 '@BASEBOARD_FAB2_LIB.BASEBOARD_FAB2(SCH_1):PAGE111_I59@DEV_DISCRETE.CAP_A(CHIPS)':
 C_PATH='@baseboard_fab2_lib.baseboard_fab2(sch_1):page111_i59@dev_discrete.cap_~
a(chips)',
 P_PATH='@baseboard_fab2_lib.baseboard_fab2(sch_1):page111_i59@dev_discrete.cap_~
a(chips)',
 PATH='I59',
 DRAWING='@BASEBOARD_FAB2_LIB.BASEBOARD_FAB2(SCH_1):PAGE111',
 TOLERANCE='10%',
 SEC_TYPE='0402V',
 MATERIAL='X7R',
 BOM_COST='DEBUG',
 PHYS_PAGE='111',
 XY='(-1400,875)',
 ROT='1',
 VER='1',
 VALUE='0.1UF',
 PACK_TYPE='0402V',
 PART_NUMBER='A36096-030',
 LOCATION='C9A4',
 ROOM='DEBUG',
 SEC='1',
 CDS_LIB='dev_discrete',
 CDS_PART_NAME='CAP_A_0402V-0.1UF,16V,10%,X7R,A',
 VOLTAGE='16V',
 PRIM_FILE='./archive_libs/discrete/cap_a/chips/chips.prt';

PART_NAME
 C9A5 'CAP_A_0402V-0.1UF,16V,10%,X7R,A':
 ROOM='DEBUG';

SECTION_NUMBER 1
 '@BASEBOARD_FAB2_LIB.BASEBOARD_FAB2(SCH_1):PAGE111_I12@DEV_DISCRETE.CAP_A(CHIPS)':
 C_PATH='@baseboard_fab2_lib.baseboard_fab2(sch_1):page111_i12@dev_discrete.cap_~
a(chips)',
 P_PATH='@baseboard_fab2_lib.baseboard_fab2(sch_1):page111_i12@dev_discrete.cap_~
a(chips)',
 PATH='I12',
 DRAWING='@BASEBOARD_FAB2_LIB.BASEBOARD_FAB2(SCH_1):PAGE111',
 TOLERANCE='10%',
 SEC_TYPE='0402V',
 MATERIAL='X7R',
 BOM_COST='DEBUG',
 PHYS_PAGE='111',
 XY='(2800,1450)',
 ROT='1',
 VER='1',
 VALUE='0.1UF',
 PACK_TYPE='0402V',
 PART_NUMBER='A36096-030',
 LOCATION='C9A5',
 ROOM='DEBUG',
 SEC='1',
 CDS_LIB='dev_discrete',
 CDS_PART_NAME='CAP_A_0402V-0.1UF,16V,10%,X7R,A',
 VOLTAGE='16V',
 PRIM_FILE='./archive_libs/discrete/cap_a/chips/chips.prt';

PART_NAME
 C9A6 'CAP_A_0402V-1.0UF,6.3V,10%,X6SA':
 ROOM='DEBUG';

SECTION_NUMBER 1
 '@BASEBOARD_FAB2_LIB.BASEBOARD_FAB2(SCH_1):PAGE111_I25@DEV_DISCRETE.CAP_A(CHIPS)':
 C_PATH='@baseboard_fab2_lib.baseboard_fab2(sch_1):page111_i25@dev_discrete.cap_~
a(chips)',
 P_PATH='@baseboard_fab2_lib.baseboard_fab2(sch_1):page111_i25@dev_discrete.cap_~
a(chips)',
 PATH='I25',
 DRAWING='@BASEBOARD_FAB2_LIB.BASEBOARD_FAB2(SCH_1):PAGE111',
 TOLERANCE='10%',
 MATERIAL='X6S',
 BOM_COST='DEBUG',
 PHYS_PAGE='111',
 XY='(750,2925)',
 ROT='2',
 VER='1',
 VALUE='1.0UF',
 PACK_TYPE='0402V',
 PART_NUMBER='D97712-004',
 LOCATION='C9A6',
 ROOM='DEBUG',
 CDS_LIB='dev_discrete',
 CDS_PART_NAME='CAP_A_0402V-1.0UF,6.3V,10%,X6SA',
 VOLTAGE='6.3V',
 PRIM_FILE='./archive_libs/discrete/cap_a/chips/chips.prt';

PART_NAME
 C9B1 'CAP_0805-10UF,16V,10%,X6S,C953A':
 ROOM='ST_SATA';

SECTION_NUMBER 1
 '@BASEBOARD_FAB2_LIB.BASEBOARD_FAB2(SCH_1):PAGE172_I39@MSTR_DISCRETE.CAP(CHIPS)':
 C_PATH='@baseboard_fab2_lib.baseboard_fab2(sch_1):page172_i39@mstr_discrete.cap~
(chips)',
 P_PATH='@baseboard_fab2_lib.baseboard_fab2(sch_1):page172_i39@mstr_discrete.cap~
(chips)',
 PATH='I39',
 DRAWING='@BASEBOARD_FAB2_LIB.BASEBOARD_FAB2(SCH_1):PAGE172',
 TOLERANCE='10%',
 SEC_TYPE='0805',
 MATERIAL='X6S',
 PHYS_PAGE='172',
 XY='(-1050,250)',
 ROT='0',
 VER='1',
 VALUE='10UF',
 PACK_TYPE='0805',
 PART_NUMBER='C95333-007',
 LOCATION='C9B1',
 ROOM='ST_SATA',
 SEC='1',
 CDS_LIB='mstr_discrete',
 CDS_PART_NAME='CAP_0805-10UF,16V,10%,X6S,C953A',
 VOLTAGE='16V',
 PRIM_FILE='./archive_libs/mstr_discrete/cap/chips/chips.prt';

PART_NAME
 C9B2 'CAP_0805-10UF,16V,10%,X6S,C953A':
 ROOM='ST_SATA';

SECTION_NUMBER 1
 '@BASEBOARD_FAB2_LIB.BASEBOARD_FAB2(SCH_1):PAGE172_I36@MSTR_DISCRETE.CAP(CHIPS)':
 C_PATH='@baseboard_fab2_lib.baseboard_fab2(sch_1):page172_i36@mstr_discrete.cap~
(chips)',
 P_PATH='@baseboard_fab2_lib.baseboard_fab2(sch_1):page172_i36@mstr_discrete.cap~
(chips)',
 PATH='I36',
 DRAWING='@BASEBOARD_FAB2_LIB.BASEBOARD_FAB2(SCH_1):PAGE172',
 TOLERANCE='10%',
 SEC_TYPE='0805',
 MATERIAL='X6S',
 PHYS_PAGE='172',
 XY='(-650,250)',
 ROT='0',
 VER='1',
 VALUE='10UF',
 PACK_TYPE='0805',
 PART_NUMBER='C95333-007',
 LOCATION='C9B2',
 ROOM='ST_SATA',
 SEC='1',
 CDS_LIB='mstr_discrete',
 CDS_PART_NAME='CAP_0805-10UF,16V,10%,X6S,C953A',
 VOLTAGE='16V',
 PRIM_FILE='./archive_libs/mstr_discrete/cap/chips/chips.prt';

PART_NAME
 C9B7 'CAP_A_0402V-0.1UF,16V,10%,X7R,A':
 ROOM='TEMP_SENSORS';

SECTION_NUMBER 1
 '@BASEBOARD_FAB2_LIB.BASEBOARD_FAB2(SCH_1):PAGE167_I39@DEV_DISCRETE.CAP_A(CHIPS)':
 C_PATH='@baseboard_fab2_lib.baseboard_fab2(sch_1):page167_i39@dev_discrete.cap_~
a(chips)',
 P_PATH='@baseboard_fab2_lib.baseboard_fab2(sch_1):page167_i39@dev_discrete.cap_~
a(chips)',
 PATH='I39',
 DRAWING='@BASEBOARD_FAB2_LIB.BASEBOARD_FAB2(SCH_1):PAGE167',
 TOLERANCE='10%',
 SEC_TYPE='0402V',
 MATERIAL='X7R',
 BOM_COST='SM_THERM',
 PHYS_PAGE='167',
 XY='(-7700,4350)',
 ROT='0',
 VER='1',
 VALUE='0.1UF',
 PACK_TYPE='0402V',
 PART_NUMBER='A36096-030',
 LOCATION='C9B7',
 ROOM='TEMP_SENSORS',
 SEC='1',
 CDS_LIB='dev_discrete',
 CDS_PART_NAME='CAP_A_0402V-0.1UF,16V,10%,X7R,A',
 VOLTAGE='16V',
 PRIM_FILE='./archive_libs/discrete/cap_a/chips/chips.prt';

PART_NAME
 C9B8 'CAPP_7343HLF-330UF,10V,20%,POSA':;

SECTION_NUMBER 1
 '@BASEBOARD_FAB2_LIB.BASEBOARD_FAB2(SCH_1):PAGE176_I113@MSTR_DISCRETE.CAPP(CHIPS)':
 C_PATH='@baseboard_fab2_lib.baseboard_fab2(sch_1):page176_i113@mstr_discrete.ca~
pp(chips)',
 P_PATH='@baseboard_fab2_lib.baseboard_fab2(sch_1):page176_i113@mstr_discrete.ca~
pp(chips)',
 PATH='I113',
 DRAWING='@BASEBOARD_FAB2_LIB.BASEBOARD_FAB2(SCH_1):PAGE176',
 TOLERANCE='20%',
 SEC_TYPE='7343HLF',
 MATERIAL='POSCAP',
 PHYS_PAGE='176',
 XY='(-3650,3150)',
 ROT='0',
 VER='1',
 VALUE='330UF',
 PACK_TYPE='7343HLF',
 PART_NUMBER='724613-043',
 LOCATION='C9B8',
 SEC='1',
 CDS_LIB='mstr_discrete',
 CDS_PART_NAME='CAPP_7343HLF-330UF,10V,20%,POSA',
 VOLTAGE='10V',
 PRIM_FILE='./archive_libs/mstr_discrete/capp/chips/chips.prt';

PART_NAME
 C9B9 'SC1U10V2KX-4-GP_SMD-BCG6-SC1U1A':;

SECTION_NUMBER 1
 '@BASEBOARD_FAB2_LIB.BASEBOARD_FAB2(SCH_1):PAGE186_I357@W_HDL.SC1U10V2KX-4-GP(CHIPS)':
 C_PATH='@baseboard_fab2_lib.baseboard_fab2(sch_1):page186_i357@w_hdl.\sc1u10v2k~
x-4-gp\(chips)',
 P_PATH='@baseboard_fab2_lib.baseboard_fab2(sch_1):page186_i357@w_hdl.\sc1u10v2k~
x-4-gp\(chips)',
 PATH='I357',
 DRAWING='@BASEBOARD_FAB2_LIB.BASEBOARD_FAB2(SCH_1):PAGE186',
 PACK_SIZE='0402',
 RATED='10V',
 ATTRIBUTE='1UF',
 TOLERANCE='10%',
 SEC_TYPE='SMD-BCG6',
 PHYS_PAGE='186',
 XY='(9650,3925)',
 ROT='0',
 VER='1',
 VALUE='SC1U10V2KX-4-GP',
 PACK_TYPE='SMD-BCG6',
 PART_NUMBER='78.10523.8FL',
 LOCATION='C9B9',
 SEC='1',
 CDS_LIB='w_hdl',
 CDS_PART_NAME='SC1U10V2KX-4-GP_SMD-BCG6-SC1U1A',
 PRIM_FILE='C:/<user>/w_hdl/sc1u10v2kx#2d4#2dgp/chips/chips.prt';

PART_NAME
 C9B10 'CAP_A_0402V-0.1UF,16V,10%,X7R,A':
 ROOM='IO_SLOT';

SECTION_NUMBER 1
 '@BASEBOARD_FAB2_LIB.BASEBOARD_FAB2(SCH_1):PAGE186_I345@DEV_DISCRETE.CAP_A(CHIPS)':
 C_PATH='@baseboard_fab2_lib.baseboard_fab2(sch_1):page186_i345@dev_discrete.cap~
_a(chips)',
 P_PATH='@baseboard_fab2_lib.baseboard_fab2(sch_1):page186_i345@dev_discrete.cap~
_a(chips)',
 PATH='I345',
 DRAWING='@BASEBOARD_FAB2_LIB.BASEBOARD_FAB2(SCH_1):PAGE186',
 TOLERANCE='10%',
 SEC_TYPE='0402V',
 MATERIAL='X7R',
 PHYS_PAGE='186',
 XY='(10050,3950)',
 ROT='0',
 VER='1',
 VALUE='0.1UF',
 PACK_TYPE='0402V',
 PART_NUMBER='A36096-030',
 LOCATION='C9B10',
 ROOM='IO_SLOT',
 SEC='1',
 CDS_LIB='dev_discrete',
 CDS_PART_NAME='CAP_A_0402V-0.1UF,16V,10%,X7R,A',
 VOLTAGE='16V',
 PRIM_FILE='./archive_libs/discrete/cap_a/chips/chips.prt';

PART_NAME
 C9E1 'CAP_A_0603V-22.0UF,4V,20%,EMPTA':
 GROUP='NI_I210&RJ45',
 ROOM='NIC_SPRV';

SECTION_NUMBER 1
 '@BASEBOARD_FAB2_LIB.BASEBOARD_FAB2(SCH_1):PAGE139_I163@DEV_DISCRETE.CAP_A(CHIPS)':
 C_PATH='@baseboard_fab2_lib.baseboard_fab2(sch_1):page139_i163@dev_discrete.cap~
_a(chips)',
 P_PATH='@baseboard_fab2_lib.baseboard_fab2(sch_1):page139_i163@dev_discrete.cap~
_a(chips)',
 PATH='I163',
 DRAWING='@BASEBOARD_FAB2_LIB.BASEBOARD_FAB2(SCH_1):PAGE139',
 TOLERANCE='20%',
 SEC_TYPE='0603V',
 MATERIAL='EMPTY',
 BOM_COST='NT_GBE_BASE',
 PHYS_PAGE='139',
 XY='(-1600,875)',
 ROT='0',
 VER='1',
 VALUE='22.0UF',
 PACK_TYPE='0603V',
 PART_NUMBER='E15431-004',
 LOCATION='C9E1',
 ROOM='NIC_SPRV',
 GROUP='NI_I210&RJ45',
 SEC='1',
 CDS_LIB='dev_discrete',
 CDS_PART_NAME='CAP_A_0603V-22.0UF,4V,20%,EMPTA',
 VOLTAGE='4V',
 PRIM_FILE='./archive_libs/discrete/cap_a/chips/chips.prt';

PART_NAME
 C9E4 'CAP_A_0402V-0.1UF,16V,10%,X7R,A':
 GROUP='NI_I210&RJ45',
 ROOM='NIC_SPRV';

SECTION_NUMBER 1
 '@BASEBOARD_FAB2_LIB.BASEBOARD_FAB2(SCH_1):PAGE139_I88@DEV_DISCRETE.CAP_A(CHIPS)':
 C_PATH='@baseboard_fab2_lib.baseboard_fab2(sch_1):page139_i88@dev_discrete.cap_~
a(chips)',
 P_PATH='@baseboard_fab2_lib.baseboard_fab2(sch_1):page139_i88@dev_discrete.cap_~
a(chips)',
 PATH='I88',
 DRAWING='@BASEBOARD_FAB2_LIB.BASEBOARD_FAB2(SCH_1):PAGE139',
 TOLERANCE='10%',
 SEC_TYPE='0402V',
 MATERIAL='X7R',
 BOM_COST='NT_GBE_BASE',
 PHYS_PAGE='139',
 XY='(-2400,2125)',
 ROT='0',
 VER='2',
 VALUE='0.1UF',
 PACK_TYPE='0402V',
 PART_NUMBER='A36096-030',
 LOCATION='C9E4',
 ROOM='NIC_SPRV',
 GROUP='NI_I210&RJ45',
 SEC='1',
 CDS_LIB='dev_discrete',
 CDS_PART_NAME='CAP_A_0402V-0.1UF,16V,10%,X7R,A',
 VOLTAGE='16V',
 PRIM_FILE='./archive_libs/discrete/cap_a/chips/chips.prt';

PART_NAME
 C9E5 'CAP_A_0402V-0.1UF,16V,10%,X7R,A':
 GROUP='NI_I210&RJ45',
 ROOM='NIC_SPRV';

SECTION_NUMBER 1
 '@BASEBOARD_FAB2_LIB.BASEBOARD_FAB2(SCH_1):PAGE139_I87@DEV_DISCRETE.CAP_A(CHIPS)':
 C_PATH='@baseboard_fab2_lib.baseboard_fab2(sch_1):page139_i87@dev_discrete.cap_~
a(chips)',
 P_PATH='@baseboard_fab2_lib.baseboard_fab2(sch_1):page139_i87@dev_discrete.cap_~
a(chips)',
 PATH='I87',
 DRAWING='@BASEBOARD_FAB2_LIB.BASEBOARD_FAB2(SCH_1):PAGE139',
 TOLERANCE='10%',
 SEC_TYPE='0402V',
 MATERIAL='X7R',
 BOM_COST='NT_GBE_BASE',
 PHYS_PAGE='139',
 XY='(-1650,2075)',
 ROT='0',
 VER='2',
 VALUE='0.1UF',
 PACK_TYPE='0402V',
 PART_NUMBER='A36096-030',
 LOCATION='C9E5',
 ROOM='NIC_SPRV',
 GROUP='NI_I210&RJ45',
 SEC='1',
 CDS_LIB='dev_discrete',
 CDS_PART_NAME='CAP_A_0402V-0.1UF,16V,10%,X7R,A',
 VOLTAGE='16V',
 PRIM_FILE='./archive_libs/discrete/cap_a/chips/chips.prt';

PART_NAME
 C9E6 'SC22U16V5MX-4-GP_SMD-BCG5-SC22A':
 GROUP='NI_I210&RJ45';

SECTION_NUMBER 1
 '@BASEBOARD_FAB2_LIB.BASEBOARD_FAB2(SCH_1):PAGE139_I248@W_HDL.SC22U16V5MX-4-GP(CHIPS)':
 C_PATH='@baseboard_fab2_lib.baseboard_fab2(sch_1):page139_i248@w_hdl.\sc22u16v5~
mx-4-gp\(chips)',
 P_PATH='@baseboard_fab2_lib.baseboard_fab2(sch_1):page139_i248@w_hdl.\sc22u16v5~
mx-4-gp\(chips)',
 PATH='I248',
 DRAWING='@BASEBOARD_FAB2_LIB.BASEBOARD_FAB2(SCH_1):PAGE139',
 TYPE='X6S',
 PACK_SIZE='0805',
 RATED='16V',
 ATTRIBUTE='22UF',
 POP='NOPOP',
 TOLERANCE='20%',
 SEC_TYPE='SMD-BCG5',
 PHYS_PAGE='139',
 XY='(-4000,800)',
 ROT='0',
 VER='1',
 VALUE='SC22U16V5MX-4-GP',
 PACK_TYPE='SMD-BCG5',
 PART_NUMBER='078.22611.0811',
 LOCATION='C9E6',
 GROUP='NI_I210&RJ45',
 SEC='1',
 CDS_LIB='w_hdl',
 CDS_PART_NAME='SC22U16V5MX-4-GP_SMD-BCG5-SC22A',
 PRIM_FILE='C:/<user>/w_hdl/sc22u16v5mx#2d4#2dgp/chips/chips.prt';

PART_NAME
 C9E7 'CAP_0402LF-0.039UF,25V,10%,X7RA':
 GROUP='NI_I210&RJ45',
 ROOM='NIC_SPRV';

SECTION_NUMBER 1
 '@BASEBOARD_FAB2_LIB.BASEBOARD_FAB2(SCH_1):PAGE139_I76@MSTR_DISCRETE.CAP(CHIPS)':
 C_PATH='@baseboard_fab2_lib.baseboard_fab2(sch_1):page139_i76@mstr_discrete.cap~
(chips)',
 P_PATH='@baseboard_fab2_lib.baseboard_fab2(sch_1):page139_i76@mstr_discrete.cap~
(chips)',
 PATH='I76',
 DRAWING='@BASEBOARD_FAB2_LIB.BASEBOARD_FAB2(SCH_1):PAGE139',
 TOLERANCE='10%',
 SEC_TYPE='0402LF',
 MATERIAL='X7R',
 BOM_COST='NT_GBE_BASE',
 PHYS_PAGE='139',
 XY='(-2725,3500)',
 ROT='0',
 VER='1',
 VALUE='0.039UF',
 PACK_TYPE='0402LF',
 PART_NUMBER='A36096-063',
 LOCATION='C9E7',
 ROOM='NIC_SPRV',
 GROUP='NI_I210&RJ45',
 SEC='1',
 CDS_LIB='mstr_discrete',
 CDS_PART_NAME='CAP_0402LF-0.039UF,25V,10%,X7RA',
 VOLTAGE='25V',
 PRIM_FILE='./archive_libs/mstr_discrete/cap/chips/chips.prt';

PART_NAME
 C9E8 'CAP_0402LF-15.0PF,50V,5%,COG,AA':
 GROUP='NI_I210&RJ45',
 ROOM='SB';

SECTION_NUMBER 1
 '@BASEBOARD_FAB2_LIB.BASEBOARD_FAB2(SCH_1):PAGE139_I250@MSTR_DISCRETE.CAP(CHIPS)':
 C_PATH='@baseboard_fab2_lib.baseboard_fab2(sch_1):page139_i250@mstr_discrete.ca~
p(chips)',
 P_PATH='@baseboard_fab2_lib.baseboard_fab2(sch_1):page139_i250@mstr_discrete.ca~
p(chips)',
 PATH='I250',
 DRAWING='@BASEBOARD_FAB2_LIB.BASEBOARD_FAB2(SCH_1):PAGE139',
 TOLERANCE='5%',
 SEC_TYPE='0402LF',
 MATERIAL='COG',
 BOM_COST='SYS_CLOCK',
 PHYS_PAGE='139',
 XY='(-7325,1200)',
 ROT='0',
 VER='1',
 VALUE='15.0PF',
 PACK_TYPE='0402LF',
 PART_NUMBER='A36095-047',
 LOCATION='C9E8',
 ROOM='SB',
 GROUP='NI_I210&RJ45',
 SEC='1',
 CDS_LIB='mstr_discrete',
 CDS_PART_NAME='CAP_0402LF-15.0PF,50V,5%,COG,AA',
 VOLTAGE='50V',
 PRIM_FILE='./archive_libs/mstr_discrete/cap/chips/chips.prt';

PART_NAME
 C9E9 'CAP_0402LF-15.0PF,50V,5%,COG,AA':
 GROUP='NI_I210&RJ45',
 ROOM='SB';

SECTION_NUMBER 1
 '@BASEBOARD_FAB2_LIB.BASEBOARD_FAB2(SCH_1):PAGE139_I249@MSTR_DISCRETE.CAP(CHIPS)':
 C_PATH='@baseboard_fab2_lib.baseboard_fab2(sch_1):page139_i249@mstr_discrete.ca~
p(chips)',
 P_PATH='@baseboard_fab2_lib.baseboard_fab2(sch_1):page139_i249@mstr_discrete.ca~
p(chips)',
 PATH='I249',
 DRAWING='@BASEBOARD_FAB2_LIB.BASEBOARD_FAB2(SCH_1):PAGE139',
 TOLERANCE='5%',
 SEC_TYPE='0402LF',
 MATERIAL='COG',
 BOM_COST='SYS_CLOCK',
 PHYS_PAGE='139',
 XY='(-7750,1200)',
 ROT='0',
 VER='1',
 VALUE='15.0PF',
 PACK_TYPE='0402LF',
 PART_NUMBER='A36095-047',
 LOCATION='C9E9',
 ROOM='SB',
 GROUP='NI_I210&RJ45',
 SEC='1',
 CDS_LIB='mstr_discrete',
 CDS_PART_NAME='CAP_0402LF-15.0PF,50V,5%,COG,AA',
 VOLTAGE='50V',
 PRIM_FILE='./archive_libs/mstr_discrete/cap/chips/chips.prt';

PART_NAME
 C9E10 'CAP_0603-10UF,6.3V,20%,X6S,E15A':
 ROOM='P1V26_BMC_STBY_VR';

SECTION_NUMBER 1
 '@BASEBOARD_FAB2_LIB.BASEBOARD_FAB2(SCH_1):PAGE238_I23@MSTR_DISCRETE.CAP(CHIPS)':
 C_PATH='@baseboard_fab2_lib.baseboard_fab2(sch_1):page238_i23@mstr_discrete.cap~
(chips)',
 P_PATH='@baseboard_fab2_lib.baseboard_fab2(sch_1):page238_i23@mstr_discrete.cap~
(chips)',
 PATH='I23',
 DRAWING='@BASEBOARD_FAB2_LIB.BASEBOARD_FAB2(SCH_1):PAGE238',
 TOLERANCE='20%',
 SEC_TYPE='0603',
 MATERIAL='X6S',
 BOM_COST='P1V26_BMC_STBY_VR',
 PHYS_PAGE='238',
 XY='(1600,2525)',
 ROT='0',
 VER='1',
 VALUE='10UF',
 PACK_TYPE='0603',
 PART_NUMBER='E15431-002',
 LOCATION='C9E10',
 ROOM='P1V26_BMC_STBY_VR',
 SEC='1',
 CDS_LIB='mstr_discrete',
 CDS_PART_NAME='CAP_0603-10UF,6.3V,20%,X6S,E15A',
 VOLTAGE='6.3V',
 PRIM_FILE='./archive_libs/mstr_discrete/cap/chips/chips.prt';

PART_NAME
 C9E11 'CAP_0402-1.0UF,16V,10%,X6S,D97A':;

SECTION_NUMBER 1
 '@BASEBOARD_FAB2_LIB.BASEBOARD_FAB2(SCH_1):PAGE238_I39@MSTR_DISCRETE.CAP(CHIPS)':
 C_PATH='@baseboard_fab2_lib.baseboard_fab2(sch_1):page238_i39@mstr_discrete.cap~
(chips)',
 P_PATH='@baseboard_fab2_lib.baseboard_fab2(sch_1):page238_i39@mstr_discrete.cap~
(chips)',
 PATH='I39',
 DRAWING='@BASEBOARD_FAB2_LIB.BASEBOARD_FAB2(SCH_1):PAGE238',
 TOLERANCE='10%',
 SEC_TYPE='0402',
 MATERIAL='X6S',
 PHYS_PAGE='238',
 XY='(-1275,2150)',
 ROT='0',
 VER='1',
 VALUE='1.0UF',
 PACK_TYPE='0402',
 PART_NUMBER='D97712-011',
 LOCATION='C9E11',
 SEC='1',
 CDS_LIB='mstr_discrete',
 CDS_PART_NAME='CAP_0402-1.0UF,16V,10%,X6S,D97A',
 VOLTAGE='16V',
 PRIM_FILE='./archive_libs/mstr_discrete/cap/chips/chips.prt';

PART_NAME
 C9E12 'CAP_A_0603V-22.0UF,4V,20%,EMPTA':
 GROUP='NI_I210&RJ45',
 ROOM='NIC_SPRV';

SECTION_NUMBER 1
 '@BASEBOARD_FAB2_LIB.BASEBOARD_FAB2(SCH_1):PAGE139_I241@DEV_DISCRETE.CAP_A(CHIPS)':
 C_PATH='@baseboard_fab2_lib.baseboard_fab2(sch_1):page139_i241@dev_discrete.cap~
_a(chips)',
 P_PATH='@baseboard_fab2_lib.baseboard_fab2(sch_1):page139_i241@dev_discrete.cap~
_a(chips)',
 PATH='I241',
 DRAWING='@BASEBOARD_FAB2_LIB.BASEBOARD_FAB2(SCH_1):PAGE139',
 TOLERANCE='20%',
 SEC_TYPE='0603V',
 MATERIAL='EMPTY',
 BOM_COST='NT_GBE_BASE',
 PHYS_PAGE='139',
 XY='(-1925,875)',
 ROT='0',
 VER='1',
 VALUE='22.0UF',
 PACK_TYPE='0603V',
 PART_NUMBER='E15431-004',
 LOCATION='C9E12',
 ROOM='NIC_SPRV',
 GROUP='NI_I210&RJ45',
 SEC='1',
 CDS_LIB='dev_discrete',
 CDS_PART_NAME='CAP_A_0603V-22.0UF,4V,20%,EMPTA',
 VOLTAGE='4V',
 PRIM_FILE='./archive_libs/discrete/cap_a/chips/chips.prt';

PART_NAME
 C9F1 'SC22U16V5MX-4-GP_SMD-BCG5-SC22A':;

SECTION_NUMBER 1
 '@BASEBOARD_FAB2_LIB.BASEBOARD_FAB2(SCH_1):PAGE240_I181@W_HDL.SC22U16V5MX-4-GP(CHIPS)':
 C_PATH='@baseboard_fab2_lib.baseboard_fab2(sch_1):page240_i181@w_hdl.\sc22u16v5~
mx-4-gp\(chips)',
 P_PATH='@baseboard_fab2_lib.baseboard_fab2(sch_1):page240_i181@w_hdl.\sc22u16v5~
mx-4-gp\(chips)',
 PATH='I181',
 DRAWING='@BASEBOARD_FAB2_LIB.BASEBOARD_FAB2(SCH_1):PAGE240',
 TYPE='X6S',
 PACK_SIZE='0805',
 RATED='16V',
 ATTRIBUTE='22UF',
 TOLERANCE='20%',
 SEC_TYPE='SMD-BCG5',
 PHYS_PAGE='240',
 XY='(6700,4275)',
 ROT='0',
 VER='1',
 VALUE='SC22U16V5MX-4-GP',
 PACK_TYPE='SMD-BCG5',
 PART_NUMBER='078.22611.0811',
 LOCATION='C9F1',
 SEC='1',
 CDS_LIB='w_hdl',
 CDS_PART_NAME='SC22U16V5MX-4-GP_SMD-BCG5-SC22A',
 PRIM_FILE='C:/<user>/w_hdl/sc22u16v5mx#2d4#2dgp/chips/chips.prt';

PART_NAME
 C9F2 'SC22U16V5MX-4-GP_SMD-BCG5-SC22A':
 GROUP='NI_I210&RJ45';

SECTION_NUMBER 1
 '@BASEBOARD_FAB2_LIB.BASEBOARD_FAB2(SCH_1):PAGE139_I245@W_HDL.SC22U16V5MX-4-GP(CHIPS)':
 C_PATH='@baseboard_fab2_lib.baseboard_fab2(sch_1):page139_i245@w_hdl.\sc22u16v5~
mx-4-gp\(chips)',
 P_PATH='@baseboard_fab2_lib.baseboard_fab2(sch_1):page139_i245@w_hdl.\sc22u16v5~
mx-4-gp\(chips)',
 PATH='I245',
 DRAWING='@BASEBOARD_FAB2_LIB.BASEBOARD_FAB2(SCH_1):PAGE139',
 TYPE='X6S',
 PACK_SIZE='0805',
 RATED='16V',
 ATTRIBUTE='22UF',
 POP='NOPOP',
 TOLERANCE='20%',
 SEC_TYPE='SMD-BCG5',
 PHYS_PAGE='139',
 XY='(-6100,825)',
 ROT='0',
 VER='1',
 VALUE='SC22U16V5MX-4-GP',
 PACK_TYPE='SMD-BCG5',
 PART_NUMBER='078.22611.0811',
 LOCATION='C9F2',
 GROUP='NI_I210&RJ45',
 SEC='1',
 CDS_LIB='w_hdl',
 CDS_PART_NAME='SC22U16V5MX-4-GP_SMD-BCG5-SC22A',
 PRIM_FILE='C:/<user>/w_hdl/sc22u16v5mx#2d4#2dgp/chips/chips.prt';

PART_NAME
 C9F3 'CAP_0603-10UF,6.3V,20%,X6S,E15A':
 ROOM='P1V26_BMC_STBY_VR';

SECTION_NUMBER 1
 '@BASEBOARD_FAB2_LIB.BASEBOARD_FAB2(SCH_1):PAGE238_I7@MSTR_DISCRETE.CAP(CHIPS)':
 C_PATH='@baseboard_fab2_lib.baseboard_fab2(sch_1):page238_i7@mstr_discrete.cap(~
chips)',
 P_PATH='@baseboard_fab2_lib.baseboard_fab2(sch_1):page238_i7@mstr_discrete.cap(~
chips)',
 PATH='I7',
 DRAWING='@BASEBOARD_FAB2_LIB.BASEBOARD_FAB2(SCH_1):PAGE238',
 TOLERANCE='20%',
 SEC_TYPE='0603',
 MATERIAL='X6S',
 BOM_COST='P1V26_BMC_STBY_VR',
 PHYS_PAGE='238',
 XY='(-2500,3025)',
 ROT='0',
 VER='1',
 VALUE='10UF',
 PACK_TYPE='0603',
 PART_NUMBER='E15431-002',
 LOCATION='C9F3',
 ROOM='P1V26_BMC_STBY_VR',
 SEC='1',
 CDS_LIB='mstr_discrete',
 CDS_PART_NAME='CAP_0603-10UF,6.3V,20%,X6S,E15A',
 VOLTAGE='6.3V',
 PRIM_FILE='./archive_libs/mstr_discrete/cap/chips/chips.prt';

PART_NAME
 C9F4 'CAP_0805LF-22UF,4V,20%,X6S,C95A':
 ROOM='P1V26_BMC_STBY_VR';

SECTION_NUMBER 1
 '@BASEBOARD_FAB2_LIB.BASEBOARD_FAB2(SCH_1):PAGE238_I30@MSTR_DISCRETE.CAP(CHIPS)':
 C_PATH='@baseboard_fab2_lib.baseboard_fab2(sch_1):page238_i30@mstr_discrete.cap~
(chips)',
 P_PATH='@baseboard_fab2_lib.baseboard_fab2(sch_1):page238_i30@mstr_discrete.cap~
(chips)',
 PATH='I30',
 DRAWING='@BASEBOARD_FAB2_LIB.BASEBOARD_FAB2(SCH_1):PAGE238',
 TOLERANCE='20%',
 SEC_TYPE='0805LF',
 MATERIAL='X6S',
 BOM_COST='P1V26_BMC_STBY_VR',
 PHYS_PAGE='238',
 XY='(2325,2525)',
 ROT='0',
 VER='1',
 VALUE='22UF',
 PACK_TYPE='0805LF',
 PART_NUMBER='C95333-002',
 LOCATION='C9F4',
 ROOM='P1V26_BMC_STBY_VR',
 SEC='1',
 CDS_LIB='mstr_discrete',
 CDS_PART_NAME='CAP_0805LF-22UF,4V,20%,X6S,C95A',
 VOLTAGE='4V',
 PRIM_FILE='./archive_libs/mstr_discrete/cap/chips/chips.prt';

PART_NAME
 C9F5 'CAP_A_0402V-0.1UF,16V,10%,X7R,A':;

SECTION_NUMBER 1
 '@BASEBOARD_FAB2_LIB.BASEBOARD_FAB2(SCH_1):PAGE239_I71@DEV_DISCRETE.CAP_A(CHIPS)':
 C_PATH='@baseboard_fab2_lib.baseboard_fab2(sch_1):page239_i71@dev_discrete.cap_~
a(chips)',
 P_PATH='@baseboard_fab2_lib.baseboard_fab2(sch_1):page239_i71@dev_discrete.cap_~
a(chips)',
 PATH='I71',
 DRAWING='@BASEBOARD_FAB2_LIB.BASEBOARD_FAB2(SCH_1):PAGE239',
 TOLERANCE='10%',
 SEC_TYPE='0402V',
 MATERIAL='X7R',
 PHYS_PAGE='239',
 XY='(7475,4125)',
 ROT='0',
 VER='1',
 VALUE='0.1UF',
 PACK_TYPE='0402V',
 PART_NUMBER='A36096-030',
 LOCATION='C9F5',
 SEC='1',
 CDS_LIB='dev_discrete',
 CDS_PART_NAME='CAP_A_0402V-0.1UF,16V,10%,X7R,A',
 VOLTAGE='16V',
 PRIM_FILE='./archive_libs/discrete/cap_a/chips/chips.prt';

PART_NAME
 C9F6 'CAP_0402LF-1000PF,50V,10%,EMPTA':
 ROOM='P1V538_BMC_STBY_VR';

SECTION_NUMBER 1
 '@BASEBOARD_FAB2_LIB.BASEBOARD_FAB2(SCH_1):PAGE239_I30@MSTR_DISCRETE.CAP(CHIPS)':
 C_PATH='@baseboard_fab2_lib.baseboard_fab2(sch_1):page239_i30@mstr_discrete.cap~
(chips)',
 P_PATH='@baseboard_fab2_lib.baseboard_fab2(sch_1):page239_i30@mstr_discrete.cap~
(chips)',
 PATH='I30',
 DRAWING='@BASEBOARD_FAB2_LIB.BASEBOARD_FAB2(SCH_1):PAGE239',
 TOLERANCE='10%',
 MATERIAL='EMPTY',
 BOM_COST='P1V538_BMC_STBY_VR',
 PHYS_PAGE='239',
 XY='(7050,3300)',
 ROT='2',
 VER='1',
 VALUE='1000PF',
 PACK_TYPE='0402LF',
 PART_NUMBER='A36096-046',
 LOCATION='C9F6',
 ROOM='P1V538_BMC_STBY_VR',
 CDS_LIB='mstr_discrete',
 CDS_PART_NAME='CAP_0402LF-1000PF,50V,10%,EMPTA',
 VOLTAGE='50V',
 PRIM_FILE='./archive_libs/mstr_discrete/cap/chips/chips.prt';

PART_NAME
 C9F8 'CAP_0402LF-1000PF,50V,10%,X7R,A':
 ROOM='P1V26_BMC_STBY_VR';

SECTION_NUMBER 1
 '@BASEBOARD_FAB2_LIB.BASEBOARD_FAB2(SCH_1):PAGE238_I19@MSTR_DISCRETE.CAP(CHIPS)':
 C_PATH='@baseboard_fab2_lib.baseboard_fab2(sch_1):page238_i19@mstr_discrete.cap~
(chips)',
 P_PATH='@baseboard_fab2_lib.baseboard_fab2(sch_1):page238_i19@mstr_discrete.cap~
(chips)',
 PATH='I19',
 DRAWING='@BASEBOARD_FAB2_LIB.BASEBOARD_FAB2(SCH_1):PAGE238',
 TOLERANCE='10%',
 MATERIAL='X7R',
 BOM_COST='P1V26_BMC_STBY_VR',
 PHYS_PAGE='238',
 XY='(1250,3050)',
 ROT='0',
 VER='1',
 VALUE='1000PF',
 PACK_TYPE='0402LF',
 PART_NUMBER='A36096-046',
 LOCATION='C9F8',
 ROOM='P1V26_BMC_STBY_VR',
 CDS_LIB='mstr_discrete',
 CDS_PART_NAME='CAP_0402LF-1000PF,50V,10%,X7R,A',
 VOLTAGE='50V',
 PRIM_FILE='./archive_libs/mstr_discrete/cap/chips/chips.prt';

PART_NAME
 C9F9 'CAP_0402LF-1000PF,50V,10%,EMPTA':
 ROOM='P1V26_BMC_STBY_VR';

SECTION_NUMBER 1
 '@BASEBOARD_FAB2_LIB.BASEBOARD_FAB2(SCH_1):PAGE238_I5@MSTR_DISCRETE.CAP(CHIPS)':
 C_PATH='@baseboard_fab2_lib.baseboard_fab2(sch_1):page238_i5@mstr_discrete.cap(~
chips)',
 P_PATH='@baseboard_fab2_lib.baseboard_fab2(sch_1):page238_i5@mstr_discrete.cap(~
chips)',
 PATH='I5',
 DRAWING='@BASEBOARD_FAB2_LIB.BASEBOARD_FAB2(SCH_1):PAGE238',
 TOLERANCE='10%',
 MATERIAL='EMPTY',
 BOM_COST='P1V26_BMC_STBY_VR',
 PHYS_PAGE='238',
 XY='(-2000,2175)',
 ROT='2',
 VER='1',
 VALUE='1000PF',
 PACK_TYPE='0402LF',
 PART_NUMBER='A36096-046',
 LOCATION='C9F9',
 ROOM='P1V26_BMC_STBY_VR',
 CDS_LIB='mstr_discrete',
 CDS_PART_NAME='CAP_0402LF-1000PF,50V,10%,EMPTA',
 VOLTAGE='50V',
 PRIM_FILE='./archive_libs/mstr_discrete/cap/chips/chips.prt';

PART_NAME
 C9F10 'CAP_0402LF-1000PF,50V,10%,X7R,A':
 ROOM='P1V538_BMC_STBY_VR';

SECTION_NUMBER 1
 '@BASEBOARD_FAB2_LIB.BASEBOARD_FAB2(SCH_1):PAGE239_I4@MSTR_DISCRETE.CAP(CHIPS)':
 C_PATH='@baseboard_fab2_lib.baseboard_fab2(sch_1):page239_i4@mstr_discrete.cap(~
chips)',
 P_PATH='@baseboard_fab2_lib.baseboard_fab2(sch_1):page239_i4@mstr_discrete.cap(~
chips)',
 PATH='I4',
 DRAWING='@BASEBOARD_FAB2_LIB.BASEBOARD_FAB2(SCH_1):PAGE239',
 TOLERANCE='10%',
 MATERIAL='X7R',
 BOM_COST='P1V538_BMC_STBY_VR',
 PHYS_PAGE='239',
 XY='(10375,4150)',
 ROT='0',
 VER='1',
 VALUE='1000PF',
 PACK_TYPE='0402LF',
 PART_NUMBER='A36096-046',
 LOCATION='C9F10',
 ROOM='P1V538_BMC_STBY_VR',
 CDS_LIB='mstr_discrete',
 CDS_PART_NAME='CAP_0402LF-1000PF,50V,10%,X7R,A',
 VOLTAGE='50V',
 PRIM_FILE='./archive_libs/mstr_discrete/cap/chips/chips.prt';

PART_NAME
 C9F13 'CAP_0805LF-22UF,4V,20%,X6S,C95A':
 ROOM='P1V538_BMC_STBY_VR';

SECTION_NUMBER 1
 '@BASEBOARD_FAB2_LIB.BASEBOARD_FAB2(SCH_1):PAGE239_I7@MSTR_DISCRETE.CAP(CHIPS)':
 C_PATH='@baseboard_fab2_lib.baseboard_fab2(sch_1):page239_i7@mstr_discrete.cap(~
chips)',
 P_PATH='@baseboard_fab2_lib.baseboard_fab2(sch_1):page239_i7@mstr_discrete.cap(~
chips)',
 PATH='I7',
 DRAWING='@BASEBOARD_FAB2_LIB.BASEBOARD_FAB2(SCH_1):PAGE239',
 TOLERANCE='20%',
 SEC_TYPE='0805LF',
 MATERIAL='X6S',
 BOM_COST='P1V538_BMC_STBY_VR',
 PHYS_PAGE='239',
 XY='(11725,3575)',
 ROT='0',
 VER='1',
 VALUE='22UF',
 PACK_TYPE='0805LF',
 PART_NUMBER='C95333-002',
 LOCATION='C9F13',
 ROOM='P1V538_BMC_STBY_VR',
 SEC='1',
 CDS_LIB='mstr_discrete',
 CDS_PART_NAME='CAP_0805LF-22UF,4V,20%,X6S,C95A',
 VOLTAGE='4V',
 PRIM_FILE='./archive_libs/mstr_discrete/cap/chips/chips.prt';

PART_NAME
 C9F22 'CAP_0402LF-470PF,50V,10%,X7R,AA':
 GROUP='NI_I210&RJ45',
 ROOM='NIC_SPRV';

SECTION_NUMBER 1
 '@BASEBOARD_FAB2_LIB.BASEBOARD_FAB2(SCH_1):PAGE141_I159@MSTR_DISCRETE.CAP(CHIPS)':
 C_PATH='@baseboard_fab2_lib.baseboard_fab2(sch_1):page141_i159@mstr_discrete.ca~
p(chips)',
 P_PATH='@baseboard_fab2_lib.baseboard_fab2(sch_1):page141_i159@mstr_discrete.ca~
p(chips)',
 PATH='I159',
 DRAWING='@BASEBOARD_FAB2_LIB.BASEBOARD_FAB2(SCH_1):PAGE141',
 TOLERANCE='10%',
 SEC_TYPE='0402LF',
 MATERIAL='X7R',
 BOM_COST='NT_GBE_BASE',
 PHYS_PAGE='141',
 XY='(-3650,1300)',
 ROT='0',
 VER='1',
 VALUE='470PF',
 PACK_TYPE='0402LF',
 PART_NUMBER='A36096-049',
 LOCATION='C9F22',
 ROOM='NIC_SPRV',
 GROUP='NI_I210&RJ45',
 SEC='1',
 CDS_LIB='mstr_discrete',
 CDS_PART_NAME='CAP_0402LF-470PF,50V,10%,X7R,AA',
 VOLTAGE='50V',
 PRIM_FILE='./archive_libs/mstr_discrete/cap/chips/chips.prt';

PART_NAME
 C9F23 'CAP_A_0402V-0.1UF,16V,10%,X7R,A':
 ROOM='BMC';

SECTION_NUMBER 1
 '@BASEBOARD_FAB2_LIB.BASEBOARD_FAB2(SCH_1):PAGE145_I15@DEV_DISCRETE.CAP_A(CHIPS)':
 C_PATH='@baseboard_fab2_lib.baseboard_fab2(sch_1):page145_i15@dev_discrete.cap_~
a(chips)',
 P_PATH='@baseboard_fab2_lib.baseboard_fab2(sch_1):page145_i15@dev_discrete.cap_~
a(chips)',
 PATH='I15',
 DRAWING='@BASEBOARD_FAB2_LIB.BASEBOARD_FAB2(SCH_1):PAGE145',
 TOLERANCE='10%',
 SEC_TYPE='0402V',
 MATERIAL='X7R',
 BOM_COST='SM_CONTROLLER',
 PHYS_PAGE='145',
 XY='(-7500,-450)',
 ROT='0',
 VER='1',
 VALUE='0.1UF',
 PACK_TYPE='0402V',
 PART_NUMBER='A36096-030',
 LOCATION='C9F23',
 ROOM='BMC',
 SEC='1',
 CDS_LIB='dev_discrete',
 CDS_PART_NAME='CAP_A_0402V-0.1UF,16V,10%,X7R,A',
 VOLTAGE='16V',
 PRIM_FILE='./archive_libs/discrete/cap_a/chips/chips.prt';

PART_NAME
 C9G1 'CAP_0402LF-470PF,50V,10%,X7R,AA':
 GROUP='NI_I210&RJ45',
 ROOM='NIC_SPRV';

SECTION_NUMBER 1
 '@BASEBOARD_FAB2_LIB.BASEBOARD_FAB2(SCH_1):PAGE141_I140@MSTR_DISCRETE.CAP(CHIPS)':
 C_PATH='@baseboard_fab2_lib.baseboard_fab2(sch_1):page141_i140@mstr_discrete.ca~
p(chips)',
 P_PATH='@baseboard_fab2_lib.baseboard_fab2(sch_1):page141_i140@mstr_discrete.ca~
p(chips)',
 PATH='I140',
 DRAWING='@BASEBOARD_FAB2_LIB.BASEBOARD_FAB2(SCH_1):PAGE141',
 TOLERANCE='10%',
 SEC_TYPE='0402LF',
 MATERIAL='X7R',
 BOM_COST='NT_GBE_BASE',
 PHYS_PAGE='141',
 XY='(-3650,2375)',
 ROT='0',
 VER='1',
 VALUE='470PF',
 PACK_TYPE='0402LF',
 PART_NUMBER='A36096-049',
 LOCATION='C9G1',
 ROOM='NIC_SPRV',
 GROUP='NI_I210&RJ45',
 SEC='1',
 CDS_LIB='mstr_discrete',
 CDS_PART_NAME='CAP_0402LF-470PF,50V,10%,X7R,AA',
 VOLTAGE='50V',
 PRIM_FILE='./archive_libs/mstr_discrete/cap/chips/chips.prt';

PART_NAME
 C9G2 'CAP_0402LF-470PF,50V,10%,X7R,AA':
 GROUP='NI_I210&RJ45',
 ROOM='NIC_SPRV';

SECTION_NUMBER 1
 '@BASEBOARD_FAB2_LIB.BASEBOARD_FAB2(SCH_1):PAGE141_I152@MSTR_DISCRETE.CAP(CHIPS)':
 C_PATH='@baseboard_fab2_lib.baseboard_fab2(sch_1):page141_i152@mstr_discrete.ca~
p(chips)',
 P_PATH='@baseboard_fab2_lib.baseboard_fab2(sch_1):page141_i152@mstr_discrete.ca~
p(chips)',
 PATH='I152',
 DRAWING='@BASEBOARD_FAB2_LIB.BASEBOARD_FAB2(SCH_1):PAGE141',
 TOLERANCE='10%',
 SEC_TYPE='0402LF',
 MATERIAL='X7R',
 BOM_COST='NT_GBE_BASE',
 PHYS_PAGE='141',
 XY='(-3200,1050)',
 ROT='0',
 VER='1',
 VALUE='470PF',
 PACK_TYPE='0402LF',
 PART_NUMBER='A36096-049',
 LOCATION='C9G2',
 ROOM='NIC_SPRV',
 GROUP='NI_I210&RJ45',
 SEC='1',
 CDS_LIB='mstr_discrete',
 CDS_PART_NAME='CAP_0402LF-470PF,50V,10%,X7R,AA',
 VOLTAGE='50V',
 PRIM_FILE='./archive_libs/mstr_discrete/cap/chips/chips.prt';

PART_NAME
 C9G3 'CAP_0402LF-470PF,50V,10%,X7R,AA':
 GROUP='NI_I210&RJ45',
 ROOM='NIC_SPRV';

SECTION_NUMBER 1
 '@BASEBOARD_FAB2_LIB.BASEBOARD_FAB2(SCH_1):PAGE141_I138@MSTR_DISCRETE.CAP(CHIPS)':
 C_PATH='@baseboard_fab2_lib.baseboard_fab2(sch_1):page141_i138@mstr_discrete.ca~
p(chips)',
 P_PATH='@baseboard_fab2_lib.baseboard_fab2(sch_1):page141_i138@mstr_discrete.ca~
p(chips)',
 PATH='I138',
 DRAWING='@BASEBOARD_FAB2_LIB.BASEBOARD_FAB2(SCH_1):PAGE141',
 TOLERANCE='10%',
 SEC_TYPE='0402LF',
 MATERIAL='X7R',
 BOM_COST='NT_GBE_BASE',
 PHYS_PAGE='141',
 XY='(-3350,2375)',
 ROT='0',
 VER='1',
 VALUE='470PF',
 PACK_TYPE='0402LF',
 PART_NUMBER='A36096-049',
 LOCATION='C9G3',
 ROOM='NIC_SPRV',
 GROUP='NI_I210&RJ45',
 SEC='1',
 CDS_LIB='mstr_discrete',
 CDS_PART_NAME='CAP_0402LF-470PF,50V,10%,X7R,AA',
 VOLTAGE='50V',
 PRIM_FILE='./archive_libs/mstr_discrete/cap/chips/chips.prt';

PART_NAME
 C9G4 'CAP_A_0402V-0.1UF,16V,10%,X7R,A':
 GROUP='NI_I210&RJ45',
 ROOM='NIC_SPRV';

SECTION_NUMBER 1
 '@BASEBOARD_FAB2_LIB.BASEBOARD_FAB2(SCH_1):PAGE141_I46@DEV_DISCRETE.CAP_A(CHIPS)':
 C_PATH='@baseboard_fab2_lib.baseboard_fab2(sch_1):page141_i46@dev_discrete.cap_~
a(chips)',
 P_PATH='@baseboard_fab2_lib.baseboard_fab2(sch_1):page141_i46@dev_discrete.cap_~
a(chips)',
 PATH='I46',
 DRAWING='@BASEBOARD_FAB2_LIB.BASEBOARD_FAB2(SCH_1):PAGE141',
 TOLERANCE='10%',
 SEC_TYPE='0402V',
 MATERIAL='X7R',
 BOM_COST='NT_GBE_BASE',
 PHYS_PAGE='141',
 XY='(-6075,575)',
 ROT='0',
 VER='1',
 VALUE='0.1UF',
 PACK_TYPE='0402V',
 PART_NUMBER='A36096-030',
 LOCATION='C9G4',
 ROOM='NIC_SPRV',
 GROUP='NI_I210&RJ45',
 SEC='1',
 CDS_LIB='dev_discrete',
 CDS_PART_NAME='CAP_A_0402V-0.1UF,16V,10%,X7R,A',
 VOLTAGE='16V',
 PRIM_FILE='./archive_libs/discrete/cap_a/chips/chips.prt';

PART_NAME
 C9G5 'CAP_0402-1.0UF,16V,10%,X7S,G71A':
 GROUP='NI_I210&RJ45',
 ROOM='NIC_SPRV';

SECTION_NUMBER 1
 '@BASEBOARD_FAB2_LIB.BASEBOARD_FAB2(SCH_1):PAGE141_I48@MSTR_DISCRETE.CAP(CHIPS)':
 C_PATH='@baseboard_fab2_lib.baseboard_fab2(sch_1):page141_i48@mstr_discrete.cap~
(chips)',
 P_PATH='@baseboard_fab2_lib.baseboard_fab2(sch_1):page141_i48@mstr_discrete.cap~
(chips)',
 PATH='I48',
 DRAWING='@BASEBOARD_FAB2_LIB.BASEBOARD_FAB2(SCH_1):PAGE141',
 TOLERANCE='10%',
 SEC_TYPE='0402',
 MATERIAL='X7S',
 BOM_COST='NT_GBE_BASE',
 PHYS_PAGE='141',
 XY='(-6750,575)',
 ROT='0',
 VER='1',
 VALUE='1.0UF',
 PACK_TYPE='0402',
 PART_NUMBER='G71842-007',
 LOCATION='C9G5',
 ROOM='NIC_SPRV',
 GROUP='NI_I210&RJ45',
 SEC='1',
 CDS_LIB='mstr_discrete',
 CDS_PART_NAME='CAP_0402-1.0UF,16V,10%,X7S,G71A',
 VOLTAGE='16V',
 PRIM_FILE='./archive_libs/mstr_discrete/cap/chips/chips.prt';

PART_NAME
 C9G6 'CAP_A_0402V-0.1UF,16V,10%,X7R,A':
 GROUP='NI_I210&RJ45',
 ROOM='NIC_SPRV';

SECTION_NUMBER 1
 '@BASEBOARD_FAB2_LIB.BASEBOARD_FAB2(SCH_1):PAGE141_I47@DEV_DISCRETE.CAP_A(CHIPS)':
 C_PATH='@baseboard_fab2_lib.baseboard_fab2(sch_1):page141_i47@dev_discrete.cap_~
a(chips)',
 P_PATH='@baseboard_fab2_lib.baseboard_fab2(sch_1):page141_i47@dev_discrete.cap_~
a(chips)',
 PATH='I47',
 DRAWING='@BASEBOARD_FAB2_LIB.BASEBOARD_FAB2(SCH_1):PAGE141',
 TOLERANCE='10%',
 SEC_TYPE='0402V',
 MATERIAL='X7R',
 BOM_COST='NT_GBE_BASE',
 PHYS_PAGE='141',
 XY='(-6400,575)',
 ROT='0',
 VER='1',
 VALUE='0.1UF',
 PACK_TYPE='0402V',
 PART_NUMBER='A36096-030',
 LOCATION='C9G6',
 ROOM='NIC_SPRV',
 GROUP='NI_I210&RJ45',
 SEC='1',
 CDS_LIB='dev_discrete',
 CDS_PART_NAME='CAP_A_0402V-0.1UF,16V,10%,X7R,A',
 VOLTAGE='16V',
 PRIM_FILE='./archive_libs/discrete/cap_a/chips/chips.prt';

PART_NAME
 C9G9 'CAP_0402LF-4700PF,50V,10%,EMPTA':
 GROUP='NI_I210&RJ45',
 ROOM='NIC_SPRV',
 NO_XNET_CONNECTION='1';

SECTION_NUMBER 1
 '@BASEBOARD_FAB2_LIB.BASEBOARD_FAB2(SCH_1):PAGE141_I99@MSTR_DISCRETE.CAP(CHIPS)':
 C_PATH='@baseboard_fab2_lib.baseboard_fab2(sch_1):page141_i99@mstr_discrete.cap~
(chips)',
 P_PATH='@baseboard_fab2_lib.baseboard_fab2(sch_1):page141_i99@mstr_discrete.cap~
(chips)',
 PATH='I99',
 DRAWING='@BASEBOARD_FAB2_LIB.BASEBOARD_FAB2(SCH_1):PAGE141',
 TOLERANCE='10%',
 SEC_TYPE='0402LF',
 MATERIAL='EMPTY',
 BOM_COST='NT_GBE_BASE',
 NO_XNET_CONNECTION='1',
 PHYS_PAGE='141',
 XY='(-2875,4425)',
 ROT='0',
 VER='2',
 VALUE='4700PF',
 PACK_TYPE='0402LF',
 PART_NUMBER='A36096-066',
 LOCATION='C9G9',
 ROOM='NIC_SPRV',
 GROUP='NI_I210&RJ45',
 SEC='1',
 CDS_LIB='mstr_discrete',
 CDS_PART_NAME='CAP_0402LF-4700PF,50V,10%,EMPTA',
 VOLTAGE='50V',
 PRIM_FILE='./archive_libs/mstr_discrete/cap/chips/chips.prt';

PART_NAME
 C9G12 'CAP_0402LF-4700PF,50V,10%,EMPTA':
 GROUP='NI_I210&RJ45',
 ROOM='NIC_SPRV',
 NO_XNET_CONNECTION='1';

SECTION_NUMBER 1
 '@BASEBOARD_FAB2_LIB.BASEBOARD_FAB2(SCH_1):PAGE141_I100@MSTR_DISCRETE.CAP(CHIPS)':
 C_PATH='@baseboard_fab2_lib.baseboard_fab2(sch_1):page141_i100@mstr_discrete.ca~
p(chips)',
 P_PATH='@baseboard_fab2_lib.baseboard_fab2(sch_1):page141_i100@mstr_discrete.ca~
p(chips)',
 PATH='I100',
 DRAWING='@BASEBOARD_FAB2_LIB.BASEBOARD_FAB2(SCH_1):PAGE141',
 TOLERANCE='10%',
 MATERIAL='EMPTY',
 BOM_COST='NT_GBE_BASE',
 NO_XNET_CONNECTION='1',
 PHYS_PAGE='141',
 XY='(-3150,4375)',
 ROT='0',
 VER='2',
 VALUE='4700PF',
 PACK_TYPE='0402LF',
 PART_NUMBER='A36096-066',
 LOCATION='C9G12',
 ROOM='NIC_SPRV',
 GROUP='NI_I210&RJ45',
 CDS_LIB='mstr_discrete',
 CDS_PART_NAME='CAP_0402LF-4700PF,50V,10%,EMPTA',
 VOLTAGE='50V',
 PRIM_FILE='./archive_libs/mstr_discrete/cap/chips/chips.prt';

PART_NAME
 C9G13 'CAP_0402LF-4700PF,50V,10%,EMPTA':
 GROUP='NI_I210&RJ45',
 ROOM='NIC_SPRV',
 NO_XNET_CONNECTION='1';

SECTION_NUMBER 1
 '@BASEBOARD_FAB2_LIB.BASEBOARD_FAB2(SCH_1):PAGE141_I102@MSTR_DISCRETE.CAP(CHIPS)':
 C_PATH='@baseboard_fab2_lib.baseboard_fab2(sch_1):page141_i102@mstr_discrete.ca~
p(chips)',
 P_PATH='@baseboard_fab2_lib.baseboard_fab2(sch_1):page141_i102@mstr_discrete.ca~
p(chips)',
 PATH='I102',
 DRAWING='@BASEBOARD_FAB2_LIB.BASEBOARD_FAB2(SCH_1):PAGE141',
 TOLERANCE='10%',
 SEC_TYPE='0402LF',
 MATERIAL='EMPTY',
 BOM_COST='NT_GBE_BASE',
 NO_XNET_CONNECTION='1',
 PHYS_PAGE='141',
 XY='(-3100,4025)',
 ROT='0',
 VER='2',
 VALUE='4700PF',
 PACK_TYPE='0402LF',
 PART_NUMBER='A36096-066',
 LOCATION='C9G13',
 ROOM='NIC_SPRV',
 GROUP='NI_I210&RJ45',
 SEC='1',
 CDS_LIB='mstr_discrete',
 CDS_PART_NAME='CAP_0402LF-4700PF,50V,10%,EMPTA',
 VOLTAGE='50V',
 PRIM_FILE='./archive_libs/mstr_discrete/cap/chips/chips.prt';

PART_NAME
 C9G14 'CAP_0402LF-47.0PF,50V,5%,COG,AA':
 ROOM='BMC_VOLT_MONITOR';

SECTION_NUMBER 1
 '@BASEBOARD_FAB2_LIB.BASEBOARD_FAB2(SCH_1):PAGE169_I146@MSTR_DISCRETE.CAP(CHIPS)':
 C_PATH='@baseboard_fab2_lib.baseboard_fab2(sch_1):page169_i146@mstr_discrete.ca~
p(chips)',
 P_PATH='@baseboard_fab2_lib.baseboard_fab2(sch_1):page169_i146@mstr_discrete.ca~
p(chips)',
 PATH='I146',
 DRAWING='@BASEBOARD_FAB2_LIB.BASEBOARD_FAB2(SCH_1):PAGE169',
 TOLERANCE='5%',
 SEC_TYPE='0402LF',
 MATERIAL='COG',
 BOM_COST='SM_HM',
 PHYS_PAGE='169',
 XY='(-2550,4600)',
 ROT='0',
 VER='1',
 VALUE='47.0PF',
 PACK_TYPE='0402LF',
 PART_NUMBER='A36095-025',
 LOCATION='C9G14',
 ROOM='BMC_VOLT_MONITOR',
 SEC='1',
 CDS_LIB='mstr_discrete',
 CDS_PART_NAME='CAP_0402LF-47.0PF,50V,5%,COG,AA',
 VOLTAGE='50V',
 PRIM_FILE='./archive_libs/mstr_discrete/cap/chips/chips.prt';

PART_NAME
 C9G15 'CAP_0402LF-47.0PF,50V,5%,COG,AA':
 ROOM='BMC_VOLT_MONITOR';

SECTION_NUMBER 1
 '@BASEBOARD_FAB2_LIB.BASEBOARD_FAB2(SCH_1):PAGE169_I139@MSTR_DISCRETE.CAP(CHIPS)':
 C_PATH='@baseboard_fab2_lib.baseboard_fab2(sch_1):page169_i139@mstr_discrete.ca~
p(chips)',
 P_PATH='@baseboard_fab2_lib.baseboard_fab2(sch_1):page169_i139@mstr_discrete.ca~
p(chips)',
 PATH='I139',
 DRAWING='@BASEBOARD_FAB2_LIB.BASEBOARD_FAB2(SCH_1):PAGE169',
 TOLERANCE='5%',
 SEC_TYPE='0402LF',
 MATERIAL='COG',
 BOM_COST='SM_HM',
 PHYS_PAGE='169',
 XY='(-4350,4550)',
 ROT='0',
 VER='1',
 VALUE='47.0PF',
 PACK_TYPE='0402LF',
 PART_NUMBER='A36095-025',
 LOCATION='C9G15',
 ROOM='BMC_VOLT_MONITOR',
 SEC='1',
 CDS_LIB='mstr_discrete',
 CDS_PART_NAME='CAP_0402LF-47.0PF,50V,5%,COG,AA',
 VOLTAGE='50V',
 PRIM_FILE='./archive_libs/mstr_discrete/cap/chips/chips.prt';

PART_NAME
 C9G16 'CAP_0402LF-4700PF,50V,10%,EMPTA':
 GROUP='NI_I210&RJ45',
 ROOM='NIC_SPRV',
 NO_XNET_CONNECTION='1';

SECTION_NUMBER 1
 '@BASEBOARD_FAB2_LIB.BASEBOARD_FAB2(SCH_1):PAGE141_I101@MSTR_DISCRETE.CAP(CHIPS)':
 C_PATH='@baseboard_fab2_lib.baseboard_fab2(sch_1):page141_i101@mstr_discrete.ca~
p(chips)',
 P_PATH='@baseboard_fab2_lib.baseboard_fab2(sch_1):page141_i101@mstr_discrete.ca~
p(chips)',
 PATH='I101',
 DRAWING='@BASEBOARD_FAB2_LIB.BASEBOARD_FAB2(SCH_1):PAGE141',
 TOLERANCE='10%',
 SEC_TYPE='0402LF',
 MATERIAL='EMPTY',
 BOM_COST='NT_GBE_BASE',
 NO_XNET_CONNECTION='1',
 PHYS_PAGE='141',
 XY='(-2825,4075)',
 ROT='0',
 VER='2',
 VALUE='4700PF',
 PACK_TYPE='0402LF',
 PART_NUMBER='A36096-066',
 LOCATION='C9G16',
 ROOM='NIC_SPRV',
 GROUP='NI_I210&RJ45',
 SEC='1',
 CDS_LIB='mstr_discrete',
 CDS_PART_NAME='CAP_0402LF-4700PF,50V,10%,EMPTA',
 VOLTAGE='50V',
 PRIM_FILE='./archive_libs/mstr_discrete/cap/chips/chips.prt';

PART_NAME
 C9G17 'CAP_0402LF-47.0PF,50V,5%,COG,AA':
 ROOM='BMC_VOLT_MONITOR';

SECTION_NUMBER 1
 '@BASEBOARD_FAB2_LIB.BASEBOARD_FAB2(SCH_1):PAGE169_I80@MSTR_DISCRETE.CAP(CHIPS)':
 C_PATH='@baseboard_fab2_lib.baseboard_fab2(sch_1):page169_i80@mstr_discrete.cap~
(chips)',
 P_PATH='@baseboard_fab2_lib.baseboard_fab2(sch_1):page169_i80@mstr_discrete.cap~
(chips)',
 PATH='I80',
 DRAWING='@BASEBOARD_FAB2_LIB.BASEBOARD_FAB2(SCH_1):PAGE169',
 TOLERANCE='5%',
 SEC_TYPE='0402LF',
 MATERIAL='COG',
 BOM_COST='SM_HM',
 PHYS_PAGE='169',
 XY='(-775,1450)',
 ROT='0',
 VER='1',
 VALUE='47.0PF',
 PACK_TYPE='0402LF',
 PART_NUMBER='A36095-025',
 LOCATION='C9G17',
 ROOM='BMC_VOLT_MONITOR',
 SEC='1',
 CDS_LIB='mstr_discrete',
 CDS_PART_NAME='CAP_0402LF-47.0PF,50V,5%,COG,AA',
 VOLTAGE='50V',
 PRIM_FILE='./archive_libs/mstr_discrete/cap/chips/chips.prt';

PART_NAME
 C9G18 'CAP_0402LF-47.0PF,50V,5%,COG,AA':
 ROOM='BMC_VOLT_MONITOR';

SECTION_NUMBER 1
 '@BASEBOARD_FAB2_LIB.BASEBOARD_FAB2(SCH_1):PAGE169_I153@MSTR_DISCRETE.CAP(CHIPS)':
 C_PATH='@baseboard_fab2_lib.baseboard_fab2(sch_1):page169_i153@mstr_discrete.ca~
p(chips)',
 P_PATH='@baseboard_fab2_lib.baseboard_fab2(sch_1):page169_i153@mstr_discrete.ca~
p(chips)',
 PATH='I153',
 DRAWING='@BASEBOARD_FAB2_LIB.BASEBOARD_FAB2(SCH_1):PAGE169',
 TOLERANCE='5%',
 SEC_TYPE='0402LF',
 MATERIAL='COG',
 BOM_COST='SM_HM',
 PHYS_PAGE='169',
 XY='(800,1475)',
 ROT='0',
 VER='1',
 VALUE='47.0PF',
 PACK_TYPE='0402LF',
 PART_NUMBER='A36095-025',
 LOCATION='C9G18',
 ROOM='BMC_VOLT_MONITOR',
 SEC='1',
 CDS_LIB='mstr_discrete',
 CDS_PART_NAME='CAP_0402LF-47.0PF,50V,5%,COG,AA',
 VOLTAGE='50V',
 PRIM_FILE='./archive_libs/mstr_discrete/cap/chips/chips.prt';

PART_NAME
 C9G20 'CAP_0402LF-47.0PF,50V,5%,COG,AA':
 ROOM='BMC_VOLT_MONITOR';

SECTION_NUMBER 1
 '@BASEBOARD_FAB2_LIB.BASEBOARD_FAB2(SCH_1):PAGE169_I86@MSTR_DISCRETE.CAP(CHIPS)':
 C_PATH='@baseboard_fab2_lib.baseboard_fab2(sch_1):page169_i86@mstr_discrete.cap~
(chips)',
 P_PATH='@baseboard_fab2_lib.baseboard_fab2(sch_1):page169_i86@mstr_discrete.cap~
(chips)',
 PATH='I86',
 DRAWING='@BASEBOARD_FAB2_LIB.BASEBOARD_FAB2(SCH_1):PAGE169',
 TOLERANCE='5%',
 SEC_TYPE='0402LF',
 MATERIAL='COG',
 BOM_COST='SM_HM',
 PHYS_PAGE='169',
 XY='(-4475,1425)',
 ROT='0',
 VER='1',
 VALUE='47.0PF',
 PACK_TYPE='0402LF',
 PART_NUMBER='A36095-025',
 LOCATION='C9G20',
 ROOM='BMC_VOLT_MONITOR',
 SEC='1',
 CDS_LIB='mstr_discrete',
 CDS_PART_NAME='CAP_0402LF-47.0PF,50V,5%,COG,AA',
 VOLTAGE='50V',
 PRIM_FILE='./archive_libs/mstr_discrete/cap/chips/chips.prt';

PART_NAME
 C9G21 'CAP_0402LF-47.0PF,50V,5%,COG,AA':
 ROOM='BMC_VOLT_MONITOR';

SECTION_NUMBER 1
 '@BASEBOARD_FAB2_LIB.BASEBOARD_FAB2(SCH_1):PAGE169_I68@MSTR_DISCRETE.CAP(CHIPS)':
 C_PATH='@baseboard_fab2_lib.baseboard_fab2(sch_1):page169_i68@mstr_discrete.cap~
(chips)',
 P_PATH='@baseboard_fab2_lib.baseboard_fab2(sch_1):page169_i68@mstr_discrete.cap~
(chips)',
 PATH='I68',
 DRAWING='@BASEBOARD_FAB2_LIB.BASEBOARD_FAB2(SCH_1):PAGE169',
 TOLERANCE='5%',
 SEC_TYPE='0402LF',
 MATERIAL='COG',
 BOM_COST='SM_HM',
 PHYS_PAGE='169',
 XY='(-2500,1350)',
 ROT='0',
 VER='1',
 VALUE='47.0PF',
 PACK_TYPE='0402LF',
 PART_NUMBER='A36095-025',
 LOCATION='C9G21',
 ROOM='BMC_VOLT_MONITOR',
 SEC='1',
 CDS_LIB='mstr_discrete',
 CDS_PART_NAME='CAP_0402LF-47.0PF,50V,5%,COG,AA',
 VOLTAGE='50V',
 PRIM_FILE='./archive_libs/mstr_discrete/cap/chips/chips.prt';

PART_NAME
 C9G22 'CAP_0402LF-10.0PF,50V,5%,COG,AA':
 ROOM='BMC_VOLT_MONITOR';

SECTION_NUMBER 1
 '@BASEBOARD_FAB2_LIB.BASEBOARD_FAB2(SCH_1):PAGE169_I108@MSTR_DISCRETE.CAP(CHIPS)':
 C_PATH='@baseboard_fab2_lib.baseboard_fab2(sch_1):page169_i108@mstr_discrete.ca~
p(chips)',
 P_PATH='@baseboard_fab2_lib.baseboard_fab2(sch_1):page169_i108@mstr_discrete.ca~
p(chips)',
 PATH='I108',
 DRAWING='@BASEBOARD_FAB2_LIB.BASEBOARD_FAB2(SCH_1):PAGE169',
 TOLERANCE='5%',
 SEC_TYPE='0402LF',
 MATERIAL='COG',
 BOM_COST='SM_HM',
 PHYS_PAGE='169',
 XY='(800,2700)',
 ROT='0',
 VER='1',
 VALUE='10.0PF',
 PACK_TYPE='0402LF',
 PART_NUMBER='A36094-025',
 LOCATION='C9G22',
 ROOM='BMC_VOLT_MONITOR',
 SEC='1',
 CDS_LIB='mstr_discrete',
 CDS_PART_NAME='CAP_0402LF-10.0PF,50V,5%,COG,AA',
 VOLTAGE='50V',
 PRIM_FILE='./archive_libs/mstr_discrete/cap/chips/chips.prt';

PART_NAME
 C9L1 'CAP_A_0402V-0.01UF,25V,10%,X7RA':
 ROOM='DDR4_CH_M1';

SECTION_NUMBER 1
 '@BASEBOARD_FAB2_LIB.BASEBOARD_FAB2(SCH_1):PAGE88_I177@DEV_DISCRETE.CAP_A(CHIPS)':
 C_PATH='@baseboard_fab2_lib.baseboard_fab2(sch_1):page88_i177@dev_discrete.cap_~
a(chips)',
 P_PATH='@baseboard_fab2_lib.baseboard_fab2(sch_1):page88_i177@dev_discrete.cap_~
a(chips)',
 PATH='I177',
 DRAWING='@BASEBOARD_FAB2_LIB.BASEBOARD_FAB2(SCH_1):PAGE88',
 TOLERANCE='10%',
 SEC_TYPE='0402V',
 MATERIAL='X7R',
 BOM_COST='MEM',
 PHYS_PAGE='88',
 XY='(-4650,1400)',
 ROT='2',
 VER='1',
 VALUE='0.01UF',
 PACK_TYPE='0402V',
 PART_NUMBER='A36096-045',
 LOCATION='C9L1',
 ROOM='DDR4_CH_M1',
 SEC='1',
 CDS_LIB='dev_discrete',
 CDS_PART_NAME='CAP_A_0402V-0.01UF,25V,10%,X7RA',
 VOLTAGE='25V',
 PRIM_FILE='./archive_libs/discrete/cap_a/chips/chips.prt';

PART_NAME
 C9L2 'CAPP_3018-470UF,2.5V,20%,ALUM,A':
 GROUP='PWR_BULK_CAP',
 ROOM='VDDQ_KLM_PWR_VR';

SECTION_NUMBER 1
 '@BASEBOARD_FAB2_LIB.BASEBOARD_FAB2(SCH_1):PAGE228_I78@MSTR_DISCRETE.CAPP(CHIPS)':
 C_PATH='@baseboard_fab2_lib.baseboard_fab2(sch_1):page228_i78@mstr_discrete.cap~
p(chips)',
 P_PATH='@baseboard_fab2_lib.baseboard_fab2(sch_1):page228_i78@mstr_discrete.cap~
p(chips)',
 PATH='I78',
 DRAWING='@BASEBOARD_FAB2_LIB.BASEBOARD_FAB2(SCH_1):PAGE228',
 TOLERANCE='20%',
 SEC_TYPE='3018',
 MATERIAL='ALUM',
 PHYS_PAGE='228',
 XY='(3800,-500)',
 ROT='0',
 VER='1',
 VALUE='470UF',
 PACK_TYPE='3018',
 PART_NUMBER='699013-049',
 LOCATION='C9L2',
 ROOM='VDDQ_KLM_PWR_VR',
 GROUP='PWR_BULK_CAP',
 SEC='1',
 CDS_LIB='mstr_discrete',
 CDS_PART_NAME='CAPP_3018-470UF,2.5V,20%,ALUM,A',
 VOLTAGE='2.5V',
 PRIM_FILE='./archive_libs/mstr_discrete/capp/chips/chips.prt';

PART_NAME
 C9L3 'CAP_A_0402V-0.01UF,25V,10%,X7RA':
 ROOM='MEM';

SECTION_NUMBER 1
 '@BASEBOARD_FAB2_LIB.BASEBOARD_FAB2(SCH_1):PAGE100_I46@DEV_DISCRETE.CAP_A(CHIPS)':
 C_PATH='@baseboard_fab2_lib.baseboard_fab2(sch_1):page100_i46@dev_discrete.cap_~
a(chips)',
 P_PATH='@baseboard_fab2_lib.baseboard_fab2(sch_1):page100_i46@dev_discrete.cap_~
a(chips)',
 PATH='I46',
 DRAWING='@BASEBOARD_FAB2_LIB.BASEBOARD_FAB2(SCH_1):PAGE100',
 TOLERANCE='10%',
 SEC_TYPE='0402V',
 MATERIAL='X7R',
 BOM_COST='SM_CONTROLLER',
 PHYS_PAGE='100',
 XY='(2450,1650)',
 ROT='0',
 VER='1',
 VALUE='0.01UF',
 PACK_TYPE='0402V',
 PART_NUMBER='A36096-045',
 LOCATION='C9L3',
 ROOM='MEM',
 SEC='1',
 CDS_LIB='dev_discrete',
 CDS_PART_NAME='CAP_A_0402V-0.01UF,25V,10%,X7RA',
 VOLTAGE='25V',
 PRIM_FILE='./archive_libs/discrete/cap_a/chips/chips.prt';

PART_NAME
 C9L4 'CAPP_3018-470UF,2.5V,20%,ALUM,A':
 GROUP='PWR_BULK_CAP',
 ROOM='VDDQ_KLM_PWR_VR';

SECTION_NUMBER 1
 '@BASEBOARD_FAB2_LIB.BASEBOARD_FAB2(SCH_1):PAGE228_I77@MSTR_DISCRETE.CAPP(CHIPS)':
 C_PATH='@baseboard_fab2_lib.baseboard_fab2(sch_1):page228_i77@mstr_discrete.cap~
p(chips)',
 P_PATH='@baseboard_fab2_lib.baseboard_fab2(sch_1):page228_i77@mstr_discrete.cap~
p(chips)',
 PATH='I77',
 DRAWING='@BASEBOARD_FAB2_LIB.BASEBOARD_FAB2(SCH_1):PAGE228',
 TOLERANCE='20%',
 SEC_TYPE='3018',
 MATERIAL='ALUM',
 PHYS_PAGE='228',
 XY='(3500,-500)',
 ROT='0',
 VER='1',
 VALUE='470UF',
 PACK_TYPE='3018',
 PART_NUMBER='699013-049',
 LOCATION='C9L4',
 ROOM='VDDQ_KLM_PWR_VR',
 GROUP='PWR_BULK_CAP',
 SEC='1',
 CDS_LIB='mstr_discrete',
 CDS_PART_NAME='CAPP_3018-470UF,2.5V,20%,ALUM,A',
 VOLTAGE='2.5V',
 PRIM_FILE='./archive_libs/mstr_discrete/capp/chips/chips.prt';

PART_NAME
 C9L5 'CAP_0805-10UF,16V,10%,X6S,C953A':
 ROOM='VDDQ_KLM_PWR_VR';

SECTION_NUMBER 1
 '@BASEBOARD_FAB2_LIB.BASEBOARD_FAB2(SCH_1):PAGE227_I80@MSTR_DISCRETE.CAP(CHIPS)':
 C_PATH='@baseboard_fab2_lib.baseboard_fab2(sch_1):page227_i80@mstr_discrete.cap~
(chips)',
 P_PATH='@baseboard_fab2_lib.baseboard_fab2(sch_1):page227_i80@mstr_discrete.cap~
(chips)',
 PATH='I80',
 DRAWING='@BASEBOARD_FAB2_LIB.BASEBOARD_FAB2(SCH_1):PAGE227',
 TOLERANCE='10%',
 SEC_TYPE='0805',
 MATERIAL='X6S',
 PHYS_PAGE='227',
 XY='(-1625,250)',
 ROT='0',
 VER='1',
 VALUE='10UF',
 PACK_TYPE='0805',
 PART_NUMBER='C95333-007',
 LOCATION='C9L5',
 ROOM='VDDQ_KLM_PWR_VR',
 SEC='1',
 CDS_LIB='mstr_discrete',
 CDS_PART_NAME='CAP_0805-10UF,16V,10%,X6S,C953A',
 VOLTAGE='16V',
 PRIM_FILE='./archive_libs/mstr_discrete/cap/chips/chips.prt';

PART_NAME
 C9L6 'CAP_0805-10UF,16V,10%,X6S,C953A':
 ROOM='VDDQ_KLM_PWR_VR';

SECTION_NUMBER 1
 '@BASEBOARD_FAB2_LIB.BASEBOARD_FAB2(SCH_1):PAGE227_I47@MSTR_DISCRETE.CAP(CHIPS)':
 C_PATH='@baseboard_fab2_lib.baseboard_fab2(sch_1):page227_i47@mstr_discrete.cap~
(chips)',
 P_PATH='@baseboard_fab2_lib.baseboard_fab2(sch_1):page227_i47@mstr_discrete.cap~
(chips)',
 PATH='I47',
 DRAWING='@BASEBOARD_FAB2_LIB.BASEBOARD_FAB2(SCH_1):PAGE227',
 TOLERANCE='10%',
 SEC_TYPE='0805',
 MATERIAL='X6S',
 PHYS_PAGE='227',
 XY='(-1700,2500)',
 ROT='0',
 VER='1',
 VALUE='10UF',
 PACK_TYPE='0805',
 PART_NUMBER='C95333-007',
 LOCATION='C9L6',
 ROOM='VDDQ_KLM_PWR_VR',
 SEC='1',
 CDS_LIB='mstr_discrete',
 CDS_PART_NAME='CAP_0805-10UF,16V,10%,X6S,C953A',
 VOLTAGE='16V',
 PRIM_FILE='./archive_libs/mstr_discrete/cap/chips/chips.prt';

PART_NAME
 C9L7 'CAP_A_0402V-0.01UF,25V,10%,X7RA':
 ROOM='DDR4_CH_L';

SECTION_NUMBER 1
 '@BASEBOARD_FAB2_LIB.BASEBOARD_FAB2(SCH_1):PAGE85_I181@DEV_DISCRETE.CAP_A(CHIPS)':
 C_PATH='@baseboard_fab2_lib.baseboard_fab2(sch_1):page85_i181@dev_discrete.cap_~
a(chips)',
 P_PATH='@baseboard_fab2_lib.baseboard_fab2(sch_1):page85_i181@dev_discrete.cap_~
a(chips)',
 PATH='I181',
 DRAWING='@BASEBOARD_FAB2_LIB.BASEBOARD_FAB2(SCH_1):PAGE85',
 TOLERANCE='10%',
 MATERIAL='X7R',
 BOM_COST='MEM',
 PHYS_PAGE='85',
 XY='(-4650,1550)',
 ROT='2',
 VER='1',
 VALUE='0.01UF',
 PACK_TYPE='0402V',
 PART_NUMBER='A36096-045',
 LOCATION='C9L7',
 ROOM='DDR4_CH_L',
 CDS_LIB='dev_discrete',
 CDS_PART_NAME='CAP_A_0402V-0.01UF,25V,10%,X7RA',
 VOLTAGE='25V',
 PRIM_FILE='./archive_libs/discrete/cap_a/chips/chips.prt';

PART_NAME
 C9L8 'CAP_A_0402V-0.01UF,25V,10%,X7RA':
 ROOM='MEM';

SECTION_NUMBER 1
 '@BASEBOARD_FAB2_LIB.BASEBOARD_FAB2(SCH_1):PAGE100_I30@DEV_DISCRETE.CAP_A(CHIPS)':
 C_PATH='@baseboard_fab2_lib.baseboard_fab2(sch_1):page100_i30@dev_discrete.cap_~
a(chips)',
 P_PATH='@baseboard_fab2_lib.baseboard_fab2(sch_1):page100_i30@dev_discrete.cap_~
a(chips)',
 PATH='I30',
 DRAWING='@BASEBOARD_FAB2_LIB.BASEBOARD_FAB2(SCH_1):PAGE100',
 TOLERANCE='10%',
 SEC_TYPE='0402V',
 MATERIAL='X7R',
 BOM_COST='SM_CONTROLLER',
 PHYS_PAGE='100',
 XY='(0,1650)',
 ROT='0',
 VER='1',
 VALUE='0.01UF',
 PACK_TYPE='0402V',
 PART_NUMBER='A36096-045',
 LOCATION='C9L8',
 ROOM='MEM',
 SEC='1',
 CDS_LIB='dev_discrete',
 CDS_PART_NAME='CAP_A_0402V-0.01UF,25V,10%,X7RA',
 VOLTAGE='25V',
 PRIM_FILE='./archive_libs/discrete/cap_a/chips/chips.prt';

PART_NAME
 C9L9 'CAPP_3018-470UF,2.5V,20%,ALUM,A':
 GROUP='PWR_BULK_CAP',
 ROOM='VDDQ_KLM_PWR_VR';

SECTION_NUMBER 1
 '@BASEBOARD_FAB2_LIB.BASEBOARD_FAB2(SCH_1):PAGE228_I75@MSTR_DISCRETE.CAPP(CHIPS)':
 C_PATH='@baseboard_fab2_lib.baseboard_fab2(sch_1):page228_i75@mstr_discrete.cap~
p(chips)',
 P_PATH='@baseboard_fab2_lib.baseboard_fab2(sch_1):page228_i75@mstr_discrete.cap~
p(chips)',
 PATH='I75',
 DRAWING='@BASEBOARD_FAB2_LIB.BASEBOARD_FAB2(SCH_1):PAGE228',
 TOLERANCE='20%',
 SEC_TYPE='3018',
 MATERIAL='ALUM',
 PHYS_PAGE='228',
 XY='(2900,-500)',
 ROT='0',
 VER='1',
 VALUE='470UF',
 PACK_TYPE='3018',
 PART_NUMBER='699013-049',
 LOCATION='C9L9',
 ROOM='VDDQ_KLM_PWR_VR',
 GROUP='PWR_BULK_CAP',
 SEC='1',
 CDS_LIB='mstr_discrete',
 CDS_PART_NAME='CAPP_3018-470UF,2.5V,20%,ALUM,A',
 VOLTAGE='2.5V',
 PRIM_FILE='./archive_libs/mstr_discrete/capp/chips/chips.prt';

PART_NAME
 C9L10 'CAP_0805-10UF,16V,10%,X6S,C953A':
 ROOM='VDDQ_KLM_PWR_VR';

SECTION_NUMBER 1
 '@BASEBOARD_FAB2_LIB.BASEBOARD_FAB2(SCH_1):PAGE227_I46@MSTR_DISCRETE.CAP(CHIPS)':
 C_PATH='@baseboard_fab2_lib.baseboard_fab2(sch_1):page227_i46@mstr_discrete.cap~
(chips)',
 P_PATH='@baseboard_fab2_lib.baseboard_fab2(sch_1):page227_i46@mstr_discrete.cap~
(chips)',
 PATH='I46',
 DRAWING='@BASEBOARD_FAB2_LIB.BASEBOARD_FAB2(SCH_1):PAGE227',
 TOLERANCE='10%',
 SEC_TYPE='0805',
 MATERIAL='X6S',
 PHYS_PAGE='227',
 XY='(-1975,2500)',
 ROT='0',
 VER='1',
 VALUE='10UF',
 PACK_TYPE='0805',
 PART_NUMBER='C95333-007',
 LOCATION='C9L10',
 ROOM='VDDQ_KLM_PWR_VR',
 SEC='1',
 CDS_LIB='mstr_discrete',
 CDS_PART_NAME='CAP_0805-10UF,16V,10%,X6S,C953A',
 VOLTAGE='16V',
 PRIM_FILE='./archive_libs/mstr_discrete/cap/chips/chips.prt';

PART_NAME
 C9L11 'CAP_0805-10UF,16V,10%,X6S,C953A':
 ROOM='VDDQ_KLM_PWR_VR';

SECTION_NUMBER 1
 '@BASEBOARD_FAB2_LIB.BASEBOARD_FAB2(SCH_1):PAGE227_I45@MSTR_DISCRETE.CAP(CHIPS)':
 C_PATH='@baseboard_fab2_lib.baseboard_fab2(sch_1):page227_i45@mstr_discrete.cap~
(chips)',
 P_PATH='@baseboard_fab2_lib.baseboard_fab2(sch_1):page227_i45@mstr_discrete.cap~
(chips)',
 PATH='I45',
 DRAWING='@BASEBOARD_FAB2_LIB.BASEBOARD_FAB2(SCH_1):PAGE227',
 TOLERANCE='10%',
 SEC_TYPE='0805',
 MATERIAL='X6S',
 PHYS_PAGE='227',
 XY='(-2250,2500)',
 ROT='0',
 VER='1',
 VALUE='10UF',
 PACK_TYPE='0805',
 PART_NUMBER='C95333-007',
 LOCATION='C9L11',
 ROOM='VDDQ_KLM_PWR_VR',
 SEC='1',
 CDS_LIB='mstr_discrete',
 CDS_PART_NAME='CAP_0805-10UF,16V,10%,X6S,C953A',
 VOLTAGE='16V',
 PRIM_FILE='./archive_libs/mstr_discrete/cap/chips/chips.prt';

PART_NAME
 C9L12 'CAPP_3018-470UF,2.5V,20%,ALUM,A':
 GROUP='PWR_BULK_CAP',
 ROOM='VDDQ_KLM_PWR_VR';

SECTION_NUMBER 1
 '@BASEBOARD_FAB2_LIB.BASEBOARD_FAB2(SCH_1):PAGE228_I76@MSTR_DISCRETE.CAPP(CHIPS)':
 C_PATH='@baseboard_fab2_lib.baseboard_fab2(sch_1):page228_i76@mstr_discrete.cap~
p(chips)',
 P_PATH='@baseboard_fab2_lib.baseboard_fab2(sch_1):page228_i76@mstr_discrete.cap~
p(chips)',
 PATH='I76',
 DRAWING='@BASEBOARD_FAB2_LIB.BASEBOARD_FAB2(SCH_1):PAGE228',
 TOLERANCE='20%',
 SEC_TYPE='3018',
 MATERIAL='ALUM',
 PHYS_PAGE='228',
 XY='(3200,-500)',
 ROT='0',
 VER='1',
 VALUE='470UF',
 PACK_TYPE='3018',
 PART_NUMBER='699013-049',
 LOCATION='C9L12',
 ROOM='VDDQ_KLM_PWR_VR',
 GROUP='PWR_BULK_CAP',
 SEC='1',
 CDS_LIB='mstr_discrete',
 CDS_PART_NAME='CAPP_3018-470UF,2.5V,20%,ALUM,A',
 VOLTAGE='2.5V',
 PRIM_FILE='./archive_libs/mstr_discrete/capp/chips/chips.prt';

PART_NAME
 C9L13 'CAP_0805-10UF,16V,10%,X6S,C953A':
 ROOM='VDDQ_KLM_PWR_VR';

SECTION_NUMBER 1
 '@BASEBOARD_FAB2_LIB.BASEBOARD_FAB2(SCH_1):PAGE227_I81@MSTR_DISCRETE.CAP(CHIPS)':
 C_PATH='@baseboard_fab2_lib.baseboard_fab2(sch_1):page227_i81@mstr_discrete.cap~
(chips)',
 P_PATH='@baseboard_fab2_lib.baseboard_fab2(sch_1):page227_i81@mstr_discrete.cap~
(chips)',
 PATH='I81',
 DRAWING='@BASEBOARD_FAB2_LIB.BASEBOARD_FAB2(SCH_1):PAGE227',
 TOLERANCE='10%',
 SEC_TYPE='0805',
 MATERIAL='X6S',
 PHYS_PAGE='227',
 XY='(-1900,250)',
 ROT='0',
 VER='1',
 VALUE='10UF',
 PACK_TYPE='0805',
 PART_NUMBER='C95333-007',
 LOCATION='C9L13',
 ROOM='VDDQ_KLM_PWR_VR',
 SEC='1',
 CDS_LIB='mstr_discrete',
 CDS_PART_NAME='CAP_0805-10UF,16V,10%,X6S,C953A',
 VOLTAGE='16V',
 PRIM_FILE='./archive_libs/mstr_discrete/cap/chips/chips.prt';

PART_NAME
 C9L14 'CAP_0805-10UF,16V,10%,X6S,C953A':
 ROOM='VDDQ_KLM_PWR_VR';

SECTION_NUMBER 1
 '@BASEBOARD_FAB2_LIB.BASEBOARD_FAB2(SCH_1):PAGE227_I84@MSTR_DISCRETE.CAP(CHIPS)':
 C_PATH='@baseboard_fab2_lib.baseboard_fab2(sch_1):page227_i84@mstr_discrete.cap~
(chips)',
 P_PATH='@baseboard_fab2_lib.baseboard_fab2(sch_1):page227_i84@mstr_discrete.cap~
(chips)',
 PATH='I84',
 DRAWING='@BASEBOARD_FAB2_LIB.BASEBOARD_FAB2(SCH_1):PAGE227',
 TOLERANCE='10%',
 SEC_TYPE='0805',
 MATERIAL='X6S',
 PHYS_PAGE='227',
 XY='(-2175,250)',
 ROT='0',
 VER='1',
 VALUE='10UF',
 PACK_TYPE='0805',
 PART_NUMBER='C95333-007',
 LOCATION='C9L14',
 ROOM='VDDQ_KLM_PWR_VR',
 SEC='1',
 CDS_LIB='mstr_discrete',
 CDS_PART_NAME='CAP_0805-10UF,16V,10%,X6S,C953A',
 VOLTAGE='16V',
 PRIM_FILE='./archive_libs/mstr_discrete/cap/chips/chips.prt';

PART_NAME
 C9M1 'CAP_A_0402V-0.01UF,25V,10%,X7RA':
 ROOM='DDR4_CH_C';

SECTION_NUMBER 1
 '@BASEBOARD_FAB2_LIB.BASEBOARD_FAB2(SCH_1):PAGE84_I4@DEV_DISCRETE.CAP_A(CHIPS)':
 C_PATH='@baseboard_fab2_lib.baseboard_fab2(sch_1):page84_i4@dev_discrete.cap_a(~
chips)',
 P_PATH='@baseboard_fab2_lib.baseboard_fab2(sch_1):page84_i4@dev_discrete.cap_a(~
chips)',
 PATH='I4',
 DRAWING='@BASEBOARD_FAB2_LIB.BASEBOARD_FAB2(SCH_1):PAGE84',
 TOLERANCE='10%',
 MATERIAL='X7R',
 BOM_COST='MEM',
 PHYS_PAGE='84',
 XY='(-3000,1125)',
 ROT='2',
 VER='1',
 VALUE='0.01UF',
 PACK_TYPE='0402V',
 PART_NUMBER='A36096-045',
 LOCATION='C9M1',
 ROOM='DDR4_CH_C',
 CDS_LIB='dev_discrete',
 CDS_PART_NAME='CAP_A_0402V-0.01UF,25V,10%,X7RA',
 VOLTAGE='25V',
 PRIM_FILE='./archive_libs/discrete/cap_a/chips/chips.prt';

PART_NAME
 C9M2 'CAP_A_0402V-0.01UF,25V,10%,X7RA':
 ROOM='MEM';

SECTION_NUMBER 1
 '@BASEBOARD_FAB2_LIB.BASEBOARD_FAB2(SCH_1):PAGE100_I15@DEV_DISCRETE.CAP_A(CHIPS)':
 C_PATH='@baseboard_fab2_lib.baseboard_fab2(sch_1):page100_i15@dev_discrete.cap_~
a(chips)',
 P_PATH='@baseboard_fab2_lib.baseboard_fab2(sch_1):page100_i15@dev_discrete.cap_~
a(chips)',
 PATH='I15',
 DRAWING='@BASEBOARD_FAB2_LIB.BASEBOARD_FAB2(SCH_1):PAGE100',
 TOLERANCE='10%',
 SEC_TYPE='0402V',
 MATERIAL='X7R',
 BOM_COST='SM_CONTROLLER',
 PHYS_PAGE='100',
 XY='(-2350,1650)',
 ROT='0',
 VER='1',
 VALUE='0.01UF',
 PACK_TYPE='0402V',
 PART_NUMBER='A36096-045',
 LOCATION='C9M2',
 ROOM='MEM',
 SEC='1',
 CDS_LIB='dev_discrete',
 CDS_PART_NAME='CAP_A_0402V-0.01UF,25V,10%,X7RA',
 VOLTAGE='25V',
 PRIM_FILE='./archive_libs/discrete/cap_a/chips/chips.prt';

PART_NAME
 C9M3 'CAPP_3018-68UF,16V,20%,TANT,72A':;

SECTION_NUMBER 1
 '@BASEBOARD_FAB2_LIB.BASEBOARD_FAB2(SCH_1):PAGE195_I99@MSTR_DISCRETE.CAPP(CHIPS)':
 C_PATH='@baseboard_fab2_lib.baseboard_fab2(sch_1):page195_i99@mstr_discrete.cap~
p(chips)',
 P_PATH='@baseboard_fab2_lib.baseboard_fab2(sch_1):page195_i99@mstr_discrete.cap~
p(chips)',
 PATH='I99',
 DRAWING='@BASEBOARD_FAB2_LIB.BASEBOARD_FAB2(SCH_1):PAGE195',
 TOLERANCE='20%',
 SEC_TYPE='3018',
 MATERIAL='TANT',
 PHYS_PAGE='195',
 XY='(-5750,775)',
 ROT='0',
 VER='1',
 VALUE='68UF',
 PACK_TYPE='3018',
 PART_NUMBER='724613-112',
 LOCATION='C9M3',
 SEC='1',
 CDS_LIB='mstr_discrete',
 CDS_PART_NAME='CAPP_3018-68UF,16V,20%,TANT,72A',
 VOLTAGE='16V',
 PRIM_FILE='./archive_libs/mstr_discrete/capp/chips/chips.prt';

PART_NAME
 C9M4 'CAP_0805-10UF,16V,10%,X6S,C953A':
 ROOM='CPU_FANS';

SECTION_NUMBER 1
 '@BASEBOARD_FAB2_LIB.BASEBOARD_FAB2(SCH_1):PAGE161_I27@MSTR_DISCRETE.CAP(CHIPS)':
 C_PATH='@baseboard_fab2_lib.baseboard_fab2(sch_1):page161_i27@mstr_discrete.cap~
(chips)',
 P_PATH='@baseboard_fab2_lib.baseboard_fab2(sch_1):page161_i27@mstr_discrete.cap~
(chips)',
 PATH='I27',
 DRAWING='@BASEBOARD_FAB2_LIB.BASEBOARD_FAB2(SCH_1):PAGE161',
 TOLERANCE='10%',
 SEC_TYPE='0805',
 MATERIAL='X6S',
 BOM_COST='SM_THERM',
 PHYS_PAGE='161',
 XY='(-1300,2275)',
 ROT='0',
 VER='1',
 VALUE='10UF',
 PACK_TYPE='0805',
 PART_NUMBER='C95333-007',
 LOCATION='C9M4',
 ROOM='CPU_FANS',
 SEC='1',
 CDS_LIB='mstr_discrete',
 CDS_PART_NAME='CAP_0805-10UF,16V,10%,X6S,C953A',
 VOLTAGE='16V',
 PRIM_FILE='./archive_libs/mstr_discrete/cap/chips/chips.prt';

PART_NAME
 C9M5 'CAP_A_0402V-0.1UF,16V,10%,X7R,A':
 ROOM='CPU_FANS';

SECTION_NUMBER 1
 '@BASEBOARD_FAB2_LIB.BASEBOARD_FAB2(SCH_1):PAGE161_I26@DEV_DISCRETE.CAP_A(CHIPS)':
 C_PATH='@baseboard_fab2_lib.baseboard_fab2(sch_1):page161_i26@dev_discrete.cap_~
a(chips)',
 P_PATH='@baseboard_fab2_lib.baseboard_fab2(sch_1):page161_i26@dev_discrete.cap_~
a(chips)',
 PATH='I26',
 DRAWING='@BASEBOARD_FAB2_LIB.BASEBOARD_FAB2(SCH_1):PAGE161',
 TOLERANCE='10%',
 SEC_TYPE='0402V',
 MATERIAL='X7R',
 BOM_COST='SM_THERM',
 PHYS_PAGE='161',
 XY='(-1000,2275)',
 ROT='0',
 VER='1',
 VALUE='0.1UF',
 PACK_TYPE='0402V',
 PART_NUMBER='A36096-030',
 LOCATION='C9M5',
 ROOM='CPU_FANS',
 SEC='1',
 CDS_LIB='dev_discrete',
 CDS_PART_NAME='CAP_A_0402V-0.1UF,16V,10%,X7R,A',
 VOLTAGE='16V',
 PRIM_FILE='./archive_libs/discrete/cap_a/chips/chips.prt';

PART_NAME
 C9M6 'CAP_A_0402V-0.1UF,16V,10%,X7R,A':
 ROOM='P12V_FAN_PWR_SWITCH';

SECTION_NUMBER 1
 '@BASEBOARD_FAB2_LIB.BASEBOARD_FAB2(SCH_1):PAGE198_I67@DEV_DISCRETE.CAP_A(CHIPS)':
 C_PATH='@baseboard_fab2_lib.baseboard_fab2(sch_1):page198_i67@dev_discrete.cap_~
a(chips)',
 P_PATH='@baseboard_fab2_lib.baseboard_fab2(sch_1):page198_i67@dev_discrete.cap_~
a(chips)',
 PATH='I67',
 DRAWING='@BASEBOARD_FAB2_LIB.BASEBOARD_FAB2(SCH_1):PAGE198',
 TOLERANCE='10%',
 SEC_TYPE='0402V',
 MATERIAL='X7R',
 PHYS_PAGE='198',
 XY='(-3775,2150)',
 ROT='0',
 VER='1',
 VALUE='0.1UF',
 PACK_TYPE='0402V',
 PART_NUMBER='A36096-030',
 LOCATION='C9M6',
 ROOM='P12V_FAN_PWR_SWITCH',
 SEC='1',
 CDS_LIB='dev_discrete',
 CDS_PART_NAME='CAP_A_0402V-0.1UF,16V,10%,X7R,A',
 VOLTAGE='16V',
 PRIM_FILE='./archive_libs/discrete/cap_a/chips/chips.prt';

PART_NAME
 C9M7 'CAP_A_0402V-0.1UF,16V,10%,X7R,A':
 ROOM='SMB_PE_HP_CPU1';

SECTION_NUMBER 1
 '@BASEBOARD_FAB2_LIB.BASEBOARD_FAB2(SCH_1):PAGE163_I12@DEV_DISCRETE.CAP_A(CHIPS)':
 C_PATH='@baseboard_fab2_lib.baseboard_fab2(sch_1):page163_i12@dev_discrete.cap_~
a(chips)',
 P_PATH='@baseboard_fab2_lib.baseboard_fab2(sch_1):page163_i12@dev_discrete.cap_~
a(chips)',
 PATH='I12',
 DRAWING='@BASEBOARD_FAB2_LIB.BASEBOARD_FAB2(SCH_1):PAGE163',
 TOLERANCE='10%',
 SEC_TYPE='0402V',
 MATERIAL='X7R',
 PHYS_PAGE='163',
 XY='(-1150,3850)',
 ROT='2',
 VER='1',
 VALUE='0.1UF',
 PACK_TYPE='0402V',
 PART_NUMBER='A36096-030',
 LOCATION='C9M7',
 ROOM='SMB_PE_HP_CPU1',
 SEC='1',
 CDS_LIB='dev_discrete',
 CDS_PART_NAME='CAP_A_0402V-0.1UF,16V,10%,X7R,A',
 VOLTAGE='16V',
 PRIM_FILE='./archive_libs/discrete/cap_a/chips/chips.prt';

PART_NAME
 C9M8 'CAP_A_0402V-0.1UF,16V,10%,X7R,A':
 ROOM='SMB_PE_HP_CPU1';

SECTION_NUMBER 1
 '@BASEBOARD_FAB2_LIB.BASEBOARD_FAB2(SCH_1):PAGE163_I10@DEV_DISCRETE.CAP_A(CHIPS)':
 C_PATH='@baseboard_fab2_lib.baseboard_fab2(sch_1):page163_i10@dev_discrete.cap_~
a(chips)',
 P_PATH='@baseboard_fab2_lib.baseboard_fab2(sch_1):page163_i10@dev_discrete.cap_~
a(chips)',
 PATH='I10',
 DRAWING='@BASEBOARD_FAB2_LIB.BASEBOARD_FAB2(SCH_1):PAGE163',
 TOLERANCE='10%',
 SEC_TYPE='0402V',
 MATERIAL='X7R',
 PHYS_PAGE='163',
 XY='(-1800,3850)',
 ROT='0',
 VER='1',
 VALUE='0.1UF',
 PACK_TYPE='0402V',
 PART_NUMBER='A36096-030',
 LOCATION='C9M8',
 ROOM='SMB_PE_HP_CPU1',
 SEC='1',
 CDS_LIB='dev_discrete',
 CDS_PART_NAME='CAP_A_0402V-0.1UF,16V,10%,X7R,A',
 VOLTAGE='16V',
 PRIM_FILE='./archive_libs/discrete/cap_a/chips/chips.prt';

PART_NAME
 C9M9 'CAP_A_0402V-0.1UF,16V,10%,X7R,A':
 ROOM='P12V_FAN_PWR_SWITCH';

SECTION_NUMBER 1
 '@BASEBOARD_FAB2_LIB.BASEBOARD_FAB2(SCH_1):PAGE198_I76@DEV_DISCRETE.CAP_A(CHIPS)':
 C_PATH='@baseboard_fab2_lib.baseboard_fab2(sch_1):page198_i76@dev_discrete.cap_~
a(chips)',
 P_PATH='@baseboard_fab2_lib.baseboard_fab2(sch_1):page198_i76@dev_discrete.cap_~
a(chips)',
 PATH='I76',
 DRAWING='@BASEBOARD_FAB2_LIB.BASEBOARD_FAB2(SCH_1):PAGE198',
 TOLERANCE='10%',
 SEC_TYPE='0402V',
 MATERIAL='X7R',
 BOM_COST='PWR_SWITCH',
 PHYS_PAGE='198',
 XY='(-825,2225)',
 ROT='0',
 VER='1',
 VALUE='0.1UF',
 PACK_TYPE='0402V',
 PART_NUMBER='A36096-030',
 LOCATION='C9M9',
 ROOM='P12V_FAN_PWR_SWITCH',
 SEC='1',
 CDS_LIB='dev_discrete',
 CDS_PART_NAME='CAP_A_0402V-0.1UF,16V,10%,X7R,A',
 VOLTAGE='16V',
 PRIM_FILE='./archive_libs/discrete/cap_a/chips/chips.prt';

PART_NAME
 C9M10 'CAP_0805-10UF,16V,10%,X6S,C953A':
 ROOM='P12V_FAN_PWR_SWITCH';

SECTION_NUMBER 1
 '@BASEBOARD_FAB2_LIB.BASEBOARD_FAB2(SCH_1):PAGE198_I74@MSTR_DISCRETE.CAP(CHIPS)':
 C_PATH='@baseboard_fab2_lib.baseboard_fab2(sch_1):page198_i74@mstr_discrete.cap~
(chips)',
 P_PATH='@baseboard_fab2_lib.baseboard_fab2(sch_1):page198_i74@mstr_discrete.cap~
(chips)',
 PATH='I74',
 DRAWING='@BASEBOARD_FAB2_LIB.BASEBOARD_FAB2(SCH_1):PAGE198',
 TOLERANCE='10%',
 SEC_TYPE='0805',
 MATERIAL='X6S',
 PHYS_PAGE='198',
 XY='(-1150,2225)',
 ROT='0',
 VER='1',
 VALUE='10UF',
 PACK_TYPE='0805',
 PART_NUMBER='C95333-007',
 LOCATION='C9M10',
 ROOM='P12V_FAN_PWR_SWITCH',
 SEC='1',
 CDS_LIB='mstr_discrete',
 CDS_PART_NAME='CAP_0805-10UF,16V,10%,X6S,C953A',
 VOLTAGE='16V',
 PRIM_FILE='./archive_libs/mstr_discrete/cap/chips/chips.prt';

PART_NAME
 C9N1 'CAP_0402-0.22UF,16V,10%,X7R,A3A':
 ROOM='IO_SLOT';

SECTION_NUMBER 1
 '@BASEBOARD_FAB2_LIB.BASEBOARD_FAB2(SCH_1):PAGE182_I40@MSTR_DISCRETE.CAP(CHIPS)':
 C_PATH='@baseboard_fab2_lib.baseboard_fab2(sch_1):page182_i40@mstr_discrete.cap~
(chips)',
 P_PATH='@baseboard_fab2_lib.baseboard_fab2(sch_1):page182_i40@mstr_discrete.cap~
(chips)',
 PATH='I40',
 DRAWING='@BASEBOARD_FAB2_LIB.BASEBOARD_FAB2(SCH_1):PAGE182',
 TOLERANCE='10%',
 SEC_TYPE='0402',
 MATERIAL='X7R',
 BOM_COST='IO_SLOT',
 PHYS_PAGE='182',
 XY='(-2925,1175)',
 ROT='0',
 VER='2',
 VALUE='0.22UF',
 PACK_TYPE='0402',
 PART_NUMBER='A36096-155',
 LOCATION='C9N1',
 ROOM='IO_SLOT',
 SEC='1',
 CDS_LIB='mstr_discrete',
 CDS_PART_NAME='CAP_0402-0.22UF,16V,10%,X7R,A3A',
 VOLTAGE='16V',
 PRIM_FILE='./archive_libs/mstr_discrete/cap/chips/chips.prt';

PART_NAME
 C9N2 'CAP_0402-0.22UF,16V,10%,X7R,A3A':
 ROOM='IO_SLOT';

SECTION_NUMBER 1
 '@BASEBOARD_FAB2_LIB.BASEBOARD_FAB2(SCH_1):PAGE182_I36@MSTR_DISCRETE.CAP(CHIPS)':
 C_PATH='@baseboard_fab2_lib.baseboard_fab2(sch_1):page182_i36@mstr_discrete.cap~
(chips)',
 P_PATH='@baseboard_fab2_lib.baseboard_fab2(sch_1):page182_i36@mstr_discrete.cap~
(chips)',
 PATH='I36',
 DRAWING='@BASEBOARD_FAB2_LIB.BASEBOARD_FAB2(SCH_1):PAGE182',
 TOLERANCE='10%',
 SEC_TYPE='0402',
 MATERIAL='X7R',
 BOM_COST='IO_SLOT',
 PHYS_PAGE='182',
 XY='(-3400,1125)',
 ROT='0',
 VER='2',
 VALUE='0.22UF',
 PACK_TYPE='0402',
 PART_NUMBER='A36096-155',
 LOCATION='C9N2',
 ROOM='IO_SLOT',
 SEC='1',
 CDS_LIB='mstr_discrete',
 CDS_PART_NAME='CAP_0402-0.22UF,16V,10%,X7R,A3A',
 VOLTAGE='16V',
 PRIM_FILE='./archive_libs/mstr_discrete/cap/chips/chips.prt';

PART_NAME
 C9N3 'CAP_0402-0.22UF,16V,10%,X7R,A3A':
 ROOM='IO_SLOT';

SECTION_NUMBER 1
 '@BASEBOARD_FAB2_LIB.BASEBOARD_FAB2(SCH_1):PAGE182_I47@MSTR_DISCRETE.CAP(CHIPS)':
 C_PATH='@baseboard_fab2_lib.baseboard_fab2(sch_1):page182_i47@mstr_discrete.cap~
(chips)',
 P_PATH='@baseboard_fab2_lib.baseboard_fab2(sch_1):page182_i47@mstr_discrete.cap~
(chips)',
 PATH='I47',
 DRAWING='@BASEBOARD_FAB2_LIB.BASEBOARD_FAB2(SCH_1):PAGE182',
 TOLERANCE='10%',
 SEC_TYPE='0402',
 MATERIAL='X7R',
 BOM_COST='IO_SLOT',
 PHYS_PAGE='182',
 XY='(-2925,2025)',
 ROT='0',
 VER='2',
 VALUE='0.22UF',
 PACK_TYPE='0402',
 PART_NUMBER='A36096-155',
 LOCATION='C9N3',
 ROOM='IO_SLOT',
 SEC='1',
 CDS_LIB='mstr_discrete',
 CDS_PART_NAME='CAP_0402-0.22UF,16V,10%,X7R,A3A',
 VOLTAGE='16V',
 PRIM_FILE='./archive_libs/mstr_discrete/cap/chips/chips.prt';

PART_NAME
 C9N4 'CAP_0402-0.22UF,16V,10%,X7R,A3A':
 ROOM='IO_SLOT';

SECTION_NUMBER 1
 '@BASEBOARD_FAB2_LIB.BASEBOARD_FAB2(SCH_1):PAGE182_I44@MSTR_DISCRETE.CAP(CHIPS)':
 C_PATH='@baseboard_fab2_lib.baseboard_fab2(sch_1):page182_i44@mstr_discrete.cap~
(chips)',
 P_PATH='@baseboard_fab2_lib.baseboard_fab2(sch_1):page182_i44@mstr_discrete.cap~
(chips)',
 PATH='I44',
 DRAWING='@BASEBOARD_FAB2_LIB.BASEBOARD_FAB2(SCH_1):PAGE182',
 TOLERANCE='10%',
 SEC_TYPE='0402',
 MATERIAL='X7R',
 BOM_COST='IO_SLOT',
 PHYS_PAGE='182',
 XY='(-3400,1975)',
 ROT='0',
 VER='2',
 VALUE='0.22UF',
 PACK_TYPE='0402',
 PART_NUMBER='A36096-155',
 LOCATION='C9N4',
 ROOM='IO_SLOT',
 SEC='1',
 CDS_LIB='mstr_discrete',
 CDS_PART_NAME='CAP_0402-0.22UF,16V,10%,X7R,A3A',
 VOLTAGE='16V',
 PRIM_FILE='./archive_libs/mstr_discrete/cap/chips/chips.prt';

PART_NAME
 C9N5 'CAP_0402-0.22UF,16V,10%,X7R,A3A':
 ROOM='IO_SLOT';

SECTION_NUMBER 1
 '@BASEBOARD_FAB2_LIB.BASEBOARD_FAB2(SCH_1):PAGE182_I45@MSTR_DISCRETE.CAP(CHIPS)':
 C_PATH='@baseboard_fab2_lib.baseboard_fab2(sch_1):page182_i45@mstr_discrete.cap~
(chips)',
 P_PATH='@baseboard_fab2_lib.baseboard_fab2(sch_1):page182_i45@mstr_discrete.cap~
(chips)',
 PATH='I45',
 DRAWING='@BASEBOARD_FAB2_LIB.BASEBOARD_FAB2(SCH_1):PAGE182',
 TOLERANCE='10%',
 SEC_TYPE='0402',
 MATERIAL='X7R',
 BOM_COST='IO_SLOT',
 PHYS_PAGE='182',
 XY='(-2925,1675)',
 ROT='0',
 VER='2',
 VALUE='0.22UF',
 PACK_TYPE='0402',
 PART_NUMBER='A36096-155',
 LOCATION='C9N5',
 ROOM='IO_SLOT',
 SEC='1',
 CDS_LIB='mstr_discrete',
 CDS_PART_NAME='CAP_0402-0.22UF,16V,10%,X7R,A3A',
 VOLTAGE='16V',
 PRIM_FILE='./archive_libs/mstr_discrete/cap/chips/chips.prt';

PART_NAME
 C9N6 'CAP_0402-0.22UF,16V,10%,X7R,A3A':
 ROOM='IO_SLOT';

SECTION_NUMBER 1
 '@BASEBOARD_FAB2_LIB.BASEBOARD_FAB2(SCH_1):PAGE182_I42@MSTR_DISCRETE.CAP(CHIPS)':
 C_PATH='@baseboard_fab2_lib.baseboard_fab2(sch_1):page182_i42@mstr_discrete.cap~
(chips)',
 P_PATH='@baseboard_fab2_lib.baseboard_fab2(sch_1):page182_i42@mstr_discrete.cap~
(chips)',
 PATH='I42',
 DRAWING='@BASEBOARD_FAB2_LIB.BASEBOARD_FAB2(SCH_1):PAGE182',
 TOLERANCE='10%',
 SEC_TYPE='0402',
 MATERIAL='X7R',
 BOM_COST='IO_SLOT',
 PHYS_PAGE='182',
 XY='(-3400,1725)',
 ROT='0',
 VER='2',
 VALUE='0.22UF',
 PACK_TYPE='0402',
 PART_NUMBER='A36096-155',
 LOCATION='C9N6',
 ROOM='IO_SLOT',
 SEC='1',
 CDS_LIB='mstr_discrete',
 CDS_PART_NAME='CAP_0402-0.22UF,16V,10%,X7R,A3A',
 VOLTAGE='16V',
 PRIM_FILE='./archive_libs/mstr_discrete/cap/chips/chips.prt';

PART_NAME
 C9N7 'CAP_0402-0.22UF,16V,10%,X7R,A3A':
 ROOM='IO_SLOT';

SECTION_NUMBER 1
 '@BASEBOARD_FAB2_LIB.BASEBOARD_FAB2(SCH_1):PAGE182_I48@MSTR_DISCRETE.CAP(CHIPS)':
 C_PATH='@baseboard_fab2_lib.baseboard_fab2(sch_1):page182_i48@mstr_discrete.cap~
(chips)',
 P_PATH='@baseboard_fab2_lib.baseboard_fab2(sch_1):page182_i48@mstr_discrete.cap~
(chips)',
 PATH='I48',
 DRAWING='@BASEBOARD_FAB2_LIB.BASEBOARD_FAB2(SCH_1):PAGE182',
 TOLERANCE='10%',
 SEC_TYPE='0402',
 MATERIAL='X7R',
 BOM_COST='IO_SLOT',
 PHYS_PAGE='182',
 XY='(-3400,2175)',
 ROT='0',
 VER='2',
 VALUE='0.22UF',
 PACK_TYPE='0402',
 PART_NUMBER='A36096-155',
 LOCATION='C9N7',
 ROOM='IO_SLOT',
 SEC='1',
 CDS_LIB='mstr_discrete',
 CDS_PART_NAME='CAP_0402-0.22UF,16V,10%,X7R,A3A',
 VOLTAGE='16V',
 PRIM_FILE='./archive_libs/mstr_discrete/cap/chips/chips.prt';

PART_NAME
 C9N8 'CAP_0402-0.22UF,16V,10%,X7R,A3A':
 ROOM='IO_SLOT';

SECTION_NUMBER 1
 '@BASEBOARD_FAB2_LIB.BASEBOARD_FAB2(SCH_1):PAGE182_I53@MSTR_DISCRETE.CAP(CHIPS)':
 C_PATH='@baseboard_fab2_lib.baseboard_fab2(sch_1):page182_i53@mstr_discrete.cap~
(chips)',
 P_PATH='@baseboard_fab2_lib.baseboard_fab2(sch_1):page182_i53@mstr_discrete.cap~
(chips)',
 PATH='I53',
 DRAWING='@BASEBOARD_FAB2_LIB.BASEBOARD_FAB2(SCH_1):PAGE182',
 TOLERANCE='10%',
 SEC_TYPE='0402',
 MATERIAL='X7R',
 BOM_COST='IO_SLOT',
 PHYS_PAGE='182',
 XY='(-2925,2375)',
 ROT='0',
 VER='2',
 VALUE='0.22UF',
 PACK_TYPE='0402',
 PART_NUMBER='A36096-155',
 LOCATION='C9N8',
 ROOM='IO_SLOT',
 SEC='1',
 CDS_LIB='mstr_discrete',
 CDS_PART_NAME='CAP_0402-0.22UF,16V,10%,X7R,A3A',
 VOLTAGE='16V',
 PRIM_FILE='./archive_libs/mstr_discrete/cap/chips/chips.prt';

PART_NAME
 C9N9 'CAP_0402-0.22UF,16V,10%,X7R,A3A':
 ROOM='IO_SLOT';

SECTION_NUMBER 1
 '@BASEBOARD_FAB2_LIB.BASEBOARD_FAB2(SCH_1):PAGE182_I52@MSTR_DISCRETE.CAP(CHIPS)':
 C_PATH='@baseboard_fab2_lib.baseboard_fab2(sch_1):page182_i52@mstr_discrete.cap~
(chips)',
 P_PATH='@baseboard_fab2_lib.baseboard_fab2(sch_1):page182_i52@mstr_discrete.cap~
(chips)',
 PATH='I52',
 DRAWING='@BASEBOARD_FAB2_LIB.BASEBOARD_FAB2(SCH_1):PAGE182',
 TOLERANCE='10%',
 SEC_TYPE='0402',
 MATERIAL='X7R',
 BOM_COST='IO_SLOT',
 PHYS_PAGE='182',
 XY='(-2925,2225)',
 ROT='0',
 VER='2',
 VALUE='0.22UF',
 PACK_TYPE='0402',
 PART_NUMBER='A36096-155',
 LOCATION='C9N9',
 ROOM='IO_SLOT',
 SEC='1',
 CDS_LIB='mstr_discrete',
 CDS_PART_NAME='CAP_0402-0.22UF,16V,10%,X7R,A3A',
 VOLTAGE='16V',
 PRIM_FILE='./archive_libs/mstr_discrete/cap/chips/chips.prt';

PART_NAME
 C9N10 'CAP_0402-0.22UF,16V,10%,X7R,A3A':
 ROOM='IO_SLOT';

SECTION_NUMBER 1
 '@BASEBOARD_FAB2_LIB.BASEBOARD_FAB2(SCH_1):PAGE182_I49@MSTR_DISCRETE.CAP(CHIPS)':
 C_PATH='@baseboard_fab2_lib.baseboard_fab2(sch_1):page182_i49@mstr_discrete.cap~
(chips)',
 P_PATH='@baseboard_fab2_lib.baseboard_fab2(sch_1):page182_i49@mstr_discrete.cap~
(chips)',
 PATH='I49',
 DRAWING='@BASEBOARD_FAB2_LIB.BASEBOARD_FAB2(SCH_1):PAGE182',
 TOLERANCE='10%',
 SEC_TYPE='0402',
 MATERIAL='X7R',
 BOM_COST='IO_SLOT',
 PHYS_PAGE='182',
 XY='(-3400,2325)',
 ROT='0',
 VER='2',
 VALUE='0.22UF',
 PACK_TYPE='0402',
 PART_NUMBER='A36096-155',
 LOCATION='C9N10',
 ROOM='IO_SLOT',
 SEC='1',
 CDS_LIB='mstr_discrete',
 CDS_PART_NAME='CAP_0402-0.22UF,16V,10%,X7R,A3A',
 VOLTAGE='16V',
 PRIM_FILE='./archive_libs/mstr_discrete/cap/chips/chips.prt';

PART_NAME
 C9N11 'CAPP_3018-470UF,2.5V,20%,ALUM,A':
 GROUP='PWR_BULK_CAP',
 ROOM='PVSA_CPU1_DECAP_VR';

SECTION_NUMBER 1
 '@BASEBOARD_FAB2_LIB.BASEBOARD_FAB2(SCH_1):PAGE210_I12@MSTR_DISCRETE.CAPP(CHIPS)':
 C_PATH='@baseboard_fab2_lib.baseboard_fab2(sch_1):page210_i12@mstr_discrete.cap~
p(chips)',
 P_PATH='@baseboard_fab2_lib.baseboard_fab2(sch_1):page210_i12@mstr_discrete.cap~
p(chips)',
 PATH='I12',
 DRAWING='@BASEBOARD_FAB2_LIB.BASEBOARD_FAB2(SCH_1):PAGE210',
 TOLERANCE='20%',
 SEC_TYPE='3018',
 MATERIAL='ALUM',
 BOM_COST='PROC_VRD_VCCIN_CPU0',
 PHYS_PAGE='210',
 XY='(-1350,1450)',
 ROT='0',
 VER='1',
 VALUE='470UF',
 PACK_TYPE='3018',
 PART_NUMBER='699013-049',
 LOCATION='C9N11',
 ROOM='PVSA_CPU1_DECAP_VR',
 GROUP='PWR_BULK_CAP',
 SEC='1',
 CDS_LIB='mstr_discrete',
 CDS_PART_NAME='CAPP_3018-470UF,2.5V,20%,ALUM,A',
 VOLTAGE='2.5V',
 PRIM_FILE='./archive_libs/mstr_discrete/capp/chips/chips.prt';

PART_NAME
 C9N12 'CAP_0402-0.22UF,16V,10%,X7R,A3A':
 ROOM='IO_SLOT';

SECTION_NUMBER 1
 '@BASEBOARD_FAB2_LIB.BASEBOARD_FAB2(SCH_1):PAGE182_I37@MSTR_DISCRETE.CAP(CHIPS)':
 C_PATH='@baseboard_fab2_lib.baseboard_fab2(sch_1):page182_i37@mstr_discrete.cap~
(chips)',
 P_PATH='@baseboard_fab2_lib.baseboard_fab2(sch_1):page182_i37@mstr_discrete.cap~
(chips)',
 PATH='I37',
 DRAWING='@BASEBOARD_FAB2_LIB.BASEBOARD_FAB2(SCH_1):PAGE182',
 TOLERANCE='10%',
 SEC_TYPE='0402',
 MATERIAL='X7R',
 BOM_COST='IO_SLOT',
 PHYS_PAGE='182',
 XY='(-3400,1275)',
 ROT='0',
 VER='2',
 VALUE='0.22UF',
 PACK_TYPE='0402',
 PART_NUMBER='A36096-155',
 LOCATION='C9N12',
 ROOM='IO_SLOT',
 SEC='1',
 CDS_LIB='mstr_discrete',
 CDS_PART_NAME='CAP_0402-0.22UF,16V,10%,X7R,A3A',
 VOLTAGE='16V',
 PRIM_FILE='./archive_libs/mstr_discrete/cap/chips/chips.prt';

PART_NAME
 C9N13 'CAP_0805-10UF,16V,10%,X6S,C953A':
 ROOM='PVSA_CPU1_PWR_VR';

SECTION_NUMBER 1
 '@BASEBOARD_FAB2_LIB.BASEBOARD_FAB2(SCH_1):PAGE210_I35@MSTR_DISCRETE.CAP(CHIPS)':
 C_PATH='@baseboard_fab2_lib.baseboard_fab2(sch_1):page210_i35@mstr_discrete.cap~
(chips)',
 P_PATH='@baseboard_fab2_lib.baseboard_fab2(sch_1):page210_i35@mstr_discrete.cap~
(chips)',
 PATH='I35',
 DRAWING='@BASEBOARD_FAB2_LIB.BASEBOARD_FAB2(SCH_1):PAGE210',
 TOLERANCE='10%',
 SEC_TYPE='0805',
 MATERIAL='X6S',
 PHYS_PAGE='210',
 XY='(-6625,3825)',
 ROT='0',
 VER='1',
 VALUE='10UF',
 PACK_TYPE='0805',
 PART_NUMBER='C95333-007',
 LOCATION='C9N13',
 ROOM='PVSA_CPU1_PWR_VR',
 SEC='1',
 CDS_LIB='mstr_discrete',
 CDS_PART_NAME='CAP_0805-10UF,16V,10%,X6S,C953A',
 VOLTAGE='16V',
 PRIM_FILE='./archive_libs/mstr_discrete/cap/chips/chips.prt';

PART_NAME
 C9N14 'CAP_0402-0.22UF,16V,10%,X7R,A3A':
 ROOM='IO_SLOT';

SECTION_NUMBER 1
 '@BASEBOARD_FAB2_LIB.BASEBOARD_FAB2(SCH_1):PAGE182_I43@MSTR_DISCRETE.CAP(CHIPS)':
 C_PATH='@baseboard_fab2_lib.baseboard_fab2(sch_1):page182_i43@mstr_discrete.cap~
(chips)',
 P_PATH='@baseboard_fab2_lib.baseboard_fab2(sch_1):page182_i43@mstr_discrete.cap~
(chips)',
 PATH='I43',
 DRAWING='@BASEBOARD_FAB2_LIB.BASEBOARD_FAB2(SCH_1):PAGE182',
 TOLERANCE='10%',
 SEC_TYPE='0402',
 MATERIAL='X7R',
 BOM_COST='IO_SLOT',
 PHYS_PAGE='182',
 XY='(-3400,1825)',
 ROT='0',
 VER='2',
 VALUE='0.22UF',
 PACK_TYPE='0402',
 PART_NUMBER='A36096-155',
 LOCATION='C9N14',
 ROOM='IO_SLOT',
 SEC='1',
 CDS_LIB='mstr_discrete',
 CDS_PART_NAME='CAP_0402-0.22UF,16V,10%,X7R,A3A',
 VOLTAGE='16V',
 PRIM_FILE='./archive_libs/mstr_discrete/cap/chips/chips.prt';

PART_NAME
 C9N15 'CAP_0402-0.22UF,16V,10%,X7R,A3A':
 ROOM='IO_SLOT';

SECTION_NUMBER 1
 '@BASEBOARD_FAB2_LIB.BASEBOARD_FAB2(SCH_1):PAGE182_I41@MSTR_DISCRETE.CAP(CHIPS)':
 C_PATH='@baseboard_fab2_lib.baseboard_fab2(sch_1):page182_i41@mstr_discrete.cap~
(chips)',
 P_PATH='@baseboard_fab2_lib.baseboard_fab2(sch_1):page182_i41@mstr_discrete.cap~
(chips)',
 PATH='I41',
 DRAWING='@BASEBOARD_FAB2_LIB.BASEBOARD_FAB2(SCH_1):PAGE182',
 TOLERANCE='10%',
 SEC_TYPE='0402',
 MATERIAL='X7R',
 BOM_COST='IO_SLOT',
 PHYS_PAGE='182',
 XY='(-2925,1325)',
 ROT='0',
 VER='2',
 VALUE='0.22UF',
 PACK_TYPE='0402',
 PART_NUMBER='A36096-155',
 LOCATION='C9N15',
 ROOM='IO_SLOT',
 SEC='1',
 CDS_LIB='mstr_discrete',
 CDS_PART_NAME='CAP_0402-0.22UF,16V,10%,X7R,A3A',
 VOLTAGE='16V',
 PRIM_FILE='./archive_libs/mstr_discrete/cap/chips/chips.prt';

PART_NAME
 C9N16 'CAP_0402-0.22UF,16V,10%,X7R,A3A':
 ROOM='IO_SLOT';

SECTION_NUMBER 1
 '@BASEBOARD_FAB2_LIB.BASEBOARD_FAB2(SCH_1):PAGE182_I46@MSTR_DISCRETE.CAP(CHIPS)':
 C_PATH='@baseboard_fab2_lib.baseboard_fab2(sch_1):page182_i46@mstr_discrete.cap~
(chips)',
 P_PATH='@baseboard_fab2_lib.baseboard_fab2(sch_1):page182_i46@mstr_discrete.cap~
(chips)',
 PATH='I46',
 DRAWING='@BASEBOARD_FAB2_LIB.BASEBOARD_FAB2(SCH_1):PAGE182',
 TOLERANCE='10%',
 SEC_TYPE='0402',
 MATERIAL='X7R',
 BOM_COST='IO_SLOT',
 PHYS_PAGE='182',
 XY='(-2925,1875)',
 ROT='0',
 VER='2',
 VALUE='0.22UF',
 PACK_TYPE='0402',
 PART_NUMBER='A36096-155',
 LOCATION='C9N16',
 ROOM='IO_SLOT',
 SEC='1',
 CDS_LIB='mstr_discrete',
 CDS_PART_NAME='CAP_0402-0.22UF,16V,10%,X7R,A3A',
 VOLTAGE='16V',
 PRIM_FILE='./archive_libs/mstr_discrete/cap/chips/chips.prt';

PART_NAME
 C9N17 'CAP_0402-0.22UF,16V,10%,X7R,A3A':
 ROOM='IO_SLOT';

SECTION_NUMBER 1
 '@BASEBOARD_FAB2_LIB.BASEBOARD_FAB2(SCH_1):PAGE182_I38@MSTR_DISCRETE.CAP(CHIPS)':
 C_PATH='@baseboard_fab2_lib.baseboard_fab2(sch_1):page182_i38@mstr_discrete.cap~
(chips)',
 P_PATH='@baseboard_fab2_lib.baseboard_fab2(sch_1):page182_i38@mstr_discrete.cap~
(chips)',
 PATH='I38',
 DRAWING='@BASEBOARD_FAB2_LIB.BASEBOARD_FAB2(SCH_1):PAGE182',
 TOLERANCE='10%',
 SEC_TYPE='0402',
 MATERIAL='X7R',
 BOM_COST='IO_SLOT',
 PHYS_PAGE='182',
 XY='(-3400,1425)',
 ROT='0',
 VER='2',
 VALUE='0.22UF',
 PACK_TYPE='0402',
 PART_NUMBER='A36096-155',
 LOCATION='C9N17',
 ROOM='IO_SLOT',
 SEC='1',
 CDS_LIB='mstr_discrete',
 CDS_PART_NAME='CAP_0402-0.22UF,16V,10%,X7R,A3A',
 VOLTAGE='16V',
 PRIM_FILE='./archive_libs/mstr_discrete/cap/chips/chips.prt';

PART_NAME
 C9N18 'CAP_0402-0.22UF,16V,10%,X7R,A3A':
 ROOM='IO_SLOT';

SECTION_NUMBER 1
 '@BASEBOARD_FAB2_LIB.BASEBOARD_FAB2(SCH_1):PAGE182_I39@MSTR_DISCRETE.CAP(CHIPS)':
 C_PATH='@baseboard_fab2_lib.baseboard_fab2(sch_1):page182_i39@mstr_discrete.cap~
(chips)',
 P_PATH='@baseboard_fab2_lib.baseboard_fab2(sch_1):page182_i39@mstr_discrete.cap~
(chips)',
 PATH='I39',
 DRAWING='@BASEBOARD_FAB2_LIB.BASEBOARD_FAB2(SCH_1):PAGE182',
 TOLERANCE='10%',
 SEC_TYPE='0402',
 MATERIAL='X7R',
 BOM_COST='IO_SLOT',
 PHYS_PAGE='182',
 XY='(-2925,1475)',
 ROT='0',
 VER='2',
 VALUE='0.22UF',
 PACK_TYPE='0402',
 PART_NUMBER='A36096-155',
 LOCATION='C9N18',
 ROOM='IO_SLOT',
 SEC='1',
 CDS_LIB='mstr_discrete',
 CDS_PART_NAME='CAP_0402-0.22UF,16V,10%,X7R,A3A',
 VOLTAGE='16V',
 PRIM_FILE='./archive_libs/mstr_discrete/cap/chips/chips.prt';

PART_NAME
 C9N19 'CAP_0805-10UF,16V,10%,X6S,C953A':
 ROOM='PVSA_CPU1_PWR_VR';

SECTION_NUMBER 1
 '@BASEBOARD_FAB2_LIB.BASEBOARD_FAB2(SCH_1):PAGE210_I36@MSTR_DISCRETE.CAP(CHIPS)':
 C_PATH='@baseboard_fab2_lib.baseboard_fab2(sch_1):page210_i36@mstr_discrete.cap~
(chips)',
 P_PATH='@baseboard_fab2_lib.baseboard_fab2(sch_1):page210_i36@mstr_discrete.cap~
(chips)',
 PATH='I36',
 DRAWING='@BASEBOARD_FAB2_LIB.BASEBOARD_FAB2(SCH_1):PAGE210',
 TOLERANCE='10%',
 SEC_TYPE='0805',
 MATERIAL='X6S',
 PHYS_PAGE='210',
 XY='(-6900,3850)',
 ROT='0',
 VER='1',
 VALUE='10UF',
 PACK_TYPE='0805',
 PART_NUMBER='C95333-007',
 LOCATION='C9N19',
 ROOM='PVSA_CPU1_PWR_VR',
 SEC='1',
 CDS_LIB='mstr_discrete',
 CDS_PART_NAME='CAP_0805-10UF,16V,10%,X6S,C953A',
 VOLTAGE='16V',
 PRIM_FILE='./archive_libs/mstr_discrete/cap/chips/chips.prt';

PART_NAME
 C9N20 'CAPP_3018-470UF,2.5V,20%,ALUM,A':
 GROUP='PWR_BULK_CAP',
 ROOM='PVSA_CPU1_DECAP_VR';

SECTION_NUMBER 1
 '@BASEBOARD_FAB2_LIB.BASEBOARD_FAB2(SCH_1):PAGE210_I14@MSTR_DISCRETE.CAPP(CHIPS)':
 C_PATH='@baseboard_fab2_lib.baseboard_fab2(sch_1):page210_i14@mstr_discrete.cap~
p(chips)',
 P_PATH='@baseboard_fab2_lib.baseboard_fab2(sch_1):page210_i14@mstr_discrete.cap~
p(chips)',
 PATH='I14',
 DRAWING='@BASEBOARD_FAB2_LIB.BASEBOARD_FAB2(SCH_1):PAGE210',
 TOLERANCE='20%',
 SEC_TYPE='3018',
 MATERIAL='ALUM',
 BOM_COST='PROC_VRD_VCCIN_CPU0',
 PHYS_PAGE='210',
 XY='(-1900,1450)',
 ROT='2',
 VER='1',
 VALUE='470UF',
 PACK_TYPE='3018',
 PART_NUMBER='699013-049',
 LOCATION='C9N20',
 ROOM='PVSA_CPU1_DECAP_VR',
 GROUP='PWR_BULK_CAP',
 SEC='1',
 CDS_LIB='mstr_discrete',
 CDS_PART_NAME='CAPP_3018-470UF,2.5V,20%,ALUM,A',
 VOLTAGE='2.5V',
 PRIM_FILE='./archive_libs/mstr_discrete/capp/chips/chips.prt';

PART_NAME
 C9N21 'CAP_0805-10UF,16V,10%,X6S,C953A':
 ROOM='PVSA_CPU1_PWR_VR';

SECTION_NUMBER 1
 '@BASEBOARD_FAB2_LIB.BASEBOARD_FAB2(SCH_1):PAGE210_I38@MSTR_DISCRETE.CAP(CHIPS)':
 C_PATH='@baseboard_fab2_lib.baseboard_fab2(sch_1):page210_i38@mstr_discrete.cap~
(chips)',
 P_PATH='@baseboard_fab2_lib.baseboard_fab2(sch_1):page210_i38@mstr_discrete.cap~
(chips)',
 PATH='I38',
 DRAWING='@BASEBOARD_FAB2_LIB.BASEBOARD_FAB2(SCH_1):PAGE210',
 TOLERANCE='10%',
 SEC_TYPE='0805',
 MATERIAL='X6S',
 PHYS_PAGE='210',
 XY='(-7175,3850)',
 ROT='0',
 VER='1',
 VALUE='10UF',
 PACK_TYPE='0805',
 PART_NUMBER='C95333-007',
 LOCATION='C9N21',
 ROOM='PVSA_CPU1_PWR_VR',
 SEC='1',
 CDS_LIB='mstr_discrete',
 CDS_PART_NAME='CAP_0805-10UF,16V,10%,X6S,C953A',
 VOLTAGE='16V',
 PRIM_FILE='./archive_libs/mstr_discrete/cap/chips/chips.prt';

PART_NAME
 C9N22 'CAP_A_0603V-22.0UF,4V,20%,X6S,A':
 GROUP='PWR_MLCC_CAP';

SECTION_NUMBER 1
 '@BASEBOARD_FAB2_LIB.BASEBOARD_FAB2(SCH_1):PAGE210_I44@DEV_DISCRETE.CAP_A(CHIPS)':
 C_PATH='@baseboard_fab2_lib.baseboard_fab2(sch_1):page210_i44@dev_discrete.cap_~
a(chips)',
 P_PATH='@baseboard_fab2_lib.baseboard_fab2(sch_1):page210_i44@dev_discrete.cap_~
a(chips)',
 PATH='I44',
 DRAWING='@BASEBOARD_FAB2_LIB.BASEBOARD_FAB2(SCH_1):PAGE210',
 TOLERANCE='20%',
 SEC_TYPE='0603V',
 MATERIAL='X6S',
 PHYS_PAGE='210',
 XY='(-1000,3100)',
 ROT='0',
 VER='1',
 VALUE='22.0UF',
 PACK_TYPE='0603V',
 PART_NUMBER='E15431-004',
 LOCATION='C9N22',
 GROUP='PWR_MLCC_CAP',
 SEC='1',
 CDS_LIB='dev_discrete',
 CDS_PART_NAME='CAP_A_0603V-22.0UF,4V,20%,X6S,A',
 VOLTAGE='4V',
 PRIM_FILE='./archive_libs/discrete/cap_a/chips/chips.prt';

PART_NAME
 C9N24 'CAPP_3018-470UF,2.5V,20%,ALUM,A':
 GROUP='PWR_BULK_CAP',
 ROOM='PVCCIN_CPU1_DECAP_VR';

SECTION_NUMBER 1
 '@BASEBOARD_FAB2_LIB.BASEBOARD_FAB2(SCH_1):PAGE208_I24@MSTR_DISCRETE.CAPP(CHIPS)':
 C_PATH='@baseboard_fab2_lib.baseboard_fab2(sch_1):page208_i24@mstr_discrete.cap~
p(chips)',
 P_PATH='@baseboard_fab2_lib.baseboard_fab2(sch_1):page208_i24@mstr_discrete.cap~
p(chips)',
 PATH='I24',
 DRAWING='@BASEBOARD_FAB2_LIB.BASEBOARD_FAB2(SCH_1):PAGE208',
 TOLERANCE='20%',
 SEC_TYPE='3018',
 MATERIAL='ALUM',
 BOM_COST='PROC_VRD_VCCIN_CPU0',
 PHYS_PAGE='208',
 XY='(-2375,2650)',
 ROT='0',
 VER='1',
 VALUE='470UF',
 PACK_TYPE='3018',
 PART_NUMBER='699013-049',
 LOCATION='C9N24',
 ROOM='PVCCIN_CPU1_DECAP_VR',
 GROUP='PWR_BULK_CAP',
 SEC='1',
 CDS_LIB='mstr_discrete',
 CDS_PART_NAME='CAPP_3018-470UF,2.5V,20%,ALUM,A',
 VOLTAGE='2.5V',
 PRIM_FILE='./archive_libs/mstr_discrete/capp/chips/chips.prt';

PART_NAME
 C9N25 'CAP_0805-10UF,16V,10%,X6S,C953A':
 ROOM='PVCCIN_CPU1_PWR_VR';

SECTION_NUMBER 1
 '@BASEBOARD_FAB2_LIB.BASEBOARD_FAB2(SCH_1):PAGE209_I8@MSTR_DISCRETE.CAP(CHIPS)':
 C_PATH='@baseboard_fab2_lib.baseboard_fab2(sch_1):page209_i8@mstr_discrete.cap(~
chips)',
 P_PATH='@baseboard_fab2_lib.baseboard_fab2(sch_1):page209_i8@mstr_discrete.cap(~
chips)',
 PATH='I8',
 DRAWING='@BASEBOARD_FAB2_LIB.BASEBOARD_FAB2(SCH_1):PAGE209',
 TOLERANCE='10%',
 SEC_TYPE='0805',
 MATERIAL='X6S',
 PHYS_PAGE='209',
 XY='(-6550,4025)',
 ROT='0',
 VER='1',
 VALUE='10UF',
 PACK_TYPE='0805',
 PART_NUMBER='C95333-007',
 LOCATION='C9N25',
 ROOM='PVCCIN_CPU1_PWR_VR',
 SEC='1',
 CDS_LIB='mstr_discrete',
 CDS_PART_NAME='CAP_0805-10UF,16V,10%,X6S,C953A',
 VOLTAGE='16V',
 PRIM_FILE='./archive_libs/mstr_discrete/cap/chips/chips.prt';

PART_NAME
 C9N26 'CAP_0805-10UF,16V,10%,X6S,C953A':
 ROOM='PVCCIN_CPU1_PWR_VR';

SECTION_NUMBER 1
 '@BASEBOARD_FAB2_LIB.BASEBOARD_FAB2(SCH_1):PAGE209_I7@MSTR_DISCRETE.CAP(CHIPS)':
 C_PATH='@baseboard_fab2_lib.baseboard_fab2(sch_1):page209_i7@mstr_discrete.cap(~
chips)',
 P_PATH='@baseboard_fab2_lib.baseboard_fab2(sch_1):page209_i7@mstr_discrete.cap(~
chips)',
 PATH='I7',
 DRAWING='@BASEBOARD_FAB2_LIB.BASEBOARD_FAB2(SCH_1):PAGE209',
 TOLERANCE='10%',
 SEC_TYPE='0805',
 MATERIAL='X6S',
 PHYS_PAGE='209',
 XY='(-6850,4025)',
 ROT='0',
 VER='1',
 VALUE='10UF',
 PACK_TYPE='0805',
 PART_NUMBER='C95333-007',
 LOCATION='C9N26',
 ROOM='PVCCIN_CPU1_PWR_VR',
 SEC='1',
 CDS_LIB='mstr_discrete',
 CDS_PART_NAME='CAP_0805-10UF,16V,10%,X6S,C953A',
 VOLTAGE='16V',
 PRIM_FILE='./archive_libs/mstr_discrete/cap/chips/chips.prt';

PART_NAME
 C9N27 'CAP_0805-10UF,16V,10%,X6S,C953A':
 ROOM='PVCCIN_CPU1_PWR_VR';

SECTION_NUMBER 1
 '@BASEBOARD_FAB2_LIB.BASEBOARD_FAB2(SCH_1):PAGE209_I5@MSTR_DISCRETE.CAP(CHIPS)':
 C_PATH='@baseboard_fab2_lib.baseboard_fab2(sch_1):page209_i5@mstr_discrete.cap(~
chips)',
 P_PATH='@baseboard_fab2_lib.baseboard_fab2(sch_1):page209_i5@mstr_discrete.cap(~
chips)',
 PATH='I5',
 DRAWING='@BASEBOARD_FAB2_LIB.BASEBOARD_FAB2(SCH_1):PAGE209',
 TOLERANCE='10%',
 SEC_TYPE='0805',
 MATERIAL='X6S',
 PHYS_PAGE='209',
 XY='(-7125,4025)',
 ROT='0',
 VER='1',
 VALUE='10UF',
 PACK_TYPE='0805',
 PART_NUMBER='C95333-007',
 LOCATION='C9N27',
 ROOM='PVCCIN_CPU1_PWR_VR',
 SEC='1',
 CDS_LIB='mstr_discrete',
 CDS_PART_NAME='CAP_0805-10UF,16V,10%,X6S,C953A',
 VOLTAGE='16V',
 PRIM_FILE='./archive_libs/mstr_discrete/cap/chips/chips.prt';

PART_NAME
 C9P1 'CAP_0805-10UF,16V,10%,X6S,C953A':
 ROOM='PVCCIN_CPU1_PWR_VR';

SECTION_NUMBER 1
 '@BASEBOARD_FAB2_LIB.BASEBOARD_FAB2(SCH_1):PAGE208_I59@MSTR_DISCRETE.CAP(CHIPS)':
 C_PATH='@baseboard_fab2_lib.baseboard_fab2(sch_1):page208_i59@mstr_discrete.cap~
(chips)',
 P_PATH='@baseboard_fab2_lib.baseboard_fab2(sch_1):page208_i59@mstr_discrete.cap~
(chips)',
 PATH='I59',
 DRAWING='@BASEBOARD_FAB2_LIB.BASEBOARD_FAB2(SCH_1):PAGE208',
 TOLERANCE='10%',
 SEC_TYPE='0805',
 MATERIAL='X6S',
 PHYS_PAGE='208',
 XY='(-6800,1575)',
 ROT='0',
 VER='1',
 VALUE='10UF',
 PACK_TYPE='0805',
 PART_NUMBER='C95333-007',
 LOCATION='C9P1',
 ROOM='PVCCIN_CPU1_PWR_VR',
 SEC='1',
 CDS_LIB='mstr_discrete',
 CDS_PART_NAME='CAP_0805-10UF,16V,10%,X6S,C953A',
 VOLTAGE='16V',
 PRIM_FILE='./archive_libs/mstr_discrete/cap/chips/chips.prt';

PART_NAME
 C9P2 'CAP_0805-10UF,16V,10%,X6S,C953A':
 ROOM='PVCCIN_CPU1_PWR_VR';

SECTION_NUMBER 1
 '@BASEBOARD_FAB2_LIB.BASEBOARD_FAB2(SCH_1):PAGE208_I60@MSTR_DISCRETE.CAP(CHIPS)':
 C_PATH='@baseboard_fab2_lib.baseboard_fab2(sch_1):page208_i60@mstr_discrete.cap~
(chips)',
 P_PATH='@baseboard_fab2_lib.baseboard_fab2(sch_1):page208_i60@mstr_discrete.cap~
(chips)',
 PATH='I60',
 DRAWING='@BASEBOARD_FAB2_LIB.BASEBOARD_FAB2(SCH_1):PAGE208',
 TOLERANCE='10%',
 SEC_TYPE='0805',
 MATERIAL='X6S',
 PHYS_PAGE='208',
 XY='(-7050,1575)',
 ROT='0',
 VER='1',
 VALUE='10UF',
 PACK_TYPE='0805',
 PART_NUMBER='C95333-007',
 LOCATION='C9P2',
 ROOM='PVCCIN_CPU1_PWR_VR',
 SEC='1',
 CDS_LIB='mstr_discrete',
 CDS_PART_NAME='CAP_0805-10UF,16V,10%,X6S,C953A',
 VOLTAGE='16V',
 PRIM_FILE='./archive_libs/mstr_discrete/cap/chips/chips.prt';

PART_NAME
 C9P3 'CAP_A_0603V-22.0UF,4V,20%,X6S,A':
 GROUP='PWR_MLCC_CAP';

SECTION_NUMBER 1
 '@BASEBOARD_FAB2_LIB.BASEBOARD_FAB2(SCH_1):PAGE207_I59@DEV_DISCRETE.CAP_A(CHIPS)':
 C_PATH='@baseboard_fab2_lib.baseboard_fab2(sch_1):page207_i59@dev_discrete.cap_~
a(chips)',
 P_PATH='@baseboard_fab2_lib.baseboard_fab2(sch_1):page207_i59@dev_discrete.cap_~
a(chips)',
 PATH='I59',
 DRAWING='@BASEBOARD_FAB2_LIB.BASEBOARD_FAB2(SCH_1):PAGE207',
 TOLERANCE='20%',
 SEC_TYPE='0603V',
 MATERIAL='X6S',
 PHYS_PAGE='207',
 XY='(-750,750)',
 ROT='0',
 VER='1',
 VALUE='22.0UF',
 PACK_TYPE='0603V',
 PART_NUMBER='E15431-004',
 LOCATION='C9P3',
 GROUP='PWR_MLCC_CAP',
 SEC='1',
 CDS_LIB='dev_discrete',
 CDS_PART_NAME='CAP_A_0603V-22.0UF,4V,20%,X6S,A',
 VOLTAGE='4V',
 PRIM_FILE='./archive_libs/discrete/cap_a/chips/chips.prt';

PART_NAME
 C9P4 'CAP_0805-10UF,16V,10%,X6S,C953A':
 ROOM='PVCCIN_CPU1_PWR_VR';

SECTION_NUMBER 1
 '@BASEBOARD_FAB2_LIB.BASEBOARD_FAB2(SCH_1):PAGE208_I53@MSTR_DISCRETE.CAP(CHIPS)':
 C_PATH='@baseboard_fab2_lib.baseboard_fab2(sch_1):page208_i53@mstr_discrete.cap~
(chips)',
 P_PATH='@baseboard_fab2_lib.baseboard_fab2(sch_1):page208_i53@mstr_discrete.cap~
(chips)',
 PATH='I53',
 DRAWING='@BASEBOARD_FAB2_LIB.BASEBOARD_FAB2(SCH_1):PAGE208',
 TOLERANCE='10%',
 SEC_TYPE='0805',
 MATERIAL='X6S',
 PHYS_PAGE='208',
 XY='(-6275,4150)',
 ROT='0',
 VER='1',
 VALUE='10UF',
 PACK_TYPE='0805',
 PART_NUMBER='C95333-007',
 LOCATION='C9P4',
 ROOM='PVCCIN_CPU1_PWR_VR',
 SEC='1',
 CDS_LIB='mstr_discrete',
 CDS_PART_NAME='CAP_0805-10UF,16V,10%,X6S,C953A',
 VOLTAGE='16V',
 PRIM_FILE='./archive_libs/mstr_discrete/cap/chips/chips.prt';

PART_NAME
 C9P5 'CAPP_3018-470UF,2.5V,20%,ALUM,A':
 GROUP='PWR_BULK_CAP',
 ROOM='PVCCIN_CPU1_DECAP_VR';

SECTION_NUMBER 1
 '@BASEBOARD_FAB2_LIB.BASEBOARD_FAB2(SCH_1):PAGE208_I14@MSTR_DISCRETE.CAPP(CHIPS)':
 C_PATH='@baseboard_fab2_lib.baseboard_fab2(sch_1):page208_i14@mstr_discrete.cap~
p(chips)',
 P_PATH='@baseboard_fab2_lib.baseboard_fab2(sch_1):page208_i14@mstr_discrete.cap~
p(chips)',
 PATH='I14',
 DRAWING='@BASEBOARD_FAB2_LIB.BASEBOARD_FAB2(SCH_1):PAGE208',
 TOLERANCE='20%',
 SEC_TYPE='3018',
 MATERIAL='ALUM',
 BOM_COST='PROC_VRD_VCCIN_CPU0',
 PHYS_PAGE='208',
 XY='(-1925,2650)',
 ROT='0',
 VER='1',
 VALUE='470UF',
 PACK_TYPE='3018',
 PART_NUMBER='699013-049',
 LOCATION='C9P5',
 ROOM='PVCCIN_CPU1_DECAP_VR',
 GROUP='PWR_BULK_CAP',
 SEC='1',
 CDS_LIB='mstr_discrete',
 CDS_PART_NAME='CAPP_3018-470UF,2.5V,20%,ALUM,A',
 VOLTAGE='2.5V',
 PRIM_FILE='./archive_libs/mstr_discrete/capp/chips/chips.prt';

PART_NAME
 C9P6 'CAP_A_0402V-0.1UF,16V,10%,X7R,A':
 ROOM='HOT_SWAP';

SECTION_NUMBER 1
 '@BASEBOARD_FAB2_LIB.BASEBOARD_FAB2(SCH_1):PAGE200_I185@DEV_DISCRETE.CAP_A(CHIPS)':
 C_PATH='@baseboard_fab2_lib.baseboard_fab2(sch_1):page200_i185@dev_discrete.cap~
_a(chips)',
 P_PATH='@baseboard_fab2_lib.baseboard_fab2(sch_1):page200_i185@dev_discrete.cap~
_a(chips)',
 PATH='I185',
 DRAWING='@BASEBOARD_FAB2_LIB.BASEBOARD_FAB2(SCH_1):PAGE200',
 TOLERANCE='10%',
 SEC_TYPE='0402V',
 MATERIAL='X7R',
 PHYS_PAGE='200',
 XY='(-825,775)',
 ROT='2',
 VER='1',
 VALUE='0.1UF',
 PACK_TYPE='0402V',
 PART_NUMBER='A36096-030',
 LOCATION='C9P6',
 ROOM='HOT_SWAP',
 SEC='1',
 CDS_LIB='dev_discrete',
 CDS_PART_NAME='CAP_A_0402V-0.1UF,16V,10%,X7R,A',
 VOLTAGE='16V',
 PRIM_FILE='./archive_libs/discrete/cap_a/chips/chips.prt';

PART_NAME
 C9P7 'CAP_0805-10UF,16V,10%,X6S,C953A':
 ROOM='PVCCIN_CPU1_PWR_VR';

SECTION_NUMBER 1
 '@BASEBOARD_FAB2_LIB.BASEBOARD_FAB2(SCH_1):PAGE208_I54@MSTR_DISCRETE.CAP(CHIPS)':
 C_PATH='@baseboard_fab2_lib.baseboard_fab2(sch_1):page208_i54@mstr_discrete.cap~
(chips)',
 P_PATH='@baseboard_fab2_lib.baseboard_fab2(sch_1):page208_i54@mstr_discrete.cap~
(chips)',
 PATH='I54',
 DRAWING='@BASEBOARD_FAB2_LIB.BASEBOARD_FAB2(SCH_1):PAGE208',
 TOLERANCE='10%',
 SEC_TYPE='0805',
 MATERIAL='X6S',
 PHYS_PAGE='208',
 XY='(-6550,4150)',
 ROT='0',
 VER='1',
 VALUE='10UF',
 PACK_TYPE='0805',
 PART_NUMBER='C95333-007',
 LOCATION='C9P7',
 ROOM='PVCCIN_CPU1_PWR_VR',
 SEC='1',
 CDS_LIB='mstr_discrete',
 CDS_PART_NAME='CAP_0805-10UF,16V,10%,X6S,C953A',
 VOLTAGE='16V',
 PRIM_FILE='./archive_libs/mstr_discrete/cap/chips/chips.prt';

PART_NAME
 C9P8 'CAPP_3018-470UF,2.5V,20%,ALUM,A':
 GROUP='PWR_BULK_CAP',
 ROOM='PVCCIN_CPU1_DECAP_VR';

SECTION_NUMBER 1
 '@BASEBOARD_FAB2_LIB.BASEBOARD_FAB2(SCH_1):PAGE208_I12@MSTR_DISCRETE.CAPP(CHIPS)':
 C_PATH='@baseboard_fab2_lib.baseboard_fab2(sch_1):page208_i12@mstr_discrete.cap~
p(chips)',
 P_PATH='@baseboard_fab2_lib.baseboard_fab2(sch_1):page208_i12@mstr_discrete.cap~
p(chips)',
 PATH='I12',
 DRAWING='@BASEBOARD_FAB2_LIB.BASEBOARD_FAB2(SCH_1):PAGE208',
 TOLERANCE='20%',
 SEC_TYPE='3018',
 MATERIAL='ALUM',
 BOM_COST='PROC_VRD_VCCIN_CPU0',
 PHYS_PAGE='208',
 XY='(-1450,2650)',
 ROT='0',
 VER='1',
 VALUE='470UF',
 PACK_TYPE='3018',
 PART_NUMBER='699013-049',
 LOCATION='C9P8',
 ROOM='PVCCIN_CPU1_DECAP_VR',
 GROUP='PWR_BULK_CAP',
 SEC='1',
 CDS_LIB='mstr_discrete',
 CDS_PART_NAME='CAPP_3018-470UF,2.5V,20%,ALUM,A',
 VOLTAGE='2.5V',
 PRIM_FILE='./archive_libs/mstr_discrete/capp/chips/chips.prt';

PART_NAME
 C9P9 'CAP_0805-10UF,16V,10%,X6S,C953A':
 ROOM='PVCCIN_CPU1_PWR_VR';

SECTION_NUMBER 1
 '@BASEBOARD_FAB2_LIB.BASEBOARD_FAB2(SCH_1):PAGE208_I55@MSTR_DISCRETE.CAP(CHIPS)':
 C_PATH='@baseboard_fab2_lib.baseboard_fab2(sch_1):page208_i55@mstr_discrete.cap~
(chips)',
 P_PATH='@baseboard_fab2_lib.baseboard_fab2(sch_1):page208_i55@mstr_discrete.cap~
(chips)',
 PATH='I55',
 DRAWING='@BASEBOARD_FAB2_LIB.BASEBOARD_FAB2(SCH_1):PAGE208',
 TOLERANCE='10%',
 SEC_TYPE='0805',
 MATERIAL='X6S',
 PHYS_PAGE='208',
 XY='(-6875,4150)',
 ROT='0',
 VER='1',
 VALUE='10UF',
 PACK_TYPE='0805',
 PART_NUMBER='C95333-007',
 LOCATION='C9P9',
 ROOM='PVCCIN_CPU1_PWR_VR',
 SEC='1',
 CDS_LIB='mstr_discrete',
 CDS_PART_NAME='CAP_0805-10UF,16V,10%,X6S,C953A',
 VOLTAGE='16V',
 PRIM_FILE='./archive_libs/mstr_discrete/cap/chips/chips.prt';

PART_NAME
 C9P10 'CAP_A_0603V-22.0UF,4V,20%,X6S,A':
 GROUP='PWR_MLCC_CAP';

SECTION_NUMBER 1
 '@BASEBOARD_FAB2_LIB.BASEBOARD_FAB2(SCH_1):PAGE208_I66@DEV_DISCRETE.CAP_A(CHIPS)':
 C_PATH='@baseboard_fab2_lib.baseboard_fab2(sch_1):page208_i66@dev_discrete.cap_~
a(chips)',
 P_PATH='@baseboard_fab2_lib.baseboard_fab2(sch_1):page208_i66@dev_discrete.cap_~
a(chips)',
 PATH='I66',
 DRAWING='@BASEBOARD_FAB2_LIB.BASEBOARD_FAB2(SCH_1):PAGE208',
 TOLERANCE='20%',
 SEC_TYPE='0603V',
 MATERIAL='X6S',
 PHYS_PAGE='208',
 XY='(-400,3400)',
 ROT='0',
 VER='1',
 VALUE='22.0UF',
 PACK_TYPE='0603V',
 PART_NUMBER='E15431-004',
 LOCATION='C9P10',
 GROUP='PWR_MLCC_CAP',
 SEC='1',
 CDS_LIB='dev_discrete',
 CDS_PART_NAME='CAP_A_0603V-22.0UF,4V,20%,X6S,A',
 VOLTAGE='4V',
 PRIM_FILE='./archive_libs/discrete/cap_a/chips/chips.prt';

PART_NAME
 C9P11 'CAP_A_0402V-0.1UF,16V,10%,X7R,A':
 ROOM='HOT_SWAP';

SECTION_NUMBER 1
 '@BASEBOARD_FAB2_LIB.BASEBOARD_FAB2(SCH_1):PAGE200_I201@DEV_DISCRETE.CAP_A(CHIPS)':
 C_PATH='@baseboard_fab2_lib.baseboard_fab2(sch_1):page200_i201@dev_discrete.cap~
_a(chips)',
 P_PATH='@baseboard_fab2_lib.baseboard_fab2(sch_1):page200_i201@dev_discrete.cap~
_a(chips)',
 PATH='I201',
 DRAWING='@BASEBOARD_FAB2_LIB.BASEBOARD_FAB2(SCH_1):PAGE200',
 TOLERANCE='10%',
 SEC_TYPE='0402V',
 MATERIAL='X7R',
 PHYS_PAGE='200',
 XY='(-3450,500)',
 ROT='2',
 VER='1',
 VALUE='0.1UF',
 PACK_TYPE='0402V',
 PART_NUMBER='A36096-030',
 LOCATION='C9P11',
 ROOM='HOT_SWAP',
 SEC='1',
 CDS_LIB='dev_discrete',
 CDS_PART_NAME='CAP_A_0402V-0.1UF,16V,10%,X7R,A',
 VOLTAGE='16V',
 PRIM_FILE='./archive_libs/discrete/cap_a/chips/chips.prt';

PART_NAME
 C9P12 'CAP_A_0402V-0.1UF,16V,10%,EMPTA':
 ROOM='HOT_SWAP';

SECTION_NUMBER 1
 '@BASEBOARD_FAB2_LIB.BASEBOARD_FAB2(SCH_1):PAGE199_I67@DEV_DISCRETE.CAP_A(CHIPS)':
 C_PATH='@baseboard_fab2_lib.baseboard_fab2(sch_1):page199_i67@dev_discrete.cap_~
a(chips)',
 P_PATH='@baseboard_fab2_lib.baseboard_fab2(sch_1):page199_i67@dev_discrete.cap_~
a(chips)',
 PATH='I67',
 DRAWING='@BASEBOARD_FAB2_LIB.BASEBOARD_FAB2(SCH_1):PAGE199',
 TOLERANCE='10%',
 SEC_TYPE='0402V',
 MATERIAL='EMPTY',
 PHYS_PAGE='199',
 XY='(-400,2625)',
 ROT='0',
 VER='1',
 VALUE='0.1UF',
 PACK_TYPE='0402V',
 PART_NUMBER='A36096-030',
 LOCATION='C9P12',
 ROOM='HOT_SWAP',
 SEC='1',
 CDS_LIB='dev_discrete',
 CDS_PART_NAME='CAP_A_0402V-0.1UF,16V,10%,EMPTA',
 VOLTAGE='16V',
 PRIM_FILE='./archive_libs/discrete/cap_a/chips/chips.prt';

PART_NAME
 C9P14 'CAP_0603LF-0.033UF,50V,10%,X7RA':
 ROOM='HOT_SWAP';

SECTION_NUMBER 1
 '@BASEBOARD_FAB2_LIB.BASEBOARD_FAB2(SCH_1):PAGE199_I24@MSTR_DISCRETE.CAP(CHIPS)':
 C_PATH='@baseboard_fab2_lib.baseboard_fab2(sch_1):page199_i24@mstr_discrete.cap~
(chips)',
 P_PATH='@baseboard_fab2_lib.baseboard_fab2(sch_1):page199_i24@mstr_discrete.cap~
(chips)',
 PATH='I24',
 DRAWING='@BASEBOARD_FAB2_LIB.BASEBOARD_FAB2(SCH_1):PAGE199',
 TOLERANCE='10%',
 SEC_TYPE='0603LF',
 MATERIAL='X7R',
 PHYS_PAGE='199',
 XY='(-4850,1500)',
 ROT='0',
 VER='1',
 VALUE='0.033UF',
 PACK_TYPE='0603LF',
 PART_NUMBER='603269-064',
 LOCATION='C9P14',
 ROOM='HOT_SWAP',
 SEC='1',
 CDS_LIB='mstr_discrete',
 CDS_PART_NAME='CAP_0603LF-0.033UF,50V,10%,X7RA',
 VOLTAGE='50V',
 PRIM_FILE='./archive_libs/mstr_discrete/cap/chips/chips.prt';

PART_NAME
 C9P15 'CAP_A_0402V-0.1UF,16V,10%,X7R,A':
 ROOM='HOT_SWAP';

SECTION_NUMBER 1
 '@BASEBOARD_FAB2_LIB.BASEBOARD_FAB2(SCH_1):PAGE199_I105@DEV_DISCRETE.CAP_A(CHIPS)':
 C_PATH='@baseboard_fab2_lib.baseboard_fab2(sch_1):page199_i105@dev_discrete.cap~
_a(chips)',
 P_PATH='@baseboard_fab2_lib.baseboard_fab2(sch_1):page199_i105@dev_discrete.cap~
_a(chips)',
 PATH='I105',
 DRAWING='@BASEBOARD_FAB2_LIB.BASEBOARD_FAB2(SCH_1):PAGE199',
 TOLERANCE='10%',
 SEC_TYPE='0402V',
 MATERIAL='X7R',
 PHYS_PAGE='199',
 XY='(-6150,850)',
 ROT='2',
 VER='1',
 VALUE='0.1UF',
 PACK_TYPE='0402V',
 PART_NUMBER='A36096-030',
 LOCATION='C9P15',
 ROOM='HOT_SWAP',
 SEC='1',
 CDS_LIB='dev_discrete',
 CDS_PART_NAME='CAP_A_0402V-0.1UF,16V,10%,X7R,A',
 VOLTAGE='16V',
 PRIM_FILE='./archive_libs/discrete/cap_a/chips/chips.prt';

PART_NAME
 C9P16 'CAP_A_0402V-0.1UF,16V,10%,EMPTA':
 ROOM='HOT_SWAP';

SECTION_NUMBER 1
 '@BASEBOARD_FAB2_LIB.BASEBOARD_FAB2(SCH_1):PAGE200_I40@DEV_DISCRETE.CAP_A(CHIPS)':
 C_PATH='@baseboard_fab2_lib.baseboard_fab2(sch_1):page200_i40@dev_discrete.cap_~
a(chips)',
 P_PATH='@baseboard_fab2_lib.baseboard_fab2(sch_1):page200_i40@dev_discrete.cap_~
a(chips)',
 PATH='I40',
 DRAWING='@BASEBOARD_FAB2_LIB.BASEBOARD_FAB2(SCH_1):PAGE200',
 TOLERANCE='10%',
 MATERIAL='EMPTY',
 PHYS_PAGE='200',
 XY='(-675,3000)',
 ROT='0',
 VER='1',
 VALUE='0.1UF',
 PACK_TYPE='0402V',
 PART_NUMBER='A36096-030',
 LOCATION='C9P16',
 ROOM='HOT_SWAP',
 CDS_LIB='dev_discrete',
 CDS_PART_NAME='CAP_A_0402V-0.1UF,16V,10%,EMPTA',
 VOLTAGE='16V',
 PRIM_FILE='./archive_libs/discrete/cap_a/chips/chips.prt';

PART_NAME
 C9P17 'CAP_A_0402V-0.1UF,16V,10%,EMPTA':
 ROOM='HOT_SWAP';

SECTION_NUMBER 1
 '@BASEBOARD_FAB2_LIB.BASEBOARD_FAB2(SCH_1):PAGE200_I36@DEV_DISCRETE.CAP_A(CHIPS)':
 C_PATH='@baseboard_fab2_lib.baseboard_fab2(sch_1):page200_i36@dev_discrete.cap_~
a(chips)',
 P_PATH='@baseboard_fab2_lib.baseboard_fab2(sch_1):page200_i36@dev_discrete.cap_~
a(chips)',
 PATH='I36',
 DRAWING='@BASEBOARD_FAB2_LIB.BASEBOARD_FAB2(SCH_1):PAGE200',
 TOLERANCE='10%',
 SEC_TYPE='0402V',
 MATERIAL='EMPTY',
 PHYS_PAGE='200',
 XY='(-1025,3425)',
 ROT='0',
 VER='1',
 VALUE='0.1UF',
 PACK_TYPE='0402V',
 PART_NUMBER='A36096-030',
 LOCATION='C9P17',
 ROOM='HOT_SWAP',
 SEC='1',
 CDS_LIB='dev_discrete',
 CDS_PART_NAME='CAP_A_0402V-0.1UF,16V,10%,EMPTA',
 VOLTAGE='16V',
 PRIM_FILE='./archive_libs/discrete/cap_a/chips/chips.prt';

PART_NAME
 C9P18 'CAPP_3018-470UF,2.5V,20%,ALUM,A':
 GROUP='PWR_BULK_CAP',
 ROOM='PVCCIN_CPU1_DECAP_VR';

SECTION_NUMBER 1
 '@BASEBOARD_FAB2_LIB.BASEBOARD_FAB2(SCH_1):PAGE208_I30@MSTR_DISCRETE.CAPP(CHIPS)':
 C_PATH='@baseboard_fab2_lib.baseboard_fab2(sch_1):page208_i30@mstr_discrete.cap~
p(chips)',
 P_PATH='@baseboard_fab2_lib.baseboard_fab2(sch_1):page208_i30@mstr_discrete.cap~
p(chips)',
 PATH='I30',
 DRAWING='@BASEBOARD_FAB2_LIB.BASEBOARD_FAB2(SCH_1):PAGE208',
 TOLERANCE='20%',
 SEC_TYPE='3018',
 MATERIAL='ALUM',
 BOM_COST='PROC_VRD_VCCIN_CPU0',
 PHYS_PAGE='208',
 XY='(-4250,2650)',
 ROT='0',
 VER='1',
 VALUE='470UF',
 PACK_TYPE='3018',
 PART_NUMBER='699013-049',
 LOCATION='C9P18',
 ROOM='PVCCIN_CPU1_DECAP_VR',
 GROUP='PWR_BULK_CAP',
 SEC='1',
 CDS_LIB='mstr_discrete',
 CDS_PART_NAME='CAPP_3018-470UF,2.5V,20%,ALUM,A',
 VOLTAGE='2.5V',
 PRIM_FILE='./archive_libs/mstr_discrete/capp/chips/chips.prt';

PART_NAME
 C9P20 'CAP_A_0603V-22.0UF,4V,20%,X6S,A':
 GROUP='PWR_MLCC_CAP';

SECTION_NUMBER 1
 '@BASEBOARD_FAB2_LIB.BASEBOARD_FAB2(SCH_1):PAGE209_I55@DEV_DISCRETE.CAP_A(CHIPS)':
 C_PATH='@baseboard_fab2_lib.baseboard_fab2(sch_1):page209_i55@dev_discrete.cap_~
a(chips)',
 P_PATH='@baseboard_fab2_lib.baseboard_fab2(sch_1):page209_i55@dev_discrete.cap_~
a(chips)',
 PATH='I55',
 DRAWING='@BASEBOARD_FAB2_LIB.BASEBOARD_FAB2(SCH_1):PAGE209',
 TOLERANCE='20%',
 SEC_TYPE='0603V',
 MATERIAL='X6S',
 PHYS_PAGE='209',
 XY='(-350,3250)',
 ROT='0',
 VER='1',
 VALUE='22.0UF',
 PACK_TYPE='0603V',
 PART_NUMBER='E15431-004',
 LOCATION='C9P20',
 GROUP='PWR_MLCC_CAP',
 SEC='1',
 CDS_LIB='dev_discrete',
 CDS_PART_NAME='CAP_A_0603V-22.0UF,4V,20%,X6S,A',
 VOLTAGE='4V',
 PRIM_FILE='./archive_libs/discrete/cap_a/chips/chips.prt';

PART_NAME
 C9P22 'CAP_0805-10UF,16V,10%,X6S,C953A':
 ROOM='PVCCIN_CPU1_PWR_VR';

SECTION_NUMBER 1
 '@BASEBOARD_FAB2_LIB.BASEBOARD_FAB2(SCH_1):PAGE207_I50@MSTR_DISCRETE.CAP(CHIPS)':
 C_PATH='@baseboard_fab2_lib.baseboard_fab2(sch_1):page207_i50@mstr_discrete.cap~
(chips)',
 P_PATH='@baseboard_fab2_lib.baseboard_fab2(sch_1):page207_i50@mstr_discrete.cap~
(chips)',
 PATH='I50',
 DRAWING='@BASEBOARD_FAB2_LIB.BASEBOARD_FAB2(SCH_1):PAGE207',
 TOLERANCE='10%',
 SEC_TYPE='0805',
 MATERIAL='X6S',
 PHYS_PAGE='207',
 XY='(-6300,1550)',
 ROT='0',
 VER='1',
 VALUE='10UF',
 PACK_TYPE='0805',
 PART_NUMBER='C95333-007',
 LOCATION='C9P22',
 ROOM='PVCCIN_CPU1_PWR_VR',
 SEC='1',
 CDS_LIB='mstr_discrete',
 CDS_PART_NAME='CAP_0805-10UF,16V,10%,X6S,C953A',
 VOLTAGE='16V',
 PRIM_FILE='./archive_libs/mstr_discrete/cap/chips/chips.prt';

PART_NAME
 C9P23 'CAPP_3018-470UF,2.5V,20%,ALUM,A':
 GROUP='PWR_BULK_CAP',
 ROOM='PVCCIN_CPU1_DECAP_VR';

SECTION_NUMBER 1
 '@BASEBOARD_FAB2_LIB.BASEBOARD_FAB2(SCH_1):PAGE208_I28@MSTR_DISCRETE.CAPP(CHIPS)':
 C_PATH='@baseboard_fab2_lib.baseboard_fab2(sch_1):page208_i28@mstr_discrete.cap~
p(chips)',
 P_PATH='@baseboard_fab2_lib.baseboard_fab2(sch_1):page208_i28@mstr_discrete.cap~
p(chips)',
 PATH='I28',
 DRAWING='@BASEBOARD_FAB2_LIB.BASEBOARD_FAB2(SCH_1):PAGE208',
 TOLERANCE='20%',
 SEC_TYPE='3018',
 MATERIAL='ALUM',
 BOM_COST='PROC_VRD_VCCIN_CPU0',
 PHYS_PAGE='208',
 XY='(-3725,2650)',
 ROT='0',
 VER='1',
 VALUE='470UF',
 PACK_TYPE='3018',
 PART_NUMBER='699013-049',
 LOCATION='C9P23',
 ROOM='PVCCIN_CPU1_DECAP_VR',
 GROUP='PWR_BULK_CAP',
 SEC='1',
 CDS_LIB='mstr_discrete',
 CDS_PART_NAME='CAPP_3018-470UF,2.5V,20%,ALUM,A',
 VOLTAGE='2.5V',
 PRIM_FILE='./archive_libs/mstr_discrete/capp/chips/chips.prt';

PART_NAME
 C9P24 'CAP_0805-10UF,16V,10%,X6S,C953A':
 ROOM='PVCCIN_CPU1_PWR_VR';

SECTION_NUMBER 1
 '@BASEBOARD_FAB2_LIB.BASEBOARD_FAB2(SCH_1):PAGE208_I58@MSTR_DISCRETE.CAP(CHIPS)':
 C_PATH='@baseboard_fab2_lib.baseboard_fab2(sch_1):page208_i58@mstr_discrete.cap~
(chips)',
 P_PATH='@baseboard_fab2_lib.baseboard_fab2(sch_1):page208_i58@mstr_discrete.cap~
(chips)',
 PATH='I58',
 DRAWING='@BASEBOARD_FAB2_LIB.BASEBOARD_FAB2(SCH_1):PAGE208',
 TOLERANCE='10%',
 SEC_TYPE='0805',
 MATERIAL='X6S',
 PHYS_PAGE='208',
 XY='(-6500,1575)',
 ROT='0',
 VER='1',
 VALUE='10UF',
 PACK_TYPE='0805',
 PART_NUMBER='C95333-007',
 LOCATION='C9P24',
 ROOM='PVCCIN_CPU1_PWR_VR',
 SEC='1',
 CDS_LIB='mstr_discrete',
 CDS_PART_NAME='CAP_0805-10UF,16V,10%,X6S,C953A',
 VOLTAGE='16V',
 PRIM_FILE='./archive_libs/mstr_discrete/cap/chips/chips.prt';

PART_NAME
 C9P25 'CAP_0805-10UF,16V,10%,X6S,C953A':
 ROOM='PVCCIN_CPU1_PWR_VR';

SECTION_NUMBER 1
 '@BASEBOARD_FAB2_LIB.BASEBOARD_FAB2(SCH_1):PAGE207_I51@MSTR_DISCRETE.CAP(CHIPS)':
 C_PATH='@baseboard_fab2_lib.baseboard_fab2(sch_1):page207_i51@mstr_discrete.cap~
(chips)',
 P_PATH='@baseboard_fab2_lib.baseboard_fab2(sch_1):page207_i51@mstr_discrete.cap~
(chips)',
 PATH='I51',
 DRAWING='@BASEBOARD_FAB2_LIB.BASEBOARD_FAB2(SCH_1):PAGE207',
 TOLERANCE='10%',
 SEC_TYPE='0805',
 MATERIAL='X6S',
 PHYS_PAGE='207',
 XY='(-6575,1550)',
 ROT='0',
 VER='1',
 VALUE='10UF',
 PACK_TYPE='0805',
 PART_NUMBER='C95333-007',
 LOCATION='C9P25',
 ROOM='PVCCIN_CPU1_PWR_VR',
 SEC='1',
 CDS_LIB='mstr_discrete',
 CDS_PART_NAME='CAP_0805-10UF,16V,10%,X6S,C953A',
 VOLTAGE='16V',
 PRIM_FILE='./archive_libs/mstr_discrete/cap/chips/chips.prt';

PART_NAME
 C9P26 'CAP_0805-10UF,16V,10%,X6S,C953A':
 ROOM='PVCCIN_CPU1_PWR_VR';

SECTION_NUMBER 1
 '@BASEBOARD_FAB2_LIB.BASEBOARD_FAB2(SCH_1):PAGE207_I54@MSTR_DISCRETE.CAP(CHIPS)':
 C_PATH='@baseboard_fab2_lib.baseboard_fab2(sch_1):page207_i54@mstr_discrete.cap~
(chips)',
 P_PATH='@baseboard_fab2_lib.baseboard_fab2(sch_1):page207_i54@mstr_discrete.cap~
(chips)',
 PATH='I54',
 DRAWING='@BASEBOARD_FAB2_LIB.BASEBOARD_FAB2(SCH_1):PAGE207',
 TOLERANCE='10%',
 SEC_TYPE='0805',
 MATERIAL='X6S',
 PHYS_PAGE='207',
 XY='(-6875,1550)',
 ROT='0',
 VER='1',
 VALUE='10UF',
 PACK_TYPE='0805',
 PART_NUMBER='C95333-007',
 LOCATION='C9P26',
 ROOM='PVCCIN_CPU1_PWR_VR',
 SEC='1',
 CDS_LIB='mstr_discrete',
 CDS_PART_NAME='CAP_0805-10UF,16V,10%,X6S,C953A',
 VOLTAGE='16V',
 PRIM_FILE='./archive_libs/mstr_discrete/cap/chips/chips.prt';

PART_NAME
 C9R2 'CAP_A_0603V-22.0UF,4V,20%,X6S,A':
 GROUP='PWR_MLCC_CAP';

SECTION_NUMBER 1
 '@BASEBOARD_FAB2_LIB.BASEBOARD_FAB2(SCH_1):PAGE208_I67@DEV_DISCRETE.CAP_A(CHIPS)':
 C_PATH='@baseboard_fab2_lib.baseboard_fab2(sch_1):page208_i67@dev_discrete.cap_~
a(chips)',
 P_PATH='@baseboard_fab2_lib.baseboard_fab2(sch_1):page208_i67@dev_discrete.cap_~
a(chips)',
 PATH='I67',
 DRAWING='@BASEBOARD_FAB2_LIB.BASEBOARD_FAB2(SCH_1):PAGE208',
 TOLERANCE='20%',
 SEC_TYPE='0603V',
 MATERIAL='X6S',
 PHYS_PAGE='208',
 XY='(-350,800)',
 ROT='0',
 VER='1',
 VALUE='22.0UF',
 PACK_TYPE='0603V',
 PART_NUMBER='E15431-004',
 LOCATION='C9R2',
 GROUP='PWR_MLCC_CAP',
 SEC='1',
 CDS_LIB='dev_discrete',
 CDS_PART_NAME='CAP_A_0603V-22.0UF,4V,20%,X6S,A',
 VOLTAGE='4V',
 PRIM_FILE='./archive_libs/discrete/cap_a/chips/chips.prt';

PART_NAME
 C9R3 'CAPP_3018-470UF,2.5V,20%,ALUM,A':
 GROUP='PWR_BULK_CAP',
 ROOM='PVCCIN_CPU1_DECAP_VR';

SECTION_NUMBER 1
 '@BASEBOARD_FAB2_LIB.BASEBOARD_FAB2(SCH_1):PAGE208_I26@MSTR_DISCRETE.CAPP(CHIPS)':
 C_PATH='@baseboard_fab2_lib.baseboard_fab2(sch_1):page208_i26@mstr_discrete.cap~
p(chips)',
 P_PATH='@baseboard_fab2_lib.baseboard_fab2(sch_1):page208_i26@mstr_discrete.cap~
p(chips)',
 PATH='I26',
 DRAWING='@BASEBOARD_FAB2_LIB.BASEBOARD_FAB2(SCH_1):PAGE208',
 TOLERANCE='20%',
 SEC_TYPE='3018',
 MATERIAL='ALUM',
 BOM_COST='PROC_VRD_VCCIN_CPU0',
 PHYS_PAGE='208',
 XY='(-3275,2650)',
 ROT='0',
 VER='1',
 VALUE='470UF',
 PACK_TYPE='3018',
 PART_NUMBER='699013-049',
 LOCATION='C9R3',
 ROOM='PVCCIN_CPU1_DECAP_VR',
 GROUP='PWR_BULK_CAP',
 SEC='1',
 CDS_LIB='mstr_discrete',
 CDS_PART_NAME='CAPP_3018-470UF,2.5V,20%,ALUM,A',
 VOLTAGE='2.5V',
 PRIM_FILE='./archive_libs/mstr_discrete/capp/chips/chips.prt';

PART_NAME
 C9R5 'CAP_0805-10UF,16V,10%,X6S,C953A':
 ROOM='HOT_SWAP';

SECTION_NUMBER 1
 '@BASEBOARD_FAB2_LIB.BASEBOARD_FAB2(SCH_1):PAGE195_I31@MSTR_DISCRETE.CAP(CHIPS)':
 C_PATH='@baseboard_fab2_lib.baseboard_fab2(sch_1):page195_i31@mstr_discrete.cap~
(chips)',
 P_PATH='@baseboard_fab2_lib.baseboard_fab2(sch_1):page195_i31@mstr_discrete.cap~
(chips)',
 PATH='I31',
 DRAWING='@BASEBOARD_FAB2_LIB.BASEBOARD_FAB2(SCH_1):PAGE195',
 POP='NOPOP',
 TOLERANCE='10%',
 SEC_TYPE='0805',
 MATERIAL='X6S',
 PHYS_PAGE='195',
 XY='(-3700,3650)',
 ROT='0',
 VER='1',
 VALUE='10UF',
 PACK_TYPE='0805',
 PART_NUMBER='C95333-007',
 LOCATION='C9R5',
 ROOM='HOT_SWAP',
 SEC='1',
 CDS_LIB='mstr_discrete',
 CDS_PART_NAME='CAP_0805-10UF,16V,10%,X6S,C953A',
 VOLTAGE='16V',
 PRIM_FILE='./archive_libs/mstr_discrete/cap/chips/chips.prt';

PART_NAME
 C9R6 'CAP_A_0402V-0.1UF,16V,10%,X7R,A':
 ROOM='HOT_SWAP';

SECTION_NUMBER 1
 '@BASEBOARD_FAB2_LIB.BASEBOARD_FAB2(SCH_1):PAGE195_I37@DEV_DISCRETE.CAP_A(CHIPS)':
 C_PATH='@baseboard_fab2_lib.baseboard_fab2(sch_1):page195_i37@dev_discrete.cap_~
a(chips)',
 P_PATH='@baseboard_fab2_lib.baseboard_fab2(sch_1):page195_i37@dev_discrete.cap_~
a(chips)',
 PATH='I37',
 DRAWING='@BASEBOARD_FAB2_LIB.BASEBOARD_FAB2(SCH_1):PAGE195',
 POP='NOPOP',
 TOLERANCE='10%',
 SEC_TYPE='0402V',
 MATERIAL='X7R',
 BOM_COST='HOT_SWAP',
 PHYS_PAGE='195',
 XY='(-2300,3650)',
 ROT='0',
 VER='1',
 VALUE='0.1UF',
 PACK_TYPE='0402V',
 PART_NUMBER='A36096-030',
 LOCATION='C9R6',
 ROOM='HOT_SWAP',
 SEC='1',
 CDS_LIB='dev_discrete',
 CDS_PART_NAME='CAP_A_0402V-0.1UF,16V,10%,X7R,A',
 VOLTAGE='16V',
 PRIM_FILE='./archive_libs/discrete/cap_a/chips/chips.prt';

PART_NAME
 C9R7 'CAP_0805-10UF,16V,10%,X6S,C953A':
 ROOM='PVCCIN_CPU1_PWR_VR';

SECTION_NUMBER 1
 '@BASEBOARD_FAB2_LIB.BASEBOARD_FAB2(SCH_1):PAGE207_I43@MSTR_DISCRETE.CAP(CHIPS)':
 C_PATH='@baseboard_fab2_lib.baseboard_fab2(sch_1):page207_i43@mstr_discrete.cap~
(chips)',
 P_PATH='@baseboard_fab2_lib.baseboard_fab2(sch_1):page207_i43@mstr_discrete.cap~
(chips)',
 PATH='I43',
 DRAWING='@BASEBOARD_FAB2_LIB.BASEBOARD_FAB2(SCH_1):PAGE207',
 TOLERANCE='10%',
 SEC_TYPE='0805',
 MATERIAL='X6S',
 PHYS_PAGE='207',
 XY='(-6425,4125)',
 ROT='0',
 VER='1',
 VALUE='10UF',
 PACK_TYPE='0805',
 PART_NUMBER='C95333-007',
 LOCATION='C9R7',
 ROOM='PVCCIN_CPU1_PWR_VR',
 SEC='1',
 CDS_LIB='mstr_discrete',
 CDS_PART_NAME='CAP_0805-10UF,16V,10%,X6S,C953A',
 VOLTAGE='16V',
 PRIM_FILE='./archive_libs/mstr_discrete/cap/chips/chips.prt';

PART_NAME
 C9R8 'CAP_A_0603V-22.0UF,4V,20%,X6S,A':
 GROUP='PWR_MLCC_CAP',
 ROOM='PVCCIN_CPU1_PWR_VR';

SECTION_NUMBER 1
 '@BASEBOARD_FAB2_LIB.BASEBOARD_FAB2(SCH_1):PAGE207_I8@DEV_DISCRETE.CAP_A(CHIPS)':
 C_PATH='@baseboard_fab2_lib.baseboard_fab2(sch_1):page207_i8@dev_discrete.cap_a~
(chips)',
 P_PATH='@baseboard_fab2_lib.baseboard_fab2(sch_1):page207_i8@dev_discrete.cap_a~
(chips)',
 PATH='I8',
 DRAWING='@BASEBOARD_FAB2_LIB.BASEBOARD_FAB2(SCH_1):PAGE207',
 TOLERANCE='20%',
 SEC_TYPE='0603V',
 MATERIAL='X6S',
 BOM_COST='PROC_VRD_VCCIN_CPU0',
 PHYS_PAGE='207',
 XY='(-1100,3350)',
 ROT='0',
 VER='1',
 VALUE='22.0UF',
 PACK_TYPE='0603V',
 PART_NUMBER='E15431-004',
 LOCATION='C9R8',
 ROOM='PVCCIN_CPU1_PWR_VR',
 GROUP='PWR_MLCC_CAP',
 SEC='1',
 CDS_LIB='dev_discrete',
 CDS_PART_NAME='CAP_A_0603V-22.0UF,4V,20%,X6S,A',
 VOLTAGE='4V',
 PRIM_FILE='./archive_libs/discrete/cap_a/chips/chips.prt';

PART_NAME
 C9R9 'CAPP_3018-470UF,2.5V,20%,ALUM,A':
 GROUP='PWR_BULK_CAP',
 ROOM='PVCCIN_CPU1_DECAP_VR';

SECTION_NUMBER 1
 '@BASEBOARD_FAB2_LIB.BASEBOARD_FAB2(SCH_1):PAGE208_I25@MSTR_DISCRETE.CAPP(CHIPS)':
 C_PATH='@baseboard_fab2_lib.baseboard_fab2(sch_1):page208_i25@mstr_discrete.cap~
p(chips)',
 P_PATH='@baseboard_fab2_lib.baseboard_fab2(sch_1):page208_i25@mstr_discrete.cap~
p(chips)',
 PATH='I25',
 DRAWING='@BASEBOARD_FAB2_LIB.BASEBOARD_FAB2(SCH_1):PAGE208',
 TOLERANCE='20%',
 SEC_TYPE='3018',
 MATERIAL='ALUM',
 BOM_COST='PROC_VRD_VCCIN_CPU0',
 PHYS_PAGE='208',
 XY='(-2825,2650)',
 ROT='0',
 VER='1',
 VALUE='470UF',
 PACK_TYPE='3018',
 PART_NUMBER='699013-049',
 LOCATION='C9R9',
 ROOM='PVCCIN_CPU1_DECAP_VR',
 GROUP='PWR_BULK_CAP',
 SEC='1',
 CDS_LIB='mstr_discrete',
 CDS_PART_NAME='CAPP_3018-470UF,2.5V,20%,ALUM,A',
 VOLTAGE='2.5V',
 PRIM_FILE='./archive_libs/mstr_discrete/capp/chips/chips.prt';

PART_NAME
 C9R10 'CAP_0805-10UF,16V,10%,X6S,C953A':
 ROOM='PVCCIN_CPU1_PWR_VR';

SECTION_NUMBER 1
 '@BASEBOARD_FAB2_LIB.BASEBOARD_FAB2(SCH_1):PAGE207_I44@MSTR_DISCRETE.CAP(CHIPS)':
 C_PATH='@baseboard_fab2_lib.baseboard_fab2(sch_1):page207_i44@mstr_discrete.cap~
(chips)',
 P_PATH='@baseboard_fab2_lib.baseboard_fab2(sch_1):page207_i44@mstr_discrete.cap~
(chips)',
 PATH='I44',
 DRAWING='@BASEBOARD_FAB2_LIB.BASEBOARD_FAB2(SCH_1):PAGE207',
 TOLERANCE='10%',
 SEC_TYPE='0805',
 MATERIAL='X6S',
 PHYS_PAGE='207',
 XY='(-6725,4125)',
 ROT='0',
 VER='1',
 VALUE='10UF',
 PACK_TYPE='0805',
 PART_NUMBER='C95333-007',
 LOCATION='C9R10',
 ROOM='PVCCIN_CPU1_PWR_VR',
 SEC='1',
 CDS_LIB='mstr_discrete',
 CDS_PART_NAME='CAP_0805-10UF,16V,10%,X6S,C953A',
 VOLTAGE='16V',
 PRIM_FILE='./archive_libs/mstr_discrete/cap/chips/chips.prt';

PART_NAME
 C9R11 'CAP_0805-10UF,16V,10%,X6S,C953A':
 ROOM='PVCCIN_CPU1_PWR_VR';

SECTION_NUMBER 1
 '@BASEBOARD_FAB2_LIB.BASEBOARD_FAB2(SCH_1):PAGE207_I48@MSTR_DISCRETE.CAP(CHIPS)':
 C_PATH='@baseboard_fab2_lib.baseboard_fab2(sch_1):page207_i48@mstr_discrete.cap~
(chips)',
 P_PATH='@baseboard_fab2_lib.baseboard_fab2(sch_1):page207_i48@mstr_discrete.cap~
(chips)',
 PATH='I48',
 DRAWING='@BASEBOARD_FAB2_LIB.BASEBOARD_FAB2(SCH_1):PAGE207',
 TOLERANCE='10%',
 SEC_TYPE='0805',
 MATERIAL='X6S',
 PHYS_PAGE='207',
 XY='(-7025,4125)',
 ROT='0',
 VER='1',
 VALUE='10UF',
 PACK_TYPE='0805',
 PART_NUMBER='C95333-007',
 LOCATION='C9R11',
 ROOM='PVCCIN_CPU1_PWR_VR',
 SEC='1',
 CDS_LIB='mstr_discrete',
 CDS_PART_NAME='CAP_0805-10UF,16V,10%,X6S,C953A',
 VOLTAGE='16V',
 PRIM_FILE='./archive_libs/mstr_discrete/cap/chips/chips.prt';

PART_NAME
 C9R12 'CAP_A_0402V-0.1UF,16V,10%,X7R,A':
 ROOM='HOT_SWAP';

SECTION_NUMBER 1
 '@BASEBOARD_FAB2_LIB.BASEBOARD_FAB2(SCH_1):PAGE195_I36@DEV_DISCRETE.CAP_A(CHIPS)':
 C_PATH='@baseboard_fab2_lib.baseboard_fab2(sch_1):page195_i36@dev_discrete.cap_~
a(chips)',
 P_PATH='@baseboard_fab2_lib.baseboard_fab2(sch_1):page195_i36@dev_discrete.cap_~
a(chips)',
 PATH='I36',
 DRAWING='@BASEBOARD_FAB2_LIB.BASEBOARD_FAB2(SCH_1):PAGE195',
 POP='NOPOP',
 TOLERANCE='10%',
 SEC_TYPE='0402V',
 MATERIAL='X7R',
 BOM_COST='HOT_SWAP',
 PHYS_PAGE='195',
 XY='(-2675,3650)',
 ROT='0',
 VER='1',
 VALUE='0.1UF',
 PACK_TYPE='0402V',
 PART_NUMBER='A36096-030',
 LOCATION='C9R12',
 ROOM='HOT_SWAP',
 SEC='1',
 CDS_LIB='dev_discrete',
 CDS_PART_NAME='CAP_A_0402V-0.1UF,16V,10%,X7R,A',
 VOLTAGE='16V',
 PRIM_FILE='./archive_libs/discrete/cap_a/chips/chips.prt';

PART_NAME
 C9R13 'CAP_A_0402V-0.1UF,16V,10%,X7R,A':
 ROOM='TEMP_SENSORS';

SECTION_NUMBER 1
 '@BASEBOARD_FAB2_LIB.BASEBOARD_FAB2(SCH_1):PAGE167_I42@DEV_DISCRETE.CAP_A(CHIPS)':
 C_PATH='@baseboard_fab2_lib.baseboard_fab2(sch_1):page167_i42@dev_discrete.cap_~
a(chips)',
 P_PATH='@baseboard_fab2_lib.baseboard_fab2(sch_1):page167_i42@dev_discrete.cap_~
a(chips)',
 PATH='I42',
 DRAWING='@BASEBOARD_FAB2_LIB.BASEBOARD_FAB2(SCH_1):PAGE167',
 TOLERANCE='10%',
 SEC_TYPE='0402V',
 MATERIAL='X7R',
 BOM_COST='SM_THERM',
 PHYS_PAGE='167',
 XY='(-1425,2150)',
 ROT='0',
 VER='1',
 VALUE='0.1UF',
 PACK_TYPE='0402V',
 PART_NUMBER='A36096-030',
 LOCATION='C9R13',
 ROOM='TEMP_SENSORS',
 SEC='1',
 CDS_LIB='dev_discrete',
 CDS_PART_NAME='CAP_A_0402V-0.1UF,16V,10%,X7R,A',
 VOLTAGE='16V',
 PRIM_FILE='./archive_libs/discrete/cap_a/chips/chips.prt';

PART_NAME
 C9R14 'CAP_A_0402V-0.1UF,16V,10%,X7R,A':
 ROOM='TEMP_SENSORS';

SECTION_NUMBER 1
 '@BASEBOARD_FAB2_LIB.BASEBOARD_FAB2(SCH_1):PAGE167_I41@DEV_DISCRETE.CAP_A(CHIPS)':
 C_PATH='@baseboard_fab2_lib.baseboard_fab2(sch_1):page167_i41@dev_discrete.cap_~
a(chips)',
 P_PATH='@baseboard_fab2_lib.baseboard_fab2(sch_1):page167_i41@dev_discrete.cap_~
a(chips)',
 PATH='I41',
 DRAWING='@BASEBOARD_FAB2_LIB.BASEBOARD_FAB2(SCH_1):PAGE167',
 TOLERANCE='10%',
 SEC_TYPE='0402V',
 MATERIAL='X7R',
 BOM_COST='SM_THERM',
 PHYS_PAGE='167',
 XY='(-7700,3675)',
 ROT='0',
 VER='1',
 VALUE='0.1UF',
 PACK_TYPE='0402V',
 PART_NUMBER='A36096-030',
 LOCATION='C9R14',
 ROOM='TEMP_SENSORS',
 SEC='1',
 CDS_LIB='dev_discrete',
 CDS_PART_NAME='CAP_A_0402V-0.1UF,16V,10%,X7R,A',
 VOLTAGE='16V',
 PRIM_FILE='./archive_libs/discrete/cap_a/chips/chips.prt';

PART_NAME
 C9T3 'CAPP_3018-68UF,16V,20%,TANT,72A':;

SECTION_NUMBER 1
 '@BASEBOARD_FAB2_LIB.BASEBOARD_FAB2(SCH_1):PAGE195_I111@MSTR_DISCRETE.CAPP(CHIPS)':
 C_PATH='@baseboard_fab2_lib.baseboard_fab2(sch_1):page195_i111@mstr_discrete.ca~
pp(chips)',
 P_PATH='@baseboard_fab2_lib.baseboard_fab2(sch_1):page195_i111@mstr_discrete.ca~
pp(chips)',
 PATH='I111',
 DRAWING='@BASEBOARD_FAB2_LIB.BASEBOARD_FAB2(SCH_1):PAGE195',
 TOLERANCE='20%',
 SEC_TYPE='3018',
 MATERIAL='TANT',
 PHYS_PAGE='195',
 XY='(-6875,1950)',
 ROT='0',
 VER='1',
 VALUE='68UF',
 PACK_TYPE='3018',
 PART_NUMBER='724613-112',
 LOCATION='C9T3',
 SEC='1',
 CDS_LIB='mstr_discrete',
 CDS_PART_NAME='CAPP_3018-68UF,16V,20%,TANT,72A',
 VOLTAGE='16V',
 PRIM_FILE='./archive_libs/mstr_discrete/capp/chips/chips.prt';

PART_NAME
 C9T4 'CAP_0805-10UF,16V,10%,X6S,C953A':
 ROOM='VDDQ_GHJ_PWR_VR';

SECTION_NUMBER 1
 '@BASEBOARD_FAB2_LIB.BASEBOARD_FAB2(SCH_1):PAGE224_I47@MSTR_DISCRETE.CAP(CHIPS)':
 C_PATH='@baseboard_fab2_lib.baseboard_fab2(sch_1):page224_i47@mstr_discrete.cap~
(chips)',
 P_PATH='@baseboard_fab2_lib.baseboard_fab2(sch_1):page224_i47@mstr_discrete.cap~
(chips)',
 PATH='I47',
 DRAWING='@BASEBOARD_FAB2_LIB.BASEBOARD_FAB2(SCH_1):PAGE224',
 TOLERANCE='10%',
 SEC_TYPE='0805',
 MATERIAL='X6S',
 PHYS_PAGE='224',
 XY='(-1650,2500)',
 ROT='0',
 VER='1',
 VALUE='10UF',
 PACK_TYPE='0805',
 PART_NUMBER='C95333-007',
 LOCATION='C9T4',
 ROOM='VDDQ_GHJ_PWR_VR',
 SEC='1',
 CDS_LIB='mstr_discrete',
 CDS_PART_NAME='CAP_0805-10UF,16V,10%,X6S,C953A',
 VOLTAGE='16V',
 PRIM_FILE='./archive_libs/mstr_discrete/cap/chips/chips.prt';

PART_NAME
 C9T5 'CAPP_3018-470UF,2.5V,20%,ALUM,A':
 GROUP='PWR_BULK_CAP',
 ROOM='VDDQ_GHJ_PWR_VR';

SECTION_NUMBER 1
 '@BASEBOARD_FAB2_LIB.BASEBOARD_FAB2(SCH_1):PAGE225_I75@MSTR_DISCRETE.CAPP(CHIPS)':
 C_PATH='@baseboard_fab2_lib.baseboard_fab2(sch_1):page225_i75@mstr_discrete.cap~
p(chips)',
 P_PATH='@baseboard_fab2_lib.baseboard_fab2(sch_1):page225_i75@mstr_discrete.cap~
p(chips)',
 PATH='I75',
 DRAWING='@BASEBOARD_FAB2_LIB.BASEBOARD_FAB2(SCH_1):PAGE225',
 TOLERANCE='20%',
 SEC_TYPE='3018',
 MATERIAL='ALUM',
 PHYS_PAGE='225',
 XY='(3250,-50)',
 ROT='0',
 VER='1',
 VALUE='470UF',
 PACK_TYPE='3018',
 PART_NUMBER='699013-049',
 LOCATION='C9T5',
 ROOM='VDDQ_GHJ_PWR_VR',
 GROUP='PWR_BULK_CAP',
 SEC='1',
 CDS_LIB='mstr_discrete',
 CDS_PART_NAME='CAPP_3018-470UF,2.5V,20%,ALUM,A',
 VOLTAGE='2.5V',
 PRIM_FILE='./archive_libs/mstr_discrete/capp/chips/chips.prt';

PART_NAME
 C9T6 'CAP_0805-10UF,16V,10%,X6S,C953A':
 ROOM='VDDQ_GHJ_PWR_VR';

SECTION_NUMBER 1
 '@BASEBOARD_FAB2_LIB.BASEBOARD_FAB2(SCH_1):PAGE224_I81@MSTR_DISCRETE.CAP(CHIPS)':
 C_PATH='@baseboard_fab2_lib.baseboard_fab2(sch_1):page224_i81@mstr_discrete.cap~
(chips)',
 P_PATH='@baseboard_fab2_lib.baseboard_fab2(sch_1):page224_i81@mstr_discrete.cap~
(chips)',
 PATH='I81',
 DRAWING='@BASEBOARD_FAB2_LIB.BASEBOARD_FAB2(SCH_1):PAGE224',
 TOLERANCE='10%',
 SEC_TYPE='0805',
 MATERIAL='X6S',
 PHYS_PAGE='224',
 XY='(-1925,125)',
 ROT='0',
 VER='1',
 VALUE='10UF',
 PACK_TYPE='0805',
 PART_NUMBER='C95333-007',
 LOCATION='C9T6',
 ROOM='VDDQ_GHJ_PWR_VR',
 SEC='1',
 CDS_LIB='mstr_discrete',
 CDS_PART_NAME='CAP_0805-10UF,16V,10%,X6S,C953A',
 VOLTAGE='16V',
 PRIM_FILE='./archive_libs/mstr_discrete/cap/chips/chips.prt';

PART_NAME
 C9T7 'CAP_A_0402V-0.01UF,25V,10%,X7RA':
 ROOM='DDR4_GH_G';

SECTION_NUMBER 1
 '@BASEBOARD_FAB2_LIB.BASEBOARD_FAB2(SCH_1):PAGE78_I2@DEV_DISCRETE.CAP_A(CHIPS)':
 C_PATH='@baseboard_fab2_lib.baseboard_fab2(sch_1):page78_i2@dev_discrete.cap_a(~
chips)',
 P_PATH='@baseboard_fab2_lib.baseboard_fab2(sch_1):page78_i2@dev_discrete.cap_a(~
chips)',
 PATH='I2',
 DRAWING='@BASEBOARD_FAB2_LIB.BASEBOARD_FAB2(SCH_1):PAGE78',
 TOLERANCE='10%',
 MATERIAL='X7R',
 BOM_COST='MEM',
 PHYS_PAGE='78',
 XY='(-2675,875)',
 ROT='2',
 VER='1',
 VALUE='0.01UF',
 PACK_TYPE='0402V',
 PART_NUMBER='A36096-045',
 LOCATION='C9T7',
 ROOM='DDR4_GH_G',
 CDS_LIB='dev_discrete',
 CDS_PART_NAME='CAP_A_0402V-0.01UF,25V,10%,X7RA',
 VOLTAGE='25V',
 PRIM_FILE='./archive_libs/discrete/cap_a/chips/chips.prt';

PART_NAME
 C9T8 'CAP_0805-10UF,16V,10%,X7R,G106A':
 ROOM='PVDDQ_GHJ_PWR_VR';

SECTION_NUMBER 1
 '@BASEBOARD_FAB2_LIB.BASEBOARD_FAB2(SCH_1):PAGE197_I56@MSTR_DISCRETE.CAP(CHIPS)':
 C_PATH='@baseboard_fab2_lib.baseboard_fab2(sch_1):page197_i56@mstr_discrete.cap~
(chips)',
 P_PATH='@baseboard_fab2_lib.baseboard_fab2(sch_1):page197_i56@mstr_discrete.cap~
(chips)',
 PATH='I56',
 DRAWING='@BASEBOARD_FAB2_LIB.BASEBOARD_FAB2(SCH_1):PAGE197',
 TOLERANCE='10%',
 MATERIAL='X7R',
 PHYS_PAGE='197',
 XY='(1325,1275)',
 ROT='0',
 VER='1',
 VALUE='10UF',
 PACK_TYPE='0805',
 PART_NUMBER='G10601-001',
 LOCATION='C9T8',
 ROOM='PVDDQ_GHJ_PWR_VR',
 CDS_LIB='mstr_discrete',
 CDS_PART_NAME='CAP_0805-10UF,16V,10%,X7R,G106A',
 VOLTAGE='16V',
 PRIM_FILE='./archive_libs/mstr_discrete/cap/chips/chips.prt';

PART_NAME
 C9T9 'CAP_0805-10UF,16V,10%,X6S,C953A':
 ROOM='VDDQ_GHJ_PWR_VR';

SECTION_NUMBER 1
 '@BASEBOARD_FAB2_LIB.BASEBOARD_FAB2(SCH_1):PAGE224_I84@MSTR_DISCRETE.CAP(CHIPS)':
 C_PATH='@baseboard_fab2_lib.baseboard_fab2(sch_1):page224_i84@mstr_discrete.cap~
(chips)',
 P_PATH='@baseboard_fab2_lib.baseboard_fab2(sch_1):page224_i84@mstr_discrete.cap~
(chips)',
 PATH='I84',
 DRAWING='@BASEBOARD_FAB2_LIB.BASEBOARD_FAB2(SCH_1):PAGE224',
 TOLERANCE='10%',
 SEC_TYPE='0805',
 MATERIAL='X6S',
 PHYS_PAGE='224',
 XY='(-2200,125)',
 ROT='0',
 VER='1',
 VALUE='10UF',
 PACK_TYPE='0805',
 PART_NUMBER='C95333-007',
 LOCATION='C9T9',
 ROOM='VDDQ_GHJ_PWR_VR',
 SEC='1',
 CDS_LIB='mstr_discrete',
 CDS_PART_NAME='CAP_0805-10UF,16V,10%,X6S,C953A',
 VOLTAGE='16V',
 PRIM_FILE='./archive_libs/mstr_discrete/cap/chips/chips.prt';

PART_NAME
 C9U2 'CAPP_3018-470UF,2.5V,20%,ALUM,A':
 GROUP='PWR_BULK_CAP',
 ROOM='VDDQ_GHJ_PWR_VR';

SECTION_NUMBER 1
 '@BASEBOARD_FAB2_LIB.BASEBOARD_FAB2(SCH_1):PAGE225_I76@MSTR_DISCRETE.CAPP(CHIPS)':
 C_PATH='@baseboard_fab2_lib.baseboard_fab2(sch_1):page225_i76@mstr_discrete.cap~
p(chips)',
 P_PATH='@baseboard_fab2_lib.baseboard_fab2(sch_1):page225_i76@mstr_discrete.cap~
p(chips)',
 PATH='I76',
 DRAWING='@BASEBOARD_FAB2_LIB.BASEBOARD_FAB2(SCH_1):PAGE225',
 TOLERANCE='20%',
 SEC_TYPE='3018',
 MATERIAL='ALUM',
 PHYS_PAGE='225',
 XY='(3550,-50)',
 ROT='0',
 VER='1',
 VALUE='470UF',
 PACK_TYPE='3018',
 PART_NUMBER='699013-049',
 LOCATION='C9U2',
 ROOM='VDDQ_GHJ_PWR_VR',
 GROUP='PWR_BULK_CAP',
 SEC='1',
 CDS_LIB='mstr_discrete',
 CDS_PART_NAME='CAPP_3018-470UF,2.5V,20%,ALUM,A',
 VOLTAGE='2.5V',
 PRIM_FILE='./archive_libs/mstr_discrete/capp/chips/chips.prt';

PART_NAME
 C9U3 'CAP_0805-10UF,16V,10%,X6S,C953A':
 ROOM='VDDQ_GHJ_PWR_VR';

SECTION_NUMBER 1
 '@BASEBOARD_FAB2_LIB.BASEBOARD_FAB2(SCH_1):PAGE224_I80@MSTR_DISCRETE.CAP(CHIPS)':
 C_PATH='@baseboard_fab2_lib.baseboard_fab2(sch_1):page224_i80@mstr_discrete.cap~
(chips)',
 P_PATH='@baseboard_fab2_lib.baseboard_fab2(sch_1):page224_i80@mstr_discrete.cap~
(chips)',
 PATH='I80',
 DRAWING='@BASEBOARD_FAB2_LIB.BASEBOARD_FAB2(SCH_1):PAGE224',
 TOLERANCE='10%',
 SEC_TYPE='0805',
 MATERIAL='X6S',
 PHYS_PAGE='224',
 XY='(-1650,125)',
 ROT='0',
 VER='1',
 VALUE='10UF',
 PACK_TYPE='0805',
 PART_NUMBER='C95333-007',
 LOCATION='C9U3',
 ROOM='VDDQ_GHJ_PWR_VR',
 SEC='1',
 CDS_LIB='mstr_discrete',
 CDS_PART_NAME='CAP_0805-10UF,16V,10%,X6S,C953A',
 VOLTAGE='16V',
 PRIM_FILE='./archive_libs/mstr_discrete/cap/chips/chips.prt';

PART_NAME
 C9U4 'CAP_0805-10UF,16V,10%,X6S,C953A':
 ROOM='VDDQ_GHJ_PWR_VR';

SECTION_NUMBER 1
 '@BASEBOARD_FAB2_LIB.BASEBOARD_FAB2(SCH_1):PAGE224_I46@MSTR_DISCRETE.CAP(CHIPS)':
 C_PATH='@baseboard_fab2_lib.baseboard_fab2(sch_1):page224_i46@mstr_discrete.cap~
(chips)',
 P_PATH='@baseboard_fab2_lib.baseboard_fab2(sch_1):page224_i46@mstr_discrete.cap~
(chips)',
 PATH='I46',
 DRAWING='@BASEBOARD_FAB2_LIB.BASEBOARD_FAB2(SCH_1):PAGE224',
 TOLERANCE='10%',
 SEC_TYPE='0805',
 MATERIAL='X6S',
 PHYS_PAGE='224',
 XY='(-1900,2500)',
 ROT='0',
 VER='1',
 VALUE='10UF',
 PACK_TYPE='0805',
 PART_NUMBER='C95333-007',
 LOCATION='C9U4',
 ROOM='VDDQ_GHJ_PWR_VR',
 SEC='1',
 CDS_LIB='mstr_discrete',
 CDS_PART_NAME='CAP_0805-10UF,16V,10%,X6S,C953A',
 VOLTAGE='16V',
 PRIM_FILE='./archive_libs/mstr_discrete/cap/chips/chips.prt';

PART_NAME
 C9U5 'CAPP_3018-470UF,2.5V,20%,ALUM,A':
 GROUP='PWR_BULK_CAP',
 ROOM='VDDQ_GHJ_PWR_VR';

SECTION_NUMBER 1
 '@BASEBOARD_FAB2_LIB.BASEBOARD_FAB2(SCH_1):PAGE225_I78@MSTR_DISCRETE.CAPP(CHIPS)':
 C_PATH='@baseboard_fab2_lib.baseboard_fab2(sch_1):page225_i78@mstr_discrete.cap~
p(chips)',
 P_PATH='@baseboard_fab2_lib.baseboard_fab2(sch_1):page225_i78@mstr_discrete.cap~
p(chips)',
 PATH='I78',
 DRAWING='@BASEBOARD_FAB2_LIB.BASEBOARD_FAB2(SCH_1):PAGE225',
 TOLERANCE='20%',
 SEC_TYPE='3018',
 MATERIAL='ALUM',
 PHYS_PAGE='225',
 XY='(4150,-50)',
 ROT='0',
 VER='1',
 VALUE='470UF',
 PACK_TYPE='3018',
 PART_NUMBER='699013-049',
 LOCATION='C9U5',
 ROOM='VDDQ_GHJ_PWR_VR',
 GROUP='PWR_BULK_CAP',
 SEC='1',
 CDS_LIB='mstr_discrete',
 CDS_PART_NAME='CAPP_3018-470UF,2.5V,20%,ALUM,A',
 VOLTAGE='2.5V',
 PRIM_FILE='./archive_libs/mstr_discrete/capp/chips/chips.prt';

PART_NAME
 C9U6 'CAP_0805-10UF,16V,10%,X6S,C953A':
 ROOM='VDDQ_GHJ_PWR_VR';

SECTION_NUMBER 1
 '@BASEBOARD_FAB2_LIB.BASEBOARD_FAB2(SCH_1):PAGE224_I45@MSTR_DISCRETE.CAP(CHIPS)':
 C_PATH='@baseboard_fab2_lib.baseboard_fab2(sch_1):page224_i45@mstr_discrete.cap~
(chips)',
 P_PATH='@baseboard_fab2_lib.baseboard_fab2(sch_1):page224_i45@mstr_discrete.cap~
(chips)',
 PATH='I45',
 DRAWING='@BASEBOARD_FAB2_LIB.BASEBOARD_FAB2(SCH_1):PAGE224',
 TOLERANCE='10%',
 SEC_TYPE='0805',
 MATERIAL='X6S',
 PHYS_PAGE='224',
 XY='(-2150,2500)',
 ROT='0',
 VER='1',
 VALUE='10UF',
 PACK_TYPE='0805',
 PART_NUMBER='C95333-007',
 LOCATION='C9U6',
 ROOM='VDDQ_GHJ_PWR_VR',
 SEC='1',
 CDS_LIB='mstr_discrete',
 CDS_PART_NAME='CAP_0805-10UF,16V,10%,X6S,C953A',
 VOLTAGE='16V',
 PRIM_FILE='./archive_libs/mstr_discrete/cap/chips/chips.prt';

PART_NAME
 C9U7 'CAP_A_0402V-0.01UF,25V,10%,X7RA':
 ROOM='DDR4_CH_J';

SECTION_NUMBER 1
 '@BASEBOARD_FAB2_LIB.BASEBOARD_FAB2(SCH_1):PAGE79_I178@DEV_DISCRETE.CAP_A(CHIPS)':
 C_PATH='@baseboard_fab2_lib.baseboard_fab2(sch_1):page79_i178@dev_discrete.cap_~
a(chips)',
 P_PATH='@baseboard_fab2_lib.baseboard_fab2(sch_1):page79_i178@dev_discrete.cap_~
a(chips)',
 PATH='I178',
 DRAWING='@BASEBOARD_FAB2_LIB.BASEBOARD_FAB2(SCH_1):PAGE79',
 TOLERANCE='10%',
 MATERIAL='X7R',
 BOM_COST='MEM',
 PHYS_PAGE='79',
 XY='(-4600,1550)',
 ROT='2',
 VER='1',
 VALUE='0.01UF',
 PACK_TYPE='0402V',
 PART_NUMBER='A36096-045',
 LOCATION='C9U7',
 ROOM='DDR4_CH_J',
 CDS_LIB='dev_discrete',
 CDS_PART_NAME='CAP_A_0402V-0.01UF,25V,10%,X7RA',
 VOLTAGE='25V',
 PRIM_FILE='./archive_libs/discrete/cap_a/chips/chips.prt';

PART_NAME
 C9U8 'CAP_0805-10UF,16V,10%,X7R,G106A':
 ROOM='PVDDQ_GHJ_PWR_VR';

SECTION_NUMBER 1
 '@BASEBOARD_FAB2_LIB.BASEBOARD_FAB2(SCH_1):PAGE197_I66@MSTR_DISCRETE.CAP(CHIPS)':
 C_PATH='@baseboard_fab2_lib.baseboard_fab2(sch_1):page197_i66@mstr_discrete.cap~
(chips)',
 P_PATH='@baseboard_fab2_lib.baseboard_fab2(sch_1):page197_i66@mstr_discrete.cap~
(chips)',
 PATH='I66',
 DRAWING='@BASEBOARD_FAB2_LIB.BASEBOARD_FAB2(SCH_1):PAGE197',
 TOLERANCE='10%',
 MATERIAL='X7R',
 PHYS_PAGE='197',
 XY='(1325,2500)',
 ROT='0',
 VER='1',
 VALUE='10UF',
 PACK_TYPE='0805',
 PART_NUMBER='G10601-001',
 LOCATION='C9U8',
 ROOM='PVDDQ_GHJ_PWR_VR',
 CDS_LIB='mstr_discrete',
 CDS_PART_NAME='CAP_0805-10UF,16V,10%,X7R,G106A',
 VOLTAGE='16V',
 PRIM_FILE='./archive_libs/mstr_discrete/cap/chips/chips.prt';

PART_NAME
 C9U9 'CAPP_3018-470UF,2.5V,20%,ALUM,A':
 GROUP='PWR_BULK_CAP',
 ROOM='VDDQ_GHJ_PWR_VR';

SECTION_NUMBER 1
 '@BASEBOARD_FAB2_LIB.BASEBOARD_FAB2(SCH_1):PAGE225_I77@MSTR_DISCRETE.CAPP(CHIPS)':
 C_PATH='@baseboard_fab2_lib.baseboard_fab2(sch_1):page225_i77@mstr_discrete.cap~
p(chips)',
 P_PATH='@baseboard_fab2_lib.baseboard_fab2(sch_1):page225_i77@mstr_discrete.cap~
p(chips)',
 PATH='I77',
 DRAWING='@BASEBOARD_FAB2_LIB.BASEBOARD_FAB2(SCH_1):PAGE225',
 TOLERANCE='20%',
 SEC_TYPE='3018',
 MATERIAL='ALUM',
 PHYS_PAGE='225',
 XY='(3850,-50)',
 ROT='0',
 VER='1',
 VALUE='470UF',
 PACK_TYPE='3018',
 PART_NUMBER='699013-049',
 LOCATION='C9U9',
 ROOM='VDDQ_GHJ_PWR_VR',
 GROUP='PWR_BULK_CAP',
 SEC='1',
 CDS_LIB='mstr_discrete',
 CDS_PART_NAME='CAPP_3018-470UF,2.5V,20%,ALUM,A',
 VOLTAGE='2.5V',
 PRIM_FILE='./archive_libs/mstr_discrete/capp/chips/chips.prt';

PART_NAME
 C9U10 'CAP_A_0402V-0.01UF,25V,10%,X7RA':
 ROOM='DDR4_CH_J';

SECTION_NUMBER 1
 '@BASEBOARD_FAB2_LIB.BASEBOARD_FAB2(SCH_1):PAGE81_I178@DEV_DISCRETE.CAP_A(CHIPS)':
 C_PATH='@baseboard_fab2_lib.baseboard_fab2(sch_1):page81_i178@dev_discrete.cap_~
a(chips)',
 P_PATH='@baseboard_fab2_lib.baseboard_fab2(sch_1):page81_i178@dev_discrete.cap_~
a(chips)',
 PATH='I178',
 DRAWING='@BASEBOARD_FAB2_LIB.BASEBOARD_FAB2(SCH_1):PAGE81',
 TOLERANCE='10%',
 MATERIAL='X7R',
 BOM_COST='MEM',
 PHYS_PAGE='81',
 XY='(-4550,1450)',
 ROT='2',
 VER='1',
 VALUE='0.01UF',
 PACK_TYPE='0402V',
 PART_NUMBER='A36096-045',
 LOCATION='C9U10',
 ROOM='DDR4_CH_J',
 CDS_LIB='dev_discrete',
 CDS_PART_NAME='CAP_A_0402V-0.01UF,25V,10%,X7RA',
 VOLTAGE='25V',
 PRIM_FILE='./archive_libs/discrete/cap_a/chips/chips.prt';

PART_NAME
 C9U11 'CAP_0805-10UF,16V,10%,X7R,G106A':
 ROOM='PVDDQ_GHJ_PWR_VR';

SECTION_NUMBER 1
 '@BASEBOARD_FAB2_LIB.BASEBOARD_FAB2(SCH_1):PAGE197_I63@MSTR_DISCRETE.CAP(CHIPS)':
 C_PATH='@baseboard_fab2_lib.baseboard_fab2(sch_1):page197_i63@mstr_discrete.cap~
(chips)',
 P_PATH='@baseboard_fab2_lib.baseboard_fab2(sch_1):page197_i63@mstr_discrete.cap~
(chips)',
 PATH='I63',
 DRAWING='@BASEBOARD_FAB2_LIB.BASEBOARD_FAB2(SCH_1):PAGE197',
 TOLERANCE='10%',
 MATERIAL='X7R',
 PHYS_PAGE='197',
 XY='(1325,1850)',
 ROT='0',
 VER='1',
 VALUE='10UF',
 PACK_TYPE='0805',
 PART_NUMBER='G10601-001',
 LOCATION='C9U11',
 ROOM='PVDDQ_GHJ_PWR_VR',
 CDS_LIB='mstr_discrete',
 CDS_PART_NAME='CAP_0805-10UF,16V,10%,X7R,G106A',
 VOLTAGE='16V',
 PRIM_FILE='./archive_libs/mstr_discrete/cap/chips/chips.prt';

PART_NAME
 C9W1 'SC22P50V2JN-4GP_SMD-BCG-SC22P5A':;

SECTION_NUMBER 1
 '@BASEBOARD_FAB2_LIB.BASEBOARD_FAB2(SCH_1):PAGE200_I235@W_HDL.SC22P50V2JN-4GP(CHIPS)':
 C_PATH='@baseboard_fab2_lib.baseboard_fab2(sch_1):page200_i235@w_hdl.\sc22p50v2~
jn-4gp\(chips)',
 P_PATH='@baseboard_fab2_lib.baseboard_fab2(sch_1):page200_i235@w_hdl.\sc22p50v2~
jn-4gp\(chips)',
 PATH='I235',
 DRAWING='@BASEBOARD_FAB2_LIB.BASEBOARD_FAB2(SCH_1):PAGE200',
 TYPE='NPO',
 PACK_SIZE='0402',
 RATED='50V',
 ATTRIBUTE='22PF',
 POP='NOPOP',
 TOLERANCE='5%',
 SEC_TYPE='SMD-BCG',
 PHYS_PAGE='200',
 XY='(-700,-100)',
 ROT='0',
 VER='1',
 VALUE='SC22P50V2JN-4GP',
 PACK_TYPE='SMD-BCG',
 PART_NUMBER='78.22034.1FL',
 LOCATION='C9W1',
 SEC='1',
 CDS_LIB='w_hdl',
 CDS_PART_NAME='SC22P50V2JN-4GP_SMD-BCG-SC22P5A',
 PRIM_FILE='C:/<user>/w_hdl/sc22p50v2jn#2d4gp/chips/chips.prt';

PART_NAME
 C9W2 'SC22P50V2JN-4GP_SMD-BCG-SC22P5A':;

SECTION_NUMBER 1
 '@BASEBOARD_FAB2_LIB.BASEBOARD_FAB2(SCH_1):PAGE200_I236@W_HDL.SC22P50V2JN-4GP(CHIPS)':
 C_PATH='@baseboard_fab2_lib.baseboard_fab2(sch_1):page200_i236@w_hdl.\sc22p50v2~
jn-4gp\(chips)',
 P_PATH='@baseboard_fab2_lib.baseboard_fab2(sch_1):page200_i236@w_hdl.\sc22p50v2~
jn-4gp\(chips)',
 PATH='I236',
 DRAWING='@BASEBOARD_FAB2_LIB.BASEBOARD_FAB2(SCH_1):PAGE200',
 TYPE='NPO',
 PACK_SIZE='0402',
 RATED='50V',
 ATTRIBUTE='22PF',
 POP='NOPOP',
 TOLERANCE='5%',
 SEC_TYPE='SMD-BCG',
 PHYS_PAGE='200',
 XY='(-1050,175)',
 ROT='0',
 VER='1',
 VALUE='SC22P50V2JN-4GP',
 PACK_TYPE='SMD-BCG',
 PART_NUMBER='78.22034.1FL',
 LOCATION='C9W2',
 SEC='1',
 CDS_LIB='w_hdl',
 CDS_PART_NAME='SC22P50V2JN-4GP_SMD-BCG-SC22P5A',
 PRIM_FILE='C:/<user>/w_hdl/sc22p50v2jn#2d4gp/chips/chips.prt';

PART_NAME
 C9W5 'CAP_A_0402V-0.1UF,16V,10%,X7R,A':;

SECTION_NUMBER 1
 '@BASEBOARD_FAB2_LIB.BASEBOARD_FAB2(SCH_1):PAGE239_I90@DEV_DISCRETE.CAP_A(CHIPS)':
 C_PATH='@baseboard_fab2_lib.baseboard_fab2(sch_1):page239_i90@dev_discrete.cap_~
a(chips)',
 P_PATH='@baseboard_fab2_lib.baseboard_fab2(sch_1):page239_i90@dev_discrete.cap_~
a(chips)',
 PATH='I90',
 DRAWING='@BASEBOARD_FAB2_LIB.BASEBOARD_FAB2(SCH_1):PAGE239',
 TOLERANCE='10%',
 SEC_TYPE='0402V',
 MATERIAL='X7R',
 PHYS_PAGE='239',
 XY='(7250,2075)',
 ROT='0',
 VER='1',
 VALUE='0.1UF',
 PACK_TYPE='0402V',
 PART_NUMBER='A36096-030',
 LOCATION='C9W5',
 SEC='1',
 CDS_LIB='dev_discrete',
 CDS_PART_NAME='CAP_A_0402V-0.1UF,16V,10%,X7R,A',
 VOLTAGE='16V',
 PRIM_FILE='./archive_libs/discrete/cap_a/chips/chips.prt';

PART_NAME
 C9W6 'CAP_0402LF-1000PF,50V,10%,EMPTA':
 ROOM='P1V538_BMC_STBY_VR';

SECTION_NUMBER 1
 '@BASEBOARD_FAB2_LIB.BASEBOARD_FAB2(SCH_1):PAGE239_I91@MSTR_DISCRETE.CAP(CHIPS)':
 C_PATH='@baseboard_fab2_lib.baseboard_fab2(sch_1):page239_i91@mstr_discrete.cap~
(chips)',
 P_PATH='@baseboard_fab2_lib.baseboard_fab2(sch_1):page239_i91@mstr_discrete.cap~
(chips)',
 PATH='I91',
 DRAWING='@BASEBOARD_FAB2_LIB.BASEBOARD_FAB2(SCH_1):PAGE239',
 TOLERANCE='10%',
 SEC_TYPE='0402LF',
 MATERIAL='EMPTY',
 BOM_COST='P1V538_BMC_STBY_VR',
 PHYS_PAGE='239',
 XY='(6625,1225)',
 ROT='2',
 VER='1',
 VALUE='1000PF',
 PACK_TYPE='0402LF',
 PART_NUMBER='A36096-046',
 LOCATION='C9W6',
 ROOM='P1V538_BMC_STBY_VR',
 SEC='1',
 CDS_LIB='mstr_discrete',
 CDS_PART_NAME='CAP_0402LF-1000PF,50V,10%,EMPTA',
 VOLTAGE='50V',
 PRIM_FILE='./archive_libs/mstr_discrete/cap/chips/chips.prt';

PART_NAME
 C9W7 'CAP_A_0402V-0.1UF,16V,10%,X7R,A':
 ROOM='SMB_PE_HP_CPU1';

SECTION_NUMBER 1
 '@BASEBOARD_FAB2_LIB.BASEBOARD_FAB2(SCH_1):PAGE248_I32@DEV_DISCRETE.CAP_A(CHIPS)':
 C_PATH='@baseboard_fab2_lib.baseboard_fab2(sch_1):page248_i32@dev_discrete.cap_~
a(chips)',
 P_PATH='@baseboard_fab2_lib.baseboard_fab2(sch_1):page248_i32@dev_discrete.cap_~
a(chips)',
 PATH='I32',
 DRAWING='@BASEBOARD_FAB2_LIB.BASEBOARD_FAB2(SCH_1):PAGE248',
 TOLERANCE='10%',
 SEC_TYPE='0402V',
 MATERIAL='X7R',
 PHYS_PAGE='248',
 XY='(-3525,4050)',
 ROT='2',
 VER='1',
 VALUE='0.1UF',
 PACK_TYPE='0402V',
 PART_NUMBER='A36096-030',
 LOCATION='C9W7',
 ROOM='SMB_PE_HP_CPU1',
 SEC='1',
 CDS_LIB='dev_discrete',
 CDS_PART_NAME='CAP_A_0402V-0.1UF,16V,10%,X7R,A',
 VOLTAGE='16V',
 PRIM_FILE='./archive_libs/discrete/cap_a/chips/chips.prt';

PART_NAME
 C9W8 'CAP_A_0402V-0.1UF,16V,10%,X7R,A':
 ROOM='SMB_PE_HP_CPU1';

SECTION_NUMBER 1
 '@BASEBOARD_FAB2_LIB.BASEBOARD_FAB2(SCH_1):PAGE248_I30@DEV_DISCRETE.CAP_A(CHIPS)':
 C_PATH='@baseboard_fab2_lib.baseboard_fab2(sch_1):page248_i30@dev_discrete.cap_~
a(chips)',
 P_PATH='@baseboard_fab2_lib.baseboard_fab2(sch_1):page248_i30@dev_discrete.cap_~
a(chips)',
 PATH='I30',
 DRAWING='@BASEBOARD_FAB2_LIB.BASEBOARD_FAB2(SCH_1):PAGE248',
 TOLERANCE='10%',
 SEC_TYPE='0402V',
 MATERIAL='X7R',
 PHYS_PAGE='248',
 XY='(-4200,4050)',
 ROT='0',
 VER='1',
 VALUE='0.1UF',
 PACK_TYPE='0402V',
 PART_NUMBER='A36096-030',
 LOCATION='C9W8',
 ROOM='SMB_PE_HP_CPU1',
 SEC='1',
 CDS_LIB='dev_discrete',
 CDS_PART_NAME='CAP_A_0402V-0.1UF,16V,10%,X7R,A',
 VOLTAGE='16V',
 PRIM_FILE='./archive_libs/discrete/cap_a/chips/chips.prt';

PART_NAME
 C9W10 'CAP_0402LF-1000PF,50V,10%,X7R,A':
 ROOM='P1V538_BMC_STBY_VR';

SECTION_NUMBER 1
 '@BASEBOARD_FAB2_LIB.BASEBOARD_FAB2(SCH_1):PAGE239_I84@MSTR_DISCRETE.CAP(CHIPS)':
 C_PATH='@baseboard_fab2_lib.baseboard_fab2(sch_1):page239_i84@mstr_discrete.cap~
(chips)',
 P_PATH='@baseboard_fab2_lib.baseboard_fab2(sch_1):page239_i84@mstr_discrete.cap~
(chips)',
 PATH='I84',
 DRAWING='@BASEBOARD_FAB2_LIB.BASEBOARD_FAB2(SCH_1):PAGE239',
 TOLERANCE='10%',
 SEC_TYPE='0402LF',
 MATERIAL='X7R',
 BOM_COST='P1V538_BMC_STBY_VR',
 PHYS_PAGE='239',
 XY='(9950,2075)',
 ROT='0',
 VER='1',
 VALUE='1000PF',
 PACK_TYPE='0402LF',
 PART_NUMBER='A36096-046',
 LOCATION='C9W10',
 ROOM='P1V538_BMC_STBY_VR',
 SEC='1',
 CDS_LIB='mstr_discrete',
 CDS_PART_NAME='CAP_0402LF-1000PF,50V,10%,X7R,A',
 VOLTAGE='50V',
 PRIM_FILE='./archive_libs/mstr_discrete/cap/chips/chips.prt';

PART_NAME
 C9W13 'CAP_0805LF-22UF,4V,20%,X6S,C95A':
 ROOM='P1V538_BMC_STBY_VR';

SECTION_NUMBER 1
 '@BASEBOARD_FAB2_LIB.BASEBOARD_FAB2(SCH_1):PAGE239_I81@MSTR_DISCRETE.CAP(CHIPS)':
 C_PATH='@baseboard_fab2_lib.baseboard_fab2(sch_1):page239_i81@mstr_discrete.cap~
(chips)',
 P_PATH='@baseboard_fab2_lib.baseboard_fab2(sch_1):page239_i81@mstr_discrete.cap~
(chips)',
 PATH='I81',
 DRAWING='@BASEBOARD_FAB2_LIB.BASEBOARD_FAB2(SCH_1):PAGE239',
 TOLERANCE='20%',
 SEC_TYPE='0805LF',
 MATERIAL='X6S',
 BOM_COST='P1V538_BMC_STBY_VR',
 PHYS_PAGE='239',
 XY='(11300,1500)',
 ROT='0',
 VER='1',
 VALUE='22UF',
 PACK_TYPE='0805LF',
 PART_NUMBER='C95333-002',
 LOCATION='C9W13',
 ROOM='P1V538_BMC_STBY_VR',
 SEC='1',
 CDS_LIB='mstr_discrete',
 CDS_PART_NAME='CAP_0805LF-22UF,4V,20%,X6S,C95A',
 VOLTAGE='4V',
 PRIM_FILE='./archive_libs/mstr_discrete/cap/chips/chips.prt';

PART_NAME
 C9W14 'CAP_0603-10UF,6.3V,20%,X6S,E15A':
 ROOM='P1V26_BMC_STBY_VR';

SECTION_NUMBER 1
 '@BASEBOARD_FAB2_LIB.BASEBOARD_FAB2(SCH_1):PAGE238_I46@MSTR_DISCRETE.CAP(CHIPS)':
 C_PATH='@baseboard_fab2_lib.baseboard_fab2(sch_1):page238_i46@mstr_discrete.cap~
(chips)',
 P_PATH='@baseboard_fab2_lib.baseboard_fab2(sch_1):page238_i46@mstr_discrete.cap~
(chips)',
 PATH='I46',
 DRAWING='@BASEBOARD_FAB2_LIB.BASEBOARD_FAB2(SCH_1):PAGE238',
 POP='NOPOP',
 TOLERANCE='20%',
 SEC_TYPE='0603',
 MATERIAL='X6S',
 BOM_COST='P1V26_BMC_STBY_VR',
 PHYS_PAGE='238',
 XY='(-2050,3050)',
 ROT='0',
 VER='1',
 VALUE='10UF',
 PACK_TYPE='0603',
 PART_NUMBER='E15431-002',
 LOCATION='C9W14',
 ROOM='P1V26_BMC_STBY_VR',
 SEC='1',
 CDS_LIB='mstr_discrete',
 CDS_PART_NAME='CAP_0603-10UF,6.3V,20%,X6S,E15A',
 VOLTAGE='6.3V',
 PRIM_FILE='./archive_libs/mstr_discrete/cap/chips/chips.prt';

PART_NAME
 C9W16 'CAP_A_0603V-22.0UF,4V,20%,X6S,A':
 ROOM='PVCCIN_CPU0_DECAP_VR';

SECTION_NUMBER 1
 '@BASEBOARD_FAB2_LIB.BASEBOARD_FAB2(SCH_1):PAGE238_I50@DEV_DISCRETE.CAP_A(CHIPS)':
 C_PATH='@baseboard_fab2_lib.baseboard_fab2(sch_1):page238_i50@dev_discrete.cap_~
a(chips)',
 P_PATH='@baseboard_fab2_lib.baseboard_fab2(sch_1):page238_i50@dev_discrete.cap_~
a(chips)',
 PATH='I50',
 DRAWING='@BASEBOARD_FAB2_LIB.BASEBOARD_FAB2(SCH_1):PAGE238',
 POP='NOPOP',
 TOLERANCE='20%',
 MATERIAL='X6S',
 BOM_COST='PROC_SOCKET',
 PHYS_PAGE='238',
 XY='(1950,2550)',
 ROT='0',
 VER='1',
 VALUE='22.0UF',
 PACK_TYPE='0603V',
 PART_NUMBER='E15431-004',
 LOCATION='C9W16',
 ROOM='PVCCIN_CPU0_DECAP_VR',
 CDS_LIB='dev_discrete',
 CDS_PART_NAME='CAP_A_0603V-22.0UF,4V,20%,X6S,A',
 VOLTAGE='4V',
 PRIM_FILE='./archive_libs/discrete/cap_a/chips/chips.prt';

PART_NAME
 C9W17 'CAP_0603-10UF,6.3V,20%,X6S,E15A':
 ROOM='P1V26_BMC_STBY_VR';

SECTION_NUMBER 1
 '@BASEBOARD_FAB2_LIB.BASEBOARD_FAB2(SCH_1):PAGE239_I104@MSTR_DISCRETE.CAP(CHIPS)':
 C_PATH='@baseboard_fab2_lib.baseboard_fab2(sch_1):page239_i104@mstr_discrete.ca~
p(chips)',
 P_PATH='@baseboard_fab2_lib.baseboard_fab2(sch_1):page239_i104@mstr_discrete.ca~
p(chips)',
 PATH='I104',
 DRAWING='@BASEBOARD_FAB2_LIB.BASEBOARD_FAB2(SCH_1):PAGE239',
 POP='NOPOP',
 TOLERANCE='20%',
 SEC_TYPE='0603',
 MATERIAL='X6S',
 BOM_COST='P1V26_BMC_STBY_VR',
 PHYS_PAGE='239',
 XY='(6550,4250)',
 ROT='0',
 VER='1',
 VALUE='10UF',
 PACK_TYPE='0603',
 PART_NUMBER='E15431-002',
 LOCATION='C9W17',
 ROOM='P1V26_BMC_STBY_VR',
 SEC='1',
 CDS_LIB='mstr_discrete',
 CDS_PART_NAME='CAP_0603-10UF,6.3V,20%,X6S,E15A',
 VOLTAGE='6.3V',
 PRIM_FILE='./archive_libs/mstr_discrete/cap/chips/chips.prt';

PART_NAME
 C9W19 'CAP_A_0603V-22.0UF,4V,20%,X6S,A':
 ROOM='PVCCIN_CPU0_DECAP_VR';

SECTION_NUMBER 1
 '@BASEBOARD_FAB2_LIB.BASEBOARD_FAB2(SCH_1):PAGE239_I111@DEV_DISCRETE.CAP_A(CHIPS)':
 C_PATH='@baseboard_fab2_lib.baseboard_fab2(sch_1):page239_i111@dev_discrete.cap~
_a(chips)',
 P_PATH='@baseboard_fab2_lib.baseboard_fab2(sch_1):page239_i111@dev_discrete.cap~
_a(chips)',
 PATH='I111',
 DRAWING='@BASEBOARD_FAB2_LIB.BASEBOARD_FAB2(SCH_1):PAGE239',
 POP='NOPOP',
 TOLERANCE='20%',
 MATERIAL='X6S',
 BOM_COST='PROC_SOCKET',
 PHYS_PAGE='239',
 XY='(11250,3650)',
 ROT='0',
 VER='1',
 VALUE='22.0UF',
 PACK_TYPE='0603V',
 PART_NUMBER='E15431-004',
 LOCATION='C9W19',
 ROOM='PVCCIN_CPU0_DECAP_VR',
 CDS_LIB='dev_discrete',
 CDS_PART_NAME='CAP_A_0603V-22.0UF,4V,20%,X6S,A',
 VOLTAGE='4V',
 PRIM_FILE='./archive_libs/discrete/cap_a/chips/chips.prt';

PART_NAME
 C10W1 'CAP_0805-10UF,16V,10%,X6S,C953A':
 ROOM='CPU_FANS';

SECTION_NUMBER 1
 '@BASEBOARD_FAB2_LIB.BASEBOARD_FAB2(SCH_1):PAGE251_I3@MSTR_DISCRETE.CAP(CHIPS)':
 C_PATH='@baseboard_fab2_lib.baseboard_fab2(sch_1):page251_i3@mstr_discrete.cap(~
chips)',
 P_PATH='@baseboard_fab2_lib.baseboard_fab2(sch_1):page251_i3@mstr_discrete.cap(~
chips)',
 PATH='I3',
 DRAWING='@BASEBOARD_FAB2_LIB.BASEBOARD_FAB2(SCH_1):PAGE251',
 TOLERANCE='10%',
 SEC_TYPE='0805',
 MATERIAL='X6S',
 BOM_COST='SM_THERM',
 PHYS_PAGE='251',
 XY='(-2075,5825)',
 ROT='0',
 VER='1',
 VALUE='10UF',
 PACK_TYPE='0805',
 PART_NUMBER='C95333-007',
 LOCATION='C10W1',
 ROOM='CPU_FANS',
 SEC='1',
 CDS_LIB='mstr_discrete',
 CDS_PART_NAME='CAP_0805-10UF,16V,10%,X6S,C953A',
 VOLTAGE='16V',
 PRIM_FILE='./archive_libs/mstr_discrete/cap/chips/chips.prt';

PART_NAME
 C10W2 'CAP_A_0402V-0.1UF,16V,10%,X7R,A':
 ROOM='CPU_FANS';

SECTION_NUMBER 1
 '@BASEBOARD_FAB2_LIB.BASEBOARD_FAB2(SCH_1):PAGE251_I1@DEV_DISCRETE.CAP_A(CHIPS)':
 C_PATH='@baseboard_fab2_lib.baseboard_fab2(sch_1):page251_i1@dev_discrete.cap_a~
(chips)',
 P_PATH='@baseboard_fab2_lib.baseboard_fab2(sch_1):page251_i1@dev_discrete.cap_a~
(chips)',
 PATH='I1',
 DRAWING='@BASEBOARD_FAB2_LIB.BASEBOARD_FAB2(SCH_1):PAGE251',
 TOLERANCE='10%',
 SEC_TYPE='0402V',
 MATERIAL='X7R',
 BOM_COST='SM_THERM',
 PHYS_PAGE='251',
 XY='(-1775,5825)',
 ROT='0',
 VER='1',
 VALUE='0.1UF',
 PACK_TYPE='0402V',
 PART_NUMBER='A36096-030',
 LOCATION='C10W2',
 ROOM='CPU_FANS',
 SEC='1',
 CDS_LIB='dev_discrete',
 CDS_PART_NAME='CAP_A_0402V-0.1UF,16V,10%,X7R,A',
 VOLTAGE='16V',
 PRIM_FILE='./archive_libs/discrete/cap_a/chips/chips.prt';

PART_NAME
 C10W3 'CAP_A_0402V-0.01UF,25V,10%,X7RA':
 ROOM='CPU_FANS';

SECTION_NUMBER 1
 '@BASEBOARD_FAB2_LIB.BASEBOARD_FAB2(SCH_1):PAGE251_I16@DEV_DISCRETE.CAP_A(CHIPS)':
 C_PATH='@baseboard_fab2_lib.baseboard_fab2(sch_1):page251_i16@dev_discrete.cap_~
a(chips)',
 P_PATH='@baseboard_fab2_lib.baseboard_fab2(sch_1):page251_i16@dev_discrete.cap_~
a(chips)',
 PATH='I16',
 DRAWING='@BASEBOARD_FAB2_LIB.BASEBOARD_FAB2(SCH_1):PAGE251',
 TOLERANCE='10%',
 SEC_TYPE='0402V',
 MATERIAL='X7R',
 BOM_COST='SM_THERM',
 PHYS_PAGE='251',
 XY='(-5175,5050)',
 ROT='2',
 VER='1',
 VALUE='0.01UF',
 PACK_TYPE='0402V',
 PART_NUMBER='A36096-045',
 LOCATION='C10W3',
 ROOM='CPU_FANS',
 SEC='1',
 CDS_LIB='dev_discrete',
 CDS_PART_NAME='CAP_A_0402V-0.01UF,25V,10%,X7RA',
 VOLTAGE='25V',
 PRIM_FILE='./archive_libs/discrete/cap_a/chips/chips.prt';

PART_NAME
 C10W4 'CAP_A_0402V-0.1UF,16V,10%,X7R,A':
 ROOM='CPU_FANS';

SECTION_NUMBER 1
 '@BASEBOARD_FAB2_LIB.BASEBOARD_FAB2(SCH_1):PAGE251_I21@DEV_DISCRETE.CAP_A(CHIPS)':
 C_PATH='@baseboard_fab2_lib.baseboard_fab2(sch_1):page251_i21@dev_discrete.cap_~
a(chips)',
 P_PATH='@baseboard_fab2_lib.baseboard_fab2(sch_1):page251_i21@dev_discrete.cap_~
a(chips)',
 PATH='I21',
 DRAWING='@BASEBOARD_FAB2_LIB.BASEBOARD_FAB2(SCH_1):PAGE251',
 TOLERANCE='10%',
 SEC_TYPE='0402V',
 MATERIAL='X7R',
 BOM_COST='SM_THERM',
 PHYS_PAGE='251',
 XY='(-6650,4900)',
 ROT='0',
 VER='1',
 VALUE='0.1UF',
 PACK_TYPE='0402V',
 PART_NUMBER='A36096-030',
 LOCATION='C10W4',
 ROOM='CPU_FANS',
 SEC='1',
 CDS_LIB='dev_discrete',
 CDS_PART_NAME='CAP_A_0402V-0.1UF,16V,10%,X7R,A',
 VOLTAGE='16V',
 PRIM_FILE='./archive_libs/discrete/cap_a/chips/chips.prt';

PART_NAME
 C10W5 'CAP_A_0402V-0.01UF,25V,10%,X7RA':
 ROOM='CPU_FANS';

SECTION_NUMBER 1
 '@BASEBOARD_FAB2_LIB.BASEBOARD_FAB2(SCH_1):PAGE251_I29@DEV_DISCRETE.CAP_A(CHIPS)':
 C_PATH='@baseboard_fab2_lib.baseboard_fab2(sch_1):page251_i29@dev_discrete.cap_~
a(chips)',
 P_PATH='@baseboard_fab2_lib.baseboard_fab2(sch_1):page251_i29@dev_discrete.cap_~
a(chips)',
 PATH='I29',
 DRAWING='@BASEBOARD_FAB2_LIB.BASEBOARD_FAB2(SCH_1):PAGE251',
 TOLERANCE='10%',
 SEC_TYPE='0402V',
 MATERIAL='X7R',
 BOM_COST='SM_THERM',
 PHYS_PAGE='251',
 XY='(-5175,3500)',
 ROT='2',
 VER='1',
 VALUE='0.01UF',
 PACK_TYPE='0402V',
 PART_NUMBER='A36096-045',
 LOCATION='C10W5',
 ROOM='CPU_FANS',
 SEC='1',
 CDS_LIB='dev_discrete',
 CDS_PART_NAME='CAP_A_0402V-0.01UF,25V,10%,X7RA',
 VOLTAGE='25V',
 PRIM_FILE='./archive_libs/discrete/cap_a/chips/chips.prt';

PART_NAME
 C12W1 'CAP_0402LF-47.0PF,50V,5%,COG,AA':
 ROOM='BMC_VOLT_MONITOR';

SECTION_NUMBER 1
 '@BASEBOARD_FAB2_LIB.BASEBOARD_FAB2(SCH_1):PAGE197_I8@MSTR_DISCRETE.CAP(CHIPS)':
 C_PATH='@baseboard_fab2_lib.baseboard_fab2(sch_1):page197_i8@mstr_discrete.cap(~
chips)',
 P_PATH='@baseboard_fab2_lib.baseboard_fab2(sch_1):page197_i8@mstr_discrete.cap(~
chips)',
 PATH='I8',
 DRAWING='@BASEBOARD_FAB2_LIB.BASEBOARD_FAB2(SCH_1):PAGE197',
 TOLERANCE='5%',
 SEC_TYPE='0402LF',
 MATERIAL='COG',
 BOM_COST='SM_HM',
 PHYS_PAGE='197',
 XY='(-4275,3550)',
 ROT='1',
 VER='1',
 VALUE='47.0PF',
 PACK_TYPE='0402LF',
 PART_NUMBER='A36095-025',
 LOCATION='C12W1',
 ROOM='BMC_VOLT_MONITOR',
 SEC='1',
 CDS_LIB='mstr_discrete',
 CDS_PART_NAME='CAP_0402LF-47.0PF,50V,5%,COG,AA',
 VOLTAGE='50V',
 PRIM_FILE='./archive_libs/mstr_discrete/cap/chips/chips.prt';

PART_NAME
 C12W2 'CAP_0402LF-47.0PF,50V,5%,COG,AA':
 ROOM='BMC_VOLT_MONITOR';

SECTION_NUMBER 1
 '@BASEBOARD_FAB2_LIB.BASEBOARD_FAB2(SCH_1):PAGE197_I1@MSTR_DISCRETE.CAP(CHIPS)':
 C_PATH='@baseboard_fab2_lib.baseboard_fab2(sch_1):page197_i1@mstr_discrete.cap(~
chips)',
 P_PATH='@baseboard_fab2_lib.baseboard_fab2(sch_1):page197_i1@mstr_discrete.cap(~
chips)',
 PATH='I1',
 DRAWING='@BASEBOARD_FAB2_LIB.BASEBOARD_FAB2(SCH_1):PAGE197',
 TOLERANCE='5%',
 SEC_TYPE='0402LF',
 MATERIAL='COG',
 BOM_COST='SM_HM',
 PHYS_PAGE='197',
 XY='(-4275,1450)',
 ROT='1',
 VER='1',
 VALUE='47.0PF',
 PACK_TYPE='0402LF',
 PART_NUMBER='A36095-025',
 LOCATION='C12W2',
 ROOM='BMC_VOLT_MONITOR',
 SEC='1',
 CDS_LIB='mstr_discrete',
 CDS_PART_NAME='CAP_0402LF-47.0PF,50V,5%,COG,AA',
 VOLTAGE='50V',
 PRIM_FILE='./archive_libs/mstr_discrete/cap/chips/chips.prt';

PART_NAME
 C12W3 'CAP_0402LF-47.0PF,50V,5%,COG,AA':
 ROOM='BMC_VOLT_MONITOR';

SECTION_NUMBER 1
 '@BASEBOARD_FAB2_LIB.BASEBOARD_FAB2(SCH_1):PAGE197_I42@MSTR_DISCRETE.CAP(CHIPS)':
 C_PATH='@baseboard_fab2_lib.baseboard_fab2(sch_1):page197_i42@mstr_discrete.cap~
(chips)',
 P_PATH='@baseboard_fab2_lib.baseboard_fab2(sch_1):page197_i42@mstr_discrete.cap~
(chips)',
 PATH='I42',
 DRAWING='@BASEBOARD_FAB2_LIB.BASEBOARD_FAB2(SCH_1):PAGE197',
 TOLERANCE='5%',
 SEC_TYPE='0402LF',
 MATERIAL='COG',
 BOM_COST='SM_HM',
 PHYS_PAGE='197',
 XY='(-1725,3550)',
 ROT='1',
 VER='1',
 VALUE='47.0PF',
 PACK_TYPE='0402LF',
 PART_NUMBER='A36095-025',
 LOCATION='C12W3',
 ROOM='BMC_VOLT_MONITOR',
 SEC='1',
 CDS_LIB='mstr_discrete',
 CDS_PART_NAME='CAP_0402LF-47.0PF,50V,5%,COG,AA',
 VOLTAGE='50V',
 PRIM_FILE='./archive_libs/mstr_discrete/cap/chips/chips.prt';

PART_NAME
 C12W4 'CAP_0402LF-47.0PF,50V,5%,COG,AA':
 ROOM='BMC_VOLT_MONITOR';

SECTION_NUMBER 1
 '@BASEBOARD_FAB2_LIB.BASEBOARD_FAB2(SCH_1):PAGE197_I18@MSTR_DISCRETE.CAP(CHIPS)':
 C_PATH='@baseboard_fab2_lib.baseboard_fab2(sch_1):page197_i18@mstr_discrete.cap~
(chips)',
 P_PATH='@baseboard_fab2_lib.baseboard_fab2(sch_1):page197_i18@mstr_discrete.cap~
(chips)',
 PATH='I18',
 DRAWING='@BASEBOARD_FAB2_LIB.BASEBOARD_FAB2(SCH_1):PAGE197',
 TOLERANCE='5%',
 SEC_TYPE='0402LF',
 MATERIAL='COG',
 BOM_COST='SM_HM',
 PHYS_PAGE='197',
 XY='(-1725,1450)',
 ROT='1',
 VER='1',
 VALUE='47.0PF',
 PACK_TYPE='0402LF',
 PART_NUMBER='A36095-025',
 LOCATION='C12W4',
 ROOM='BMC_VOLT_MONITOR',
 SEC='1',
 CDS_LIB='mstr_discrete',
 CDS_PART_NAME='CAP_0402LF-47.0PF,50V,5%,COG,AA',
 VOLTAGE='50V',
 PRIM_FILE='./archive_libs/mstr_discrete/cap/chips/chips.prt';

PART_NAME
 C14W1 'CAP_A_0402V-0.1UF,16V,10%,X7R,A':
 ROOM='CPUFANS';

SECTION_NUMBER 1
 '@BASEBOARD_FAB2_LIB.BASEBOARD_FAB2(SCH_1):PAGE248_I13@DEV_DISCRETE.CAP_A(CHIPS)':
 C_PATH='@baseboard_fab2_lib.baseboard_fab2(sch_1):page248_i13@dev_discrete.cap_~
a(chips)',
 P_PATH='@baseboard_fab2_lib.baseboard_fab2(sch_1):page248_i13@dev_discrete.cap_~
a(chips)',
 PATH='I13',
 DRAWING='@BASEBOARD_FAB2_LIB.BASEBOARD_FAB2(SCH_1):PAGE248',
 TOLERANCE='10%',
 SEC_TYPE='0402V',
 MATERIAL='X7R',
 BOM_COST='SM_THERM',
 PHYS_PAGE='248',
 XY='(-2750,2025)',
 ROT='0',
 VER='1',
 VALUE='0.1UF',
 PACK_TYPE='0402V',
 PART_NUMBER='A36096-030',
 LOCATION='C14W1',
 ROOM='CPUFANS',
 SEC='1',
 CDS_LIB='dev_discrete',
 CDS_PART_NAME='CAP_A_0402V-0.1UF,16V,10%,X7R,A',
 VOLTAGE='16V',
 PRIM_FILE='./archive_libs/discrete/cap_a/chips/chips.prt';

PART_NAME
 C14W2 'CAP_A_0402V-0.1UF,16V,10%,X7R,A':
 ROOM='CPUFANS';

SECTION_NUMBER 1
 '@BASEBOARD_FAB2_LIB.BASEBOARD_FAB2(SCH_1):PAGE248_I17@DEV_DISCRETE.CAP_A(CHIPS)':
 C_PATH='@baseboard_fab2_lib.baseboard_fab2(sch_1):page248_i17@dev_discrete.cap_~
a(chips)',
 P_PATH='@baseboard_fab2_lib.baseboard_fab2(sch_1):page248_i17@dev_discrete.cap_~
a(chips)',
 PATH='I17',
 DRAWING='@BASEBOARD_FAB2_LIB.BASEBOARD_FAB2(SCH_1):PAGE248',
 TOLERANCE='10%',
 SEC_TYPE='0402V',
 MATERIAL='X7R',
 BOM_COST='SM_THERM',
 PHYS_PAGE='248',
 XY='(-3700,1175)',
 ROT='0',
 VER='1',
 VALUE='0.1UF',
 PACK_TYPE='0402V',
 PART_NUMBER='A36096-030',
 LOCATION='C14W2',
 ROOM='CPUFANS',
 SEC='1',
 CDS_LIB='dev_discrete',
 CDS_PART_NAME='CAP_A_0402V-0.1UF,16V,10%,X7R,A',
 VOLTAGE='16V',
 PRIM_FILE='./archive_libs/discrete/cap_a/chips/chips.prt';

PART_NAME
 C22W1 'SC22U16V5MX-4-GP_SMD-BCG5-SC22A':;

SECTION_NUMBER 1
 '@BASEBOARD_FAB2_LIB.BASEBOARD_FAB2(SCH_1):PAGE225_I246@W_HDL.SC22U16V5MX-4-GP(CHIPS)':
 C_PATH='@baseboard_fab2_lib.baseboard_fab2(sch_1):page225_i246@w_hdl.\sc22u16v5~
mx-4-gp\(chips)',
 P_PATH='@baseboard_fab2_lib.baseboard_fab2(sch_1):page225_i246@w_hdl.\sc22u16v5~
mx-4-gp\(chips)',
 PATH='I246',
 DRAWING='@BASEBOARD_FAB2_LIB.BASEBOARD_FAB2(SCH_1):PAGE225',
 TYPE='X6S',
 PACK_SIZE='0805',
 RATED='16V',
 ATTRIBUTE='22UF',
 TOLERANCE='20%',
 SEC_TYPE='SMD-BCG5',
 PHYS_PAGE='225',
 XY='(-250,1150)',
 ROT='0',
 VER='1',
 VALUE='SC22U16V5MX-4-GP',
 PACK_TYPE='SMD-BCG5',
 PART_NUMBER='078.22611.0811',
 LOCATION='C22W1',
 SEC='1',
 CDS_LIB='w_hdl',
 CDS_PART_NAME='SC22U16V5MX-4-GP_SMD-BCG5-SC22A',
 PRIM_FILE='C:/<user>/w_hdl/sc22u16v5mx#2d4#2dgp/chips/chips.prt';

PART_NAME
 C22W2 'SC22U16V5MX-4-GP_SMD-BCG5-SC22A':;

SECTION_NUMBER 1
 '@BASEBOARD_FAB2_LIB.BASEBOARD_FAB2(SCH_1):PAGE225_I247@W_HDL.SC22U16V5MX-4-GP(CHIPS)':
 C_PATH='@baseboard_fab2_lib.baseboard_fab2(sch_1):page225_i247@w_hdl.\sc22u16v5~
mx-4-gp\(chips)',
 P_PATH='@baseboard_fab2_lib.baseboard_fab2(sch_1):page225_i247@w_hdl.\sc22u16v5~
mx-4-gp\(chips)',
 PATH='I247',
 DRAWING='@BASEBOARD_FAB2_LIB.BASEBOARD_FAB2(SCH_1):PAGE225',
 TYPE='X6S',
 PACK_SIZE='0805',
 RATED='16V',
 ATTRIBUTE='22UF',
 TOLERANCE='20%',
 SEC_TYPE='SMD-BCG5',
 PHYS_PAGE='225',
 XY='(-950,1150)',
 ROT='0',
 VER='1',
 VALUE='SC22U16V5MX-4-GP',
 PACK_TYPE='SMD-BCG5',
 PART_NUMBER='078.22611.0811',
 LOCATION='C22W2',
 SEC='1',
 CDS_LIB='w_hdl',
 CDS_PART_NAME='SC22U16V5MX-4-GP_SMD-BCG5-SC22A',
 PRIM_FILE='C:/<user>/w_hdl/sc22u16v5mx#2d4#2dgp/chips/chips.prt';

PART_NAME
 C22W3 'SC22U16V5MX-4-GP_SMD-BCG5-SC22A':;

SECTION_NUMBER 1
 '@BASEBOARD_FAB2_LIB.BASEBOARD_FAB2(SCH_1):PAGE225_I249@W_HDL.SC22U16V5MX-4-GP(CHIPS)':
 C_PATH='@baseboard_fab2_lib.baseboard_fab2(sch_1):page225_i249@w_hdl.\sc22u16v5~
mx-4-gp\(chips)',
 P_PATH='@baseboard_fab2_lib.baseboard_fab2(sch_1):page225_i249@w_hdl.\sc22u16v5~
mx-4-gp\(chips)',
 PATH='I249',
 DRAWING='@BASEBOARD_FAB2_LIB.BASEBOARD_FAB2(SCH_1):PAGE225',
 TYPE='X6S',
 PACK_SIZE='0805',
 RATED='16V',
 ATTRIBUTE='22UF',
 TOLERANCE='20%',
 SEC_TYPE='SMD-BCG5',
 PHYS_PAGE='225',
 XY='(450,1150)',
 ROT='0',
 VER='1',
 VALUE='SC22U16V5MX-4-GP',
 PACK_TYPE='SMD-BCG5',
 PART_NUMBER='078.22611.0811',
 LOCATION='C22W3',
 SEC='1',
 CDS_LIB='w_hdl',
 CDS_PART_NAME='SC22U16V5MX-4-GP_SMD-BCG5-SC22A',
 PRIM_FILE='C:/<user>/w_hdl/sc22u16v5mx#2d4#2dgp/chips/chips.prt';

PART_NAME
 C22W4 'SC22U16V5MX-4-GP_SMD-BCG5-SC22A':;

SECTION_NUMBER 1
 '@BASEBOARD_FAB2_LIB.BASEBOARD_FAB2(SCH_1):PAGE225_I251@W_HDL.SC22U16V5MX-4-GP(CHIPS)':
 C_PATH='@baseboard_fab2_lib.baseboard_fab2(sch_1):page225_i251@w_hdl.\sc22u16v5~
mx-4-gp\(chips)',
 P_PATH='@baseboard_fab2_lib.baseboard_fab2(sch_1):page225_i251@w_hdl.\sc22u16v5~
mx-4-gp\(chips)',
 PATH='I251',
 DRAWING='@BASEBOARD_FAB2_LIB.BASEBOARD_FAB2(SCH_1):PAGE225',
 TYPE='X6S',
 PACK_SIZE='0805',
 RATED='16V',
 ATTRIBUTE='22UF',
 TOLERANCE='20%',
 SEC_TYPE='SMD-BCG5',
 PHYS_PAGE='225',
 XY='(1150,1150)',
 ROT='0',
 VER='1',
 VALUE='SC22U16V5MX-4-GP',
 PACK_TYPE='SMD-BCG5',
 PART_NUMBER='078.22611.0811',
 LOCATION='C22W4',
 SEC='1',
 CDS_LIB='w_hdl',
 CDS_PART_NAME='SC22U16V5MX-4-GP_SMD-BCG5-SC22A',
 PRIM_FILE='C:/<user>/w_hdl/sc22u16v5mx#2d4#2dgp/chips/chips.prt';

PART_NAME
 C22W5 'SC22U16V5MX-4-GP_SMD-BCG5-SC22A':;

SECTION_NUMBER 1
 '@BASEBOARD_FAB2_LIB.BASEBOARD_FAB2(SCH_1):PAGE234_I222@W_HDL.SC22U16V5MX-4-GP(CHIPS)':
 C_PATH='@baseboard_fab2_lib.baseboard_fab2(sch_1):page234_i222@w_hdl.\sc22u16v5~
mx-4-gp\(chips)',
 P_PATH='@baseboard_fab2_lib.baseboard_fab2(sch_1):page234_i222@w_hdl.\sc22u16v5~
mx-4-gp\(chips)',
 PATH='I222',
 DRAWING='@BASEBOARD_FAB2_LIB.BASEBOARD_FAB2(SCH_1):PAGE234',
 TYPE='X6S',
 PACK_SIZE='0805',
 RATED='16V',
 ATTRIBUTE='22UF',
 TOLERANCE='20%',
 SEC_TYPE='SMD-BCG5',
 PHYS_PAGE='234',
 XY='(-7050,4100)',
 ROT='0',
 VER='1',
 VALUE='SC22U16V5MX-4-GP',
 PACK_TYPE='SMD-BCG5',
 PART_NUMBER='078.22611.0811',
 LOCATION='C22W5',
 SEC='1',
 CDS_LIB='w_hdl',
 CDS_PART_NAME='SC22U16V5MX-4-GP_SMD-BCG5-SC22A',
 PRIM_FILE='C:/<user>/w_hdl/sc22u16v5mx#2d4#2dgp/chips/chips.prt';

PART_NAME
 C22W6 'SC22U16V5MX-4-GP_SMD-BCG5-SC22A':;

SECTION_NUMBER 1
 '@BASEBOARD_FAB2_LIB.BASEBOARD_FAB2(SCH_1):PAGE233_I278@W_HDL.SC22U16V5MX-4-GP(CHIPS)':
 C_PATH='@baseboard_fab2_lib.baseboard_fab2(sch_1):page233_i278@w_hdl.\sc22u16v5~
mx-4-gp\(chips)',
 P_PATH='@baseboard_fab2_lib.baseboard_fab2(sch_1):page233_i278@w_hdl.\sc22u16v5~
mx-4-gp\(chips)',
 PATH='I278',
 DRAWING='@BASEBOARD_FAB2_LIB.BASEBOARD_FAB2(SCH_1):PAGE233',
 TYPE='X6S',
 PACK_SIZE='0805',
 RATED='16V',
 ATTRIBUTE='22UF',
 TOLERANCE='20%',
 SEC_TYPE='SMD-BCG5',
 PHYS_PAGE='233',
 XY='(-7000,3950)',
 ROT='0',
 VER='1',
 VALUE='SC22U16V5MX-4-GP',
 PACK_TYPE='SMD-BCG5',
 PART_NUMBER='078.22611.0811',
 LOCATION='C22W6',
 SEC='1',
 CDS_LIB='w_hdl',
 CDS_PART_NAME='SC22U16V5MX-4-GP_SMD-BCG5-SC22A',
 PRIM_FILE='C:/<user>/w_hdl/sc22u16v5mx#2d4#2dgp/chips/chips.prt';

PART_NAME
 C22W7 'SC22U16V5MX-4-GP_SMD-BCG5-SC22A':;

SECTION_NUMBER 1
 '@BASEBOARD_FAB2_LIB.BASEBOARD_FAB2(SCH_1):PAGE232_I311@W_HDL.SC22U16V5MX-4-GP(CHIPS)':
 C_PATH='@baseboard_fab2_lib.baseboard_fab2(sch_1):page232_i311@w_hdl.\sc22u16v5~
mx-4-gp\(chips)',
 P_PATH='@baseboard_fab2_lib.baseboard_fab2(sch_1):page232_i311@w_hdl.\sc22u16v5~
mx-4-gp\(chips)',
 PATH='I311',
 DRAWING='@BASEBOARD_FAB2_LIB.BASEBOARD_FAB2(SCH_1):PAGE232',
 TYPE='X6S',
 PACK_SIZE='0805',
 RATED='16V',
 ATTRIBUTE='22UF',
 TOLERANCE='20%',
 SEC_TYPE='SMD-BCG5',
 PHYS_PAGE='232',
 XY='(-7300,4100)',
 ROT='0',
 VER='1',
 VALUE='SC22U16V5MX-4-GP',
 PACK_TYPE='SMD-BCG5',
 PART_NUMBER='078.22611.0811',
 LOCATION='C22W7',
 SEC='1',
 CDS_LIB='w_hdl',
 CDS_PART_NAME='SC22U16V5MX-4-GP_SMD-BCG5-SC22A',
 PRIM_FILE='C:/<user>/w_hdl/sc22u16v5mx#2d4#2dgp/chips/chips.prt';

PART_NAME
 C22W8 'SC22U16V5MX-4-GP_SMD-BCG5-SC22A':;

SECTION_NUMBER 1
 '@BASEBOARD_FAB2_LIB.BASEBOARD_FAB2(SCH_1):PAGE241_I96@W_HDL.SC22U16V5MX-4-GP(CHIPS)':
 C_PATH='@baseboard_fab2_lib.baseboard_fab2(sch_1):page241_i96@w_hdl.\sc22u16v5m~
x-4-gp\(chips)',
 P_PATH='@baseboard_fab2_lib.baseboard_fab2(sch_1):page241_i96@w_hdl.\sc22u16v5m~
x-4-gp\(chips)',
 PATH='I96',
 DRAWING='@BASEBOARD_FAB2_LIB.BASEBOARD_FAB2(SCH_1):PAGE241',
 TYPE='X6S',
 PACK_SIZE='0805',
 RATED='16V',
 ATTRIBUTE='22UF',
 TOLERANCE='20%',
 SEC_TYPE='SMD-BCG5',
 PHYS_PAGE='241',
 XY='(-2750,4325)',
 ROT='0',
 VER='1',
 VALUE='SC22U16V5MX-4-GP',
 PACK_TYPE='SMD-BCG5',
 PART_NUMBER='078.22611.0811',
 LOCATION='C22W8',
 SEC='1',
 CDS_LIB='w_hdl',
 CDS_PART_NAME='SC22U16V5MX-4-GP_SMD-BCG5-SC22A',
 PRIM_FILE='C:/<user>/w_hdl/sc22u16v5mx#2d4#2dgp/chips/chips.prt';

PART_NAME
 C22W9 'SC22U16V5MX-4-GP_SMD-BCG5-SC22A':;

SECTION_NUMBER 1
 '@BASEBOARD_FAB2_LIB.BASEBOARD_FAB2(SCH_1):PAGE241_I95@W_HDL.SC22U16V5MX-4-GP(CHIPS)':
 C_PATH='@baseboard_fab2_lib.baseboard_fab2(sch_1):page241_i95@w_hdl.\sc22u16v5m~
x-4-gp\(chips)',
 P_PATH='@baseboard_fab2_lib.baseboard_fab2(sch_1):page241_i95@w_hdl.\sc22u16v5m~
x-4-gp\(chips)',
 PATH='I95',
 DRAWING='@BASEBOARD_FAB2_LIB.BASEBOARD_FAB2(SCH_1):PAGE241',
 TYPE='X6S',
 PACK_SIZE='0805',
 RATED='16V',
 ATTRIBUTE='22UF',
 TOLERANCE='20%',
 SEC_TYPE='SMD-BCG5',
 PHYS_PAGE='241',
 XY='(-2100,4325)',
 ROT='0',
 VER='1',
 VALUE='SC22U16V5MX-4-GP',
 PACK_TYPE='SMD-BCG5',
 PART_NUMBER='078.22611.0811',
 LOCATION='C22W9',
 SEC='1',
 CDS_LIB='w_hdl',
 CDS_PART_NAME='SC22U16V5MX-4-GP_SMD-BCG5-SC22A',
 PRIM_FILE='C:/<user>/w_hdl/sc22u16v5mx#2d4#2dgp/chips/chips.prt';

PART_NAME
 C22W10 'SC22U16V5MX-4-GP_SMD-BCG5-SC22A':;

SECTION_NUMBER 1
 '@BASEBOARD_FAB2_LIB.BASEBOARD_FAB2(SCH_1):PAGE231_I225@W_HDL.SC22U16V5MX-4-GP(CHIPS)':
 C_PATH='@baseboard_fab2_lib.baseboard_fab2(sch_1):page231_i225@w_hdl.\sc22u16v5~
mx-4-gp\(chips)',
 P_PATH='@baseboard_fab2_lib.baseboard_fab2(sch_1):page231_i225@w_hdl.\sc22u16v5~
mx-4-gp\(chips)',
 PATH='I225',
 DRAWING='@BASEBOARD_FAB2_LIB.BASEBOARD_FAB2(SCH_1):PAGE231',
 TYPE='X6S',
 PACK_SIZE='0805',
 RATED='16V',
 ATTRIBUTE='22UF',
 TOLERANCE='20%',
 SEC_TYPE='SMD-BCG5',
 PHYS_PAGE='231',
 XY='(-6650,4325)',
 ROT='0',
 VER='1',
 VALUE='SC22U16V5MX-4-GP',
 PACK_TYPE='SMD-BCG5',
 PART_NUMBER='078.22611.0811',
 LOCATION='C22W10',
 SEC='1',
 CDS_LIB='w_hdl',
 CDS_PART_NAME='SC22U16V5MX-4-GP_SMD-BCG5-SC22A',
 PRIM_FILE='C:/<user>/w_hdl/sc22u16v5mx#2d4#2dgp/chips/chips.prt';

PART_NAME
 C22W11 'SC22U16V5MX-4-GP_SMD-BCG5-SC22A':;

SECTION_NUMBER 1
 '@BASEBOARD_FAB2_LIB.BASEBOARD_FAB2(SCH_1):PAGE240_I182@W_HDL.SC22U16V5MX-4-GP(CHIPS)':
 C_PATH='@baseboard_fab2_lib.baseboard_fab2(sch_1):page240_i182@w_hdl.\sc22u16v5~
mx-4-gp\(chips)',
 P_PATH='@baseboard_fab2_lib.baseboard_fab2(sch_1):page240_i182@w_hdl.\sc22u16v5~
mx-4-gp\(chips)',
 PATH='I182',
 DRAWING='@BASEBOARD_FAB2_LIB.BASEBOARD_FAB2(SCH_1):PAGE240',
 TYPE='X6S',
 PACK_SIZE='0805',
 RATED='16V',
 ATTRIBUTE='22UF',
 TOLERANCE='20%',
 SEC_TYPE='SMD-BCG5',
 PHYS_PAGE='240',
 XY='(7000,4275)',
 ROT='0',
 VER='1',
 VALUE='SC22U16V5MX-4-GP',
 PACK_TYPE='SMD-BCG5',
 PART_NUMBER='078.22611.0811',
 LOCATION='C22W11',
 SEC='1',
 CDS_LIB='w_hdl',
 CDS_PART_NAME='SC22U16V5MX-4-GP_SMD-BCG5-SC22A',
 PRIM_FILE='C:/<user>/w_hdl/sc22u16v5mx#2d4#2dgp/chips/chips.prt';

PART_NAME
 C22W12 'SC22U16V5MX-4-GP_SMD-BCG5-SC22A':;

SECTION_NUMBER 1
 '@BASEBOARD_FAB2_LIB.BASEBOARD_FAB2(SCH_1):PAGE240_I186@W_HDL.SC22U16V5MX-4-GP(CHIPS)':
 C_PATH='@baseboard_fab2_lib.baseboard_fab2(sch_1):page240_i186@w_hdl.\sc22u16v5~
mx-4-gp\(chips)',
 P_PATH='@baseboard_fab2_lib.baseboard_fab2(sch_1):page240_i186@w_hdl.\sc22u16v5~
mx-4-gp\(chips)',
 PATH='I186',
 DRAWING='@BASEBOARD_FAB2_LIB.BASEBOARD_FAB2(SCH_1):PAGE240',
 TYPE='X6S',
 PACK_SIZE='0805',
 RATED='16V',
 ATTRIBUTE='22UF',
 TOLERANCE='20%',
 SEC_TYPE='SMD-BCG5',
 PHYS_PAGE='240',
 XY='(7800,4275)',
 ROT='0',
 VER='1',
 VALUE='SC22U16V5MX-4-GP',
 PACK_TYPE='SMD-BCG5',
 PART_NUMBER='078.22611.0811',
 LOCATION='C22W12',
 SEC='1',
 CDS_LIB='w_hdl',
 CDS_PART_NAME='SC22U16V5MX-4-GP_SMD-BCG5-SC22A',
 PRIM_FILE='C:/<user>/w_hdl/sc22u16v5mx#2d4#2dgp/chips/chips.prt';

PART_NAME
 C22W13 'SC22U16V5MX-4-GP_SMD-BCG5-SC22A':;

SECTION_NUMBER 1
 '@BASEBOARD_FAB2_LIB.BASEBOARD_FAB2(SCH_1):PAGE214_I149@W_HDL.SC22U16V5MX-4-GP(CHIPS)':
 C_PATH='@baseboard_fab2_lib.baseboard_fab2(sch_1):page214_i149@w_hdl.\sc22u16v5~
mx-4-gp\(chips)',
 P_PATH='@baseboard_fab2_lib.baseboard_fab2(sch_1):page214_i149@w_hdl.\sc22u16v5~
mx-4-gp\(chips)',
 PATH='I149',
 DRAWING='@BASEBOARD_FAB2_LIB.BASEBOARD_FAB2(SCH_1):PAGE214',
 TYPE='X6S',
 PACK_SIZE='0805',
 RATED='16V',
 ATTRIBUTE='22UF',
 TOLERANCE='20%',
 SEC_TYPE='SMD-BCG5',
 PHYS_PAGE='214',
 XY='(550,1200)',
 ROT='0',
 VER='1',
 VALUE='SC22U16V5MX-4-GP',
 PACK_TYPE='SMD-BCG5',
 PART_NUMBER='078.22611.0811',
 LOCATION='C22W13',
 SEC='1',
 CDS_LIB='w_hdl',
 CDS_PART_NAME='SC22U16V5MX-4-GP_SMD-BCG5-SC22A',
 PRIM_FILE='C:/<user>/w_hdl/sc22u16v5mx#2d4#2dgp/chips/chips.prt';

PART_NAME
 C22W14 'SC22U16V5MX-4-GP_SMD-BCG5-SC22A':;

SECTION_NUMBER 1
 '@BASEBOARD_FAB2_LIB.BASEBOARD_FAB2(SCH_1):PAGE214_I152@W_HDL.SC22U16V5MX-4-GP(CHIPS)':
 C_PATH='@baseboard_fab2_lib.baseboard_fab2(sch_1):page214_i152@w_hdl.\sc22u16v5~
mx-4-gp\(chips)',
 P_PATH='@baseboard_fab2_lib.baseboard_fab2(sch_1):page214_i152@w_hdl.\sc22u16v5~
mx-4-gp\(chips)',
 PATH='I152',
 DRAWING='@BASEBOARD_FAB2_LIB.BASEBOARD_FAB2(SCH_1):PAGE214',
 TYPE='X6S',
 PACK_SIZE='0805',
 RATED='16V',
 ATTRIBUTE='22UF',
 TOLERANCE='20%',
 SEC_TYPE='SMD-BCG5',
 PHYS_PAGE='214',
 XY='(850,1200)',
 ROT='0',
 VER='1',
 VALUE='SC22U16V5MX-4-GP',
 PACK_TYPE='SMD-BCG5',
 PART_NUMBER='078.22611.0811',
 LOCATION='C22W14',
 SEC='1',
 CDS_LIB='w_hdl',
 CDS_PART_NAME='SC22U16V5MX-4-GP_SMD-BCG5-SC22A',
 PRIM_FILE='C:/<user>/w_hdl/sc22u16v5mx#2d4#2dgp/chips/chips.prt';

PART_NAME
 C22W15 'SC22U16V5MX-4-GP_SMD-BCG5-SC22A':;

SECTION_NUMBER 1
 '@BASEBOARD_FAB2_LIB.BASEBOARD_FAB2(SCH_1):PAGE214_I154@W_HDL.SC22U16V5MX-4-GP(CHIPS)':
 C_PATH='@baseboard_fab2_lib.baseboard_fab2(sch_1):page214_i154@w_hdl.\sc22u16v5~
mx-4-gp\(chips)',
 P_PATH='@baseboard_fab2_lib.baseboard_fab2(sch_1):page214_i154@w_hdl.\sc22u16v5~
mx-4-gp\(chips)',
 PATH='I154',
 DRAWING='@BASEBOARD_FAB2_LIB.BASEBOARD_FAB2(SCH_1):PAGE214',
 TYPE='X6S',
 PACK_SIZE='0805',
 RATED='16V',
 ATTRIBUTE='22UF',
 TOLERANCE='20%',
 SEC_TYPE='SMD-BCG5',
 PHYS_PAGE='214',
 XY='(1150,1200)',
 ROT='0',
 VER='1',
 VALUE='SC22U16V5MX-4-GP',
 PACK_TYPE='SMD-BCG5',
 PART_NUMBER='078.22611.0811',
 LOCATION='C22W15',
 SEC='1',
 CDS_LIB='w_hdl',
 CDS_PART_NAME='SC22U16V5MX-4-GP_SMD-BCG5-SC22A',
 PRIM_FILE='C:/<user>/w_hdl/sc22u16v5mx#2d4#2dgp/chips/chips.prt';

PART_NAME
 C22W16 'SC22U16V5MX-4-GP_SMD-BCG5-SC22A':;

SECTION_NUMBER 1
 '@BASEBOARD_FAB2_LIB.BASEBOARD_FAB2(SCH_1):PAGE214_I160@W_HDL.SC22U16V5MX-4-GP(CHIPS)':
 C_PATH='@baseboard_fab2_lib.baseboard_fab2(sch_1):page214_i160@w_hdl.\sc22u16v5~
mx-4-gp\(chips)',
 P_PATH='@baseboard_fab2_lib.baseboard_fab2(sch_1):page214_i160@w_hdl.\sc22u16v5~
mx-4-gp\(chips)',
 PATH='I160',
 DRAWING='@BASEBOARD_FAB2_LIB.BASEBOARD_FAB2(SCH_1):PAGE214',
 TYPE='X6S',
 PACK_SIZE='0805',
 RATED='16V',
 ATTRIBUTE='22UF',
 TOLERANCE='20%',
 SEC_TYPE='SMD-BCG5',
 PHYS_PAGE='214',
 XY='(1900,1200)',
 ROT='0',
 VER='1',
 VALUE='SC22U16V5MX-4-GP',
 PACK_TYPE='SMD-BCG5',
 PART_NUMBER='078.22611.0811',
 LOCATION='C22W16',
 SEC='1',
 CDS_LIB='w_hdl',
 CDS_PART_NAME='SC22U16V5MX-4-GP_SMD-BCG5-SC22A',
 PRIM_FILE='C:/<user>/w_hdl/sc22u16v5mx#2d4#2dgp/chips/chips.prt';

PART_NAME
 C22W17 'SC22U16V5MX-4-GP_SMD-BCG5-SC22A':;

SECTION_NUMBER 1
 '@BASEBOARD_FAB2_LIB.BASEBOARD_FAB2(SCH_1):PAGE214_I158@W_HDL.SC22U16V5MX-4-GP(CHIPS)':
 C_PATH='@baseboard_fab2_lib.baseboard_fab2(sch_1):page214_i158@w_hdl.\sc22u16v5~
mx-4-gp\(chips)',
 P_PATH='@baseboard_fab2_lib.baseboard_fab2(sch_1):page214_i158@w_hdl.\sc22u16v5~
mx-4-gp\(chips)',
 PATH='I158',
 DRAWING='@BASEBOARD_FAB2_LIB.BASEBOARD_FAB2(SCH_1):PAGE214',
 TYPE='X6S',
 PACK_SIZE='0805',
 RATED='16V',
 ATTRIBUTE='22UF',
 TOLERANCE='20%',
 SEC_TYPE='SMD-BCG5',
 PHYS_PAGE='214',
 XY='(2200,1200)',
 ROT='0',
 VER='1',
 VALUE='SC22U16V5MX-4-GP',
 PACK_TYPE='SMD-BCG5',
 PART_NUMBER='078.22611.0811',
 LOCATION='C22W17',
 SEC='1',
 CDS_LIB='w_hdl',
 CDS_PART_NAME='SC22U16V5MX-4-GP_SMD-BCG5-SC22A',
 PRIM_FILE='C:/<user>/w_hdl/sc22u16v5mx#2d4#2dgp/chips/chips.prt';

PART_NAME
 C22W18 'SC22U16V5MX-4-GP_SMD-BCG5-SC22A':;

SECTION_NUMBER 1
 '@BASEBOARD_FAB2_LIB.BASEBOARD_FAB2(SCH_1):PAGE214_I156@W_HDL.SC22U16V5MX-4-GP(CHIPS)':
 C_PATH='@baseboard_fab2_lib.baseboard_fab2(sch_1):page214_i156@w_hdl.\sc22u16v5~
mx-4-gp\(chips)',
 P_PATH='@baseboard_fab2_lib.baseboard_fab2(sch_1):page214_i156@w_hdl.\sc22u16v5~
mx-4-gp\(chips)',
 PATH='I156',
 DRAWING='@BASEBOARD_FAB2_LIB.BASEBOARD_FAB2(SCH_1):PAGE214',
 TYPE='X6S',
 PACK_SIZE='0805',
 RATED='16V',
 ATTRIBUTE='22UF',
 TOLERANCE='20%',
 SEC_TYPE='SMD-BCG5',
 PHYS_PAGE='214',
 XY='(2500,1200)',
 ROT='0',
 VER='1',
 VALUE='SC22U16V5MX-4-GP',
 PACK_TYPE='SMD-BCG5',
 PART_NUMBER='078.22611.0811',
 LOCATION='C22W18',
 SEC='1',
 CDS_LIB='w_hdl',
 CDS_PART_NAME='SC22U16V5MX-4-GP_SMD-BCG5-SC22A',
 PRIM_FILE='C:/<user>/w_hdl/sc22u16v5mx#2d4#2dgp/chips/chips.prt';

PART_NAME
 C22W19 'SC22U16V5MX-4-GP_SMD-BCG5-SC22A':;

SECTION_NUMBER 1
 '@BASEBOARD_FAB2_LIB.BASEBOARD_FAB2(SCH_1):PAGE214_I169@W_HDL.SC22U16V5MX-4-GP(CHIPS)':
 C_PATH='@baseboard_fab2_lib.baseboard_fab2(sch_1):page214_i169@w_hdl.\sc22u16v5~
mx-4-gp\(chips)',
 P_PATH='@baseboard_fab2_lib.baseboard_fab2(sch_1):page214_i169@w_hdl.\sc22u16v5~
mx-4-gp\(chips)',
 PATH='I169',
 DRAWING='@BASEBOARD_FAB2_LIB.BASEBOARD_FAB2(SCH_1):PAGE214',
 TYPE='X6S',
 PACK_SIZE='0805',
 RATED='16V',
 ATTRIBUTE='22UF',
 TOLERANCE='20%',
 SEC_TYPE='SMD-BCG5',
 PHYS_PAGE='214',
 XY='(3250,1200)',
 ROT='0',
 VER='1',
 VALUE='SC22U16V5MX-4-GP',
 PACK_TYPE='SMD-BCG5',
 PART_NUMBER='078.22611.0811',
 LOCATION='C22W19',
 SEC='1',
 CDS_LIB='w_hdl',
 CDS_PART_NAME='SC22U16V5MX-4-GP_SMD-BCG5-SC22A',
 PRIM_FILE='C:/<user>/w_hdl/sc22u16v5mx#2d4#2dgp/chips/chips.prt';

PART_NAME
 C22W20 'SC22U16V5MX-4-GP_SMD-BCG5-SC22A':;

SECTION_NUMBER 1
 '@BASEBOARD_FAB2_LIB.BASEBOARD_FAB2(SCH_1):PAGE214_I168@W_HDL.SC22U16V5MX-4-GP(CHIPS)':
 C_PATH='@baseboard_fab2_lib.baseboard_fab2(sch_1):page214_i168@w_hdl.\sc22u16v5~
mx-4-gp\(chips)',
 P_PATH='@baseboard_fab2_lib.baseboard_fab2(sch_1):page214_i168@w_hdl.\sc22u16v5~
mx-4-gp\(chips)',
 PATH='I168',
 DRAWING='@BASEBOARD_FAB2_LIB.BASEBOARD_FAB2(SCH_1):PAGE214',
 TYPE='X6S',
 PACK_SIZE='0805',
 RATED='16V',
 ATTRIBUTE='22UF',
 TOLERANCE='20%',
 SEC_TYPE='SMD-BCG5',
 PHYS_PAGE='214',
 XY='(3550,1200)',
 ROT='0',
 VER='1',
 VALUE='SC22U16V5MX-4-GP',
 PACK_TYPE='SMD-BCG5',
 PART_NUMBER='078.22611.0811',
 LOCATION='C22W20',
 SEC='1',
 CDS_LIB='w_hdl',
 CDS_PART_NAME='SC22U16V5MX-4-GP_SMD-BCG5-SC22A',
 PRIM_FILE='C:/<user>/w_hdl/sc22u16v5mx#2d4#2dgp/chips/chips.prt';

PART_NAME
 C22W21 'SC22U16V5MX-4-GP_SMD-BCG5-SC22A':;

SECTION_NUMBER 1
 '@BASEBOARD_FAB2_LIB.BASEBOARD_FAB2(SCH_1):PAGE214_I166@W_HDL.SC22U16V5MX-4-GP(CHIPS)':
 C_PATH='@baseboard_fab2_lib.baseboard_fab2(sch_1):page214_i166@w_hdl.\sc22u16v5~
mx-4-gp\(chips)',
 P_PATH='@baseboard_fab2_lib.baseboard_fab2(sch_1):page214_i166@w_hdl.\sc22u16v5~
mx-4-gp\(chips)',
 PATH='I166',
 DRAWING='@BASEBOARD_FAB2_LIB.BASEBOARD_FAB2(SCH_1):PAGE214',
 TYPE='X6S',
 PACK_SIZE='0805',
 RATED='16V',
 ATTRIBUTE='22UF',
 TOLERANCE='20%',
 SEC_TYPE='SMD-BCG5',
 PHYS_PAGE='214',
 XY='(3850,1200)',
 ROT='0',
 VER='1',
 VALUE='SC22U16V5MX-4-GP',
 PACK_TYPE='SMD-BCG5',
 PART_NUMBER='078.22611.0811',
 LOCATION='C22W21',
 SEC='1',
 CDS_LIB='w_hdl',
 CDS_PART_NAME='SC22U16V5MX-4-GP_SMD-BCG5-SC22A',
 PRIM_FILE='C:/<user>/w_hdl/sc22u16v5mx#2d4#2dgp/chips/chips.prt';

PART_NAME
 C22W22 'SC22U16V5MX-4-GP_SMD-BCG5-SC22A':;

SECTION_NUMBER 1
 '@BASEBOARD_FAB2_LIB.BASEBOARD_FAB2(SCH_1):PAGE236_I171@W_HDL.SC22U16V5MX-4-GP(CHIPS)':
 C_PATH='@baseboard_fab2_lib.baseboard_fab2(sch_1):page236_i171@w_hdl.\sc22u16v5~
mx-4-gp\(chips)',
 P_PATH='@baseboard_fab2_lib.baseboard_fab2(sch_1):page236_i171@w_hdl.\sc22u16v5~
mx-4-gp\(chips)',
 PATH='I171',
 DRAWING='@BASEBOARD_FAB2_LIB.BASEBOARD_FAB2(SCH_1):PAGE236',
 TYPE='X6S',
 PACK_SIZE='0805',
 RATED='16V',
 ATTRIBUTE='22UF',
 TOLERANCE='20%',
 SEC_TYPE='SMD-BCG5',
 PHYS_PAGE='236',
 XY='(10850,975)',
 ROT='0',
 VER='1',
 VALUE='SC22U16V5MX-4-GP',
 PACK_TYPE='SMD-BCG5',
 PART_NUMBER='078.22611.0811',
 LOCATION='C22W22',
 SEC='1',
 CDS_LIB='w_hdl',
 CDS_PART_NAME='SC22U16V5MX-4-GP_SMD-BCG5-SC22A',
 PRIM_FILE='C:/<user>/w_hdl/sc22u16v5mx#2d4#2dgp/chips/chips.prt';

PART_NAME
 C22W23 'SC22U16V5MX-4-GP_SMD-BCG5-SC22A':;

SECTION_NUMBER 1
 '@BASEBOARD_FAB2_LIB.BASEBOARD_FAB2(SCH_1):PAGE236_I159@W_HDL.SC22U16V5MX-4-GP(CHIPS)':
 C_PATH='@baseboard_fab2_lib.baseboard_fab2(sch_1):page236_i159@w_hdl.\sc22u16v5~
mx-4-gp\(chips)',
 P_PATH='@baseboard_fab2_lib.baseboard_fab2(sch_1):page236_i159@w_hdl.\sc22u16v5~
mx-4-gp\(chips)',
 PATH='I159',
 DRAWING='@BASEBOARD_FAB2_LIB.BASEBOARD_FAB2(SCH_1):PAGE236',
 TYPE='X6S',
 PACK_SIZE='0805',
 RATED='16V',
 ATTRIBUTE='22UF',
 TOLERANCE='20%',
 SEC_TYPE='SMD-BCG5',
 PHYS_PAGE='236',
 XY='(11150,975)',
 ROT='0',
 VER='1',
 VALUE='SC22U16V5MX-4-GP',
 PACK_TYPE='SMD-BCG5',
 PART_NUMBER='078.22611.0811',
 LOCATION='C22W23',
 SEC='1',
 CDS_LIB='w_hdl',
 CDS_PART_NAME='SC22U16V5MX-4-GP_SMD-BCG5-SC22A',
 PRIM_FILE='C:/<user>/w_hdl/sc22u16v5mx#2d4#2dgp/chips/chips.prt';

PART_NAME
 C22W24 'SC22U16V5MX-4-GP_SMD-BCG5-SC22A':;

SECTION_NUMBER 1
 '@BASEBOARD_FAB2_LIB.BASEBOARD_FAB2(SCH_1):PAGE236_I160@W_HDL.SC22U16V5MX-4-GP(CHIPS)':
 C_PATH='@baseboard_fab2_lib.baseboard_fab2(sch_1):page236_i160@w_hdl.\sc22u16v5~
mx-4-gp\(chips)',
 P_PATH='@baseboard_fab2_lib.baseboard_fab2(sch_1):page236_i160@w_hdl.\sc22u16v5~
mx-4-gp\(chips)',
 PATH='I160',
 DRAWING='@BASEBOARD_FAB2_LIB.BASEBOARD_FAB2(SCH_1):PAGE236',
 TYPE='X6S',
 PACK_SIZE='0805',
 RATED='16V',
 ATTRIBUTE='22UF',
 TOLERANCE='20%',
 SEC_TYPE='SMD-BCG5',
 PHYS_PAGE='236',
 XY='(11450,975)',
 ROT='0',
 VER='1',
 VALUE='SC22U16V5MX-4-GP',
 PACK_TYPE='SMD-BCG5',
 PART_NUMBER='078.22611.0811',
 LOCATION='C22W24',
 SEC='1',
 CDS_LIB='w_hdl',
 CDS_PART_NAME='SC22U16V5MX-4-GP_SMD-BCG5-SC22A',
 PRIM_FILE='C:/<user>/w_hdl/sc22u16v5mx#2d4#2dgp/chips/chips.prt';

PART_NAME
 C22W25 'SC22U16V5MX-4-GP_SMD-BCG5-SC22A':;

SECTION_NUMBER 1
 '@BASEBOARD_FAB2_LIB.BASEBOARD_FAB2(SCH_1):PAGE236_I162@W_HDL.SC22U16V5MX-4-GP(CHIPS)':
 C_PATH='@baseboard_fab2_lib.baseboard_fab2(sch_1):page236_i162@w_hdl.\sc22u16v5~
mx-4-gp\(chips)',
 P_PATH='@baseboard_fab2_lib.baseboard_fab2(sch_1):page236_i162@w_hdl.\sc22u16v5~
mx-4-gp\(chips)',
 PATH='I162',
 DRAWING='@BASEBOARD_FAB2_LIB.BASEBOARD_FAB2(SCH_1):PAGE236',
 TYPE='X6S',
 PACK_SIZE='0805',
 RATED='16V',
 ATTRIBUTE='22UF',
 TOLERANCE='20%',
 SEC_TYPE='SMD-BCG5',
 PHYS_PAGE='236',
 XY='(12100,975)',
 ROT='0',
 VER='1',
 VALUE='SC22U16V5MX-4-GP',
 PACK_TYPE='SMD-BCG5',
 PART_NUMBER='078.22611.0811',
 LOCATION='C22W25',
 SEC='1',
 CDS_LIB='w_hdl',
 CDS_PART_NAME='SC22U16V5MX-4-GP_SMD-BCG5-SC22A',
 PRIM_FILE='C:/<user>/w_hdl/sc22u16v5mx#2d4#2dgp/chips/chips.prt';

PART_NAME
 C22W26 'SC22U16V5MX-4-GP_SMD-BCG5-SC22A':;

SECTION_NUMBER 1
 '@BASEBOARD_FAB2_LIB.BASEBOARD_FAB2(SCH_1):PAGE236_I165@W_HDL.SC22U16V5MX-4-GP(CHIPS)':
 C_PATH='@baseboard_fab2_lib.baseboard_fab2(sch_1):page236_i165@w_hdl.\sc22u16v5~
mx-4-gp\(chips)',
 P_PATH='@baseboard_fab2_lib.baseboard_fab2(sch_1):page236_i165@w_hdl.\sc22u16v5~
mx-4-gp\(chips)',
 PATH='I165',
 DRAWING='@BASEBOARD_FAB2_LIB.BASEBOARD_FAB2(SCH_1):PAGE236',
 TYPE='X6S',
 PACK_SIZE='0805',
 RATED='16V',
 ATTRIBUTE='22UF',
 TOLERANCE='20%',
 SEC_TYPE='SMD-BCG5',
 PHYS_PAGE='236',
 XY='(12400,975)',
 ROT='0',
 VER='1',
 VALUE='SC22U16V5MX-4-GP',
 PACK_TYPE='SMD-BCG5',
 PART_NUMBER='078.22611.0811',
 LOCATION='C22W26',
 SEC='1',
 CDS_LIB='w_hdl',
 CDS_PART_NAME='SC22U16V5MX-4-GP_SMD-BCG5-SC22A',
 PRIM_FILE='C:/<user>/w_hdl/sc22u16v5mx#2d4#2dgp/chips/chips.prt';

PART_NAME
 C22W27 'SC22U16V5MX-4-GP_SMD-BCG5-SC22A':;

SECTION_NUMBER 1
 '@BASEBOARD_FAB2_LIB.BASEBOARD_FAB2(SCH_1):PAGE236_I163@W_HDL.SC22U16V5MX-4-GP(CHIPS)':
 C_PATH='@baseboard_fab2_lib.baseboard_fab2(sch_1):page236_i163@w_hdl.\sc22u16v5~
mx-4-gp\(chips)',
 P_PATH='@baseboard_fab2_lib.baseboard_fab2(sch_1):page236_i163@w_hdl.\sc22u16v5~
mx-4-gp\(chips)',
 PATH='I163',
 DRAWING='@BASEBOARD_FAB2_LIB.BASEBOARD_FAB2(SCH_1):PAGE236',
 TYPE='X6S',
 PACK_SIZE='0805',
 RATED='16V',
 ATTRIBUTE='22UF',
 TOLERANCE='20%',
 SEC_TYPE='SMD-BCG5',
 PHYS_PAGE='236',
 XY='(12700,975)',
 ROT='0',
 VER='1',
 VALUE='SC22U16V5MX-4-GP',
 PACK_TYPE='SMD-BCG5',
 PART_NUMBER='078.22611.0811',
 LOCATION='C22W27',
 SEC='1',
 CDS_LIB='w_hdl',
 CDS_PART_NAME='SC22U16V5MX-4-GP_SMD-BCG5-SC22A',
 PRIM_FILE='C:/<user>/w_hdl/sc22u16v5mx#2d4#2dgp/chips/chips.prt';

PART_NAME
 C22W28 'SC22U16V5MX-4-GP_SMD-BCG5-SC22A':;

SECTION_NUMBER 1
 '@BASEBOARD_FAB2_LIB.BASEBOARD_FAB2(SCH_1):PAGE212_I136@W_HDL.SC22U16V5MX-4-GP(CHIPS)':
 C_PATH='@baseboard_fab2_lib.baseboard_fab2(sch_1):page212_i136@w_hdl.\sc22u16v5~
mx-4-gp\(chips)',
 P_PATH='@baseboard_fab2_lib.baseboard_fab2(sch_1):page212_i136@w_hdl.\sc22u16v5~
mx-4-gp\(chips)',
 PATH='I136',
 DRAWING='@BASEBOARD_FAB2_LIB.BASEBOARD_FAB2(SCH_1):PAGE212',
 TYPE='X6S',
 PACK_SIZE='0805',
 RATED='16V',
 ATTRIBUTE='22UF',
 TOLERANCE='20%',
 SEC_TYPE='SMD-BCG5',
 PHYS_PAGE='212',
 XY='(950,2175)',
 ROT='0',
 VER='1',
 VALUE='SC22U16V5MX-4-GP',
 PACK_TYPE='SMD-BCG5',
 PART_NUMBER='078.22611.0811',
 LOCATION='C22W28',
 SEC='1',
 CDS_LIB='w_hdl',
 CDS_PART_NAME='SC22U16V5MX-4-GP_SMD-BCG5-SC22A',
 PRIM_FILE='C:/<user>/w_hdl/sc22u16v5mx#2d4#2dgp/chips/chips.prt';

PART_NAME
 C22W29 'SC22U16V5MX-4-GP_SMD-BCG5-SC22A':;

SECTION_NUMBER 1
 '@BASEBOARD_FAB2_LIB.BASEBOARD_FAB2(SCH_1):PAGE212_I134@W_HDL.SC22U16V5MX-4-GP(CHIPS)':
 C_PATH='@baseboard_fab2_lib.baseboard_fab2(sch_1):page212_i134@w_hdl.\sc22u16v5~
mx-4-gp\(chips)',
 P_PATH='@baseboard_fab2_lib.baseboard_fab2(sch_1):page212_i134@w_hdl.\sc22u16v5~
mx-4-gp\(chips)',
 PATH='I134',
 DRAWING='@BASEBOARD_FAB2_LIB.BASEBOARD_FAB2(SCH_1):PAGE212',
 TYPE='X6S',
 PACK_SIZE='0805',
 RATED='16V',
 ATTRIBUTE='22UF',
 TOLERANCE='20%',
 SEC_TYPE='SMD-BCG5',
 PHYS_PAGE='212',
 XY='(1250,2175)',
 ROT='0',
 VER='1',
 VALUE='SC22U16V5MX-4-GP',
 PACK_TYPE='SMD-BCG5',
 PART_NUMBER='078.22611.0811',
 LOCATION='C22W29',
 SEC='1',
 CDS_LIB='w_hdl',
 CDS_PART_NAME='SC22U16V5MX-4-GP_SMD-BCG5-SC22A',
 PRIM_FILE='C:/<user>/w_hdl/sc22u16v5mx#2d4#2dgp/chips/chips.prt';

PART_NAME
 C22W30 'SC22U16V5MX-4-GP_SMD-BCG5-SC22A':;

SECTION_NUMBER 1
 '@BASEBOARD_FAB2_LIB.BASEBOARD_FAB2(SCH_1):PAGE212_I132@W_HDL.SC22U16V5MX-4-GP(CHIPS)':
 C_PATH='@baseboard_fab2_lib.baseboard_fab2(sch_1):page212_i132@w_hdl.\sc22u16v5~
mx-4-gp\(chips)',
 P_PATH='@baseboard_fab2_lib.baseboard_fab2(sch_1):page212_i132@w_hdl.\sc22u16v5~
mx-4-gp\(chips)',
 PATH='I132',
 DRAWING='@BASEBOARD_FAB2_LIB.BASEBOARD_FAB2(SCH_1):PAGE212',
 TYPE='X6S',
 PACK_SIZE='0805',
 RATED='16V',
 ATTRIBUTE='22UF',
 TOLERANCE='20%',
 SEC_TYPE='SMD-BCG5',
 PHYS_PAGE='212',
 XY='(1550,2175)',
 ROT='0',
 VER='1',
 VALUE='SC22U16V5MX-4-GP',
 PACK_TYPE='SMD-BCG5',
 PART_NUMBER='078.22611.0811',
 LOCATION='C22W30',
 SEC='1',
 CDS_LIB='w_hdl',
 CDS_PART_NAME='SC22U16V5MX-4-GP_SMD-BCG5-SC22A',
 PRIM_FILE='C:/<user>/w_hdl/sc22u16v5mx#2d4#2dgp/chips/chips.prt';

PART_NAME
 C22W31 'SC22U16V5MX-4-GP_SMD-BCG5-SC22A':;

SECTION_NUMBER 1
 '@BASEBOARD_FAB2_LIB.BASEBOARD_FAB2(SCH_1):PAGE212_I129@W_HDL.SC22U16V5MX-4-GP(CHIPS)':
 C_PATH='@baseboard_fab2_lib.baseboard_fab2(sch_1):page212_i129@w_hdl.\sc22u16v5~
mx-4-gp\(chips)',
 P_PATH='@baseboard_fab2_lib.baseboard_fab2(sch_1):page212_i129@w_hdl.\sc22u16v5~
mx-4-gp\(chips)',
 PATH='I129',
 DRAWING='@BASEBOARD_FAB2_LIB.BASEBOARD_FAB2(SCH_1):PAGE212',
 TYPE='X6S',
 PACK_SIZE='0805',
 RATED='16V',
 ATTRIBUTE='22UF',
 TOLERANCE='20%',
 SEC_TYPE='SMD-BCG5',
 PHYS_PAGE='212',
 XY='(2300,2175)',
 ROT='0',
 VER='1',
 VALUE='SC22U16V5MX-4-GP',
 PACK_TYPE='SMD-BCG5',
 PART_NUMBER='078.22611.0811',
 LOCATION='C22W31',
 SEC='1',
 CDS_LIB='w_hdl',
 CDS_PART_NAME='SC22U16V5MX-4-GP_SMD-BCG5-SC22A',
 PRIM_FILE='C:/<user>/w_hdl/sc22u16v5mx#2d4#2dgp/chips/chips.prt';

PART_NAME
 C22W32 'SC22U16V5MX-4-GP_SMD-BCG5-SC22A':;

SECTION_NUMBER 1
 '@BASEBOARD_FAB2_LIB.BASEBOARD_FAB2(SCH_1):PAGE212_I126@W_HDL.SC22U16V5MX-4-GP(CHIPS)':
 C_PATH='@baseboard_fab2_lib.baseboard_fab2(sch_1):page212_i126@w_hdl.\sc22u16v5~
mx-4-gp\(chips)',
 P_PATH='@baseboard_fab2_lib.baseboard_fab2(sch_1):page212_i126@w_hdl.\sc22u16v5~
mx-4-gp\(chips)',
 PATH='I126',
 DRAWING='@BASEBOARD_FAB2_LIB.BASEBOARD_FAB2(SCH_1):PAGE212',
 TYPE='X6S',
 PACK_SIZE='0805',
 RATED='16V',
 ATTRIBUTE='22UF',
 TOLERANCE='20%',
 SEC_TYPE='SMD-BCG5',
 PHYS_PAGE='212',
 XY='(2600,2175)',
 ROT='0',
 VER='1',
 VALUE='SC22U16V5MX-4-GP',
 PACK_TYPE='SMD-BCG5',
 PART_NUMBER='078.22611.0811',
 LOCATION='C22W32',
 SEC='1',
 CDS_LIB='w_hdl',
 CDS_PART_NAME='SC22U16V5MX-4-GP_SMD-BCG5-SC22A',
 PRIM_FILE='C:/<user>/w_hdl/sc22u16v5mx#2d4#2dgp/chips/chips.prt';

PART_NAME
 C22W33 'SC22U16V5MX-4-GP_SMD-BCG5-SC22A':;

SECTION_NUMBER 1
 '@BASEBOARD_FAB2_LIB.BASEBOARD_FAB2(SCH_1):PAGE212_I124@W_HDL.SC22U16V5MX-4-GP(CHIPS)':
 C_PATH='@baseboard_fab2_lib.baseboard_fab2(sch_1):page212_i124@w_hdl.\sc22u16v5~
mx-4-gp\(chips)',
 P_PATH='@baseboard_fab2_lib.baseboard_fab2(sch_1):page212_i124@w_hdl.\sc22u16v5~
mx-4-gp\(chips)',
 PATH='I124',
 DRAWING='@BASEBOARD_FAB2_LIB.BASEBOARD_FAB2(SCH_1):PAGE212',
 TYPE='X6S',
 PACK_SIZE='0805',
 RATED='16V',
 ATTRIBUTE='22UF',
 TOLERANCE='20%',
 SEC_TYPE='SMD-BCG5',
 PHYS_PAGE='212',
 XY='(2900,2175)',
 ROT='0',
 VER='1',
 VALUE='SC22U16V5MX-4-GP',
 PACK_TYPE='SMD-BCG5',
 PART_NUMBER='078.22611.0811',
 LOCATION='C22W33',
 SEC='1',
 CDS_LIB='w_hdl',
 CDS_PART_NAME='SC22U16V5MX-4-GP_SMD-BCG5-SC22A',
 PRIM_FILE='C:/<user>/w_hdl/sc22u16v5mx#2d4#2dgp/chips/chips.prt';

PART_NAME
 C22W34 'SC22U16V5MX-4-GP_SMD-BCG5-SC22A':
 GROUP='NI_I210&RJ45';

SECTION_NUMBER 1
 '@BASEBOARD_FAB2_LIB.BASEBOARD_FAB2(SCH_1):PAGE139_I244@W_HDL.SC22U16V5MX-4-GP(CHIPS)':
 C_PATH='@baseboard_fab2_lib.baseboard_fab2(sch_1):page139_i244@w_hdl.\sc22u16v5~
mx-4-gp\(chips)',
 P_PATH='@baseboard_fab2_lib.baseboard_fab2(sch_1):page139_i244@w_hdl.\sc22u16v5~
mx-4-gp\(chips)',
 PATH='I244',
 DRAWING='@BASEBOARD_FAB2_LIB.BASEBOARD_FAB2(SCH_1):PAGE139',
 TYPE='X6S',
 PACK_SIZE='0805',
 RATED='16V',
 ATTRIBUTE='22UF',
 POP='NOPOP',
 TOLERANCE='20%',
 SEC_TYPE='SMD-BCG5',
 PHYS_PAGE='139',
 XY='(-5800,825)',
 ROT='0',
 VER='1',
 VALUE='SC22U16V5MX-4-GP',
 PACK_TYPE='SMD-BCG5',
 PART_NUMBER='078.22611.0811',
 LOCATION='C22W34',
 GROUP='NI_I210&RJ45',
 SEC='1',
 CDS_LIB='w_hdl',
 CDS_PART_NAME='SC22U16V5MX-4-GP_SMD-BCG5-SC22A',
 PRIM_FILE='C:/<user>/w_hdl/sc22u16v5mx#2d4#2dgp/chips/chips.prt';

PART_NAME
 C22W35 'SC22U16V5MX-4-GP_SMD-BCG5-SC22A':
 GROUP='NI_I210&RJ45';

SECTION_NUMBER 1
 '@BASEBOARD_FAB2_LIB.BASEBOARD_FAB2(SCH_1):PAGE139_I246@W_HDL.SC22U16V5MX-4-GP(CHIPS)':
 C_PATH='@baseboard_fab2_lib.baseboard_fab2(sch_1):page139_i246@w_hdl.\sc22u16v5~
mx-4-gp\(chips)',
 P_PATH='@baseboard_fab2_lib.baseboard_fab2(sch_1):page139_i246@w_hdl.\sc22u16v5~
mx-4-gp\(chips)',
 PATH='I246',
 DRAWING='@BASEBOARD_FAB2_LIB.BASEBOARD_FAB2(SCH_1):PAGE139',
 TYPE='X6S',
 PACK_SIZE='0805',
 RATED='16V',
 ATTRIBUTE='22UF',
 POP='NOPOP',
 TOLERANCE='20%',
 SEC_TYPE='SMD-BCG5',
 PHYS_PAGE='139',
 XY='(-3700,800)',
 ROT='0',
 VER='1',
 VALUE='SC22U16V5MX-4-GP',
 PACK_TYPE='SMD-BCG5',
 PART_NUMBER='078.22611.0811',
 LOCATION='C22W35',
 GROUP='NI_I210&RJ45',
 SEC='1',
 CDS_LIB='w_hdl',
 CDS_PART_NAME='SC22U16V5MX-4-GP_SMD-BCG5-SC22A',
 PRIM_FILE='C:/<user>/w_hdl/sc22u16v5mx#2d4#2dgp/chips/chips.prt';

PART_NAME
 C25P80 'CAP_A_0402V-0.1UF,16V,10%,X7R,A':
 GROUP='AST2500',
 ROOM='PROC_SIDEBAND';

SECTION_NUMBER 1
 '@BASEBOARD_FAB2_LIB.BASEBOARD_FAB2(SCH_1):PAGE255_I134@DEV_DISCRETE.CAP_A(CHIPS)':
 C_PATH='@baseboard_fab2_lib.baseboard_fab2(sch_1):page255_i134@dev_discrete.cap~
_a(chips)',
 P_PATH='@baseboard_fab2_lib.baseboard_fab2(sch_1):page252_i134@dev_discrete.cap~
_a(chips)',
 PATH='I134',
 DRAWING='@BASEBOARD_FAB2_LIB.BASEBOARD_FAB2(SCH_1):PAGE255',
 TOLERANCE='10%',
 SEC_TYPE='0402V',
 MATERIAL='X7R',
 BOM_COST='PROC_SIDEBAND',
 PHYS_PAGE='252',
 XY='(-3500,5200)',
 ROT='1',
 VER='1',
 VALUE='0.1UF',
 PACK_TYPE='0402V',
 PART_NUMBER='A36096-030',
 LOCATION='C25P80',
 ROOM='PROC_SIDEBAND',
 GROUP='AST2500',
 SEC='1',
 CDS_LIB='dev_discrete',
 CDS_PART_NAME='CAP_A_0402V-0.1UF,16V,10%,X7R,A',
 VOLTAGE='16V',
 PRIM_FILE='./archive_libs/discrete/cap_a/chips/chips.prt';

PART_NAME
 C25P83 'CAP_A_0402V-0.1UF,16V,10%,X7R,A':
 GROUP='AST2500',
 ROOM='PROC_SIDEBAND';

SECTION_NUMBER 1
 '@BASEBOARD_FAB2_LIB.BASEBOARD_FAB2(SCH_1):PAGE255_I74@DEV_DISCRETE.CAP_A(CHIPS)':
 C_PATH='@baseboard_fab2_lib.baseboard_fab2(sch_1):page255_i74@dev_discrete.cap_~
a(chips)',
 P_PATH='@baseboard_fab2_lib.baseboard_fab2(sch_1):page252_i74@dev_discrete.cap_~
a(chips)',
 PATH='I74',
 DRAWING='@BASEBOARD_FAB2_LIB.BASEBOARD_FAB2(SCH_1):PAGE255',
 TOLERANCE='10%',
 SEC_TYPE='0402V',
 MATERIAL='X7R',
 BOM_COST='PROC_SIDEBAND',
 PHYS_PAGE='252',
 XY='(-3200,2350)',
 ROT='0',
 VER='1',
 VALUE='0.1UF',
 PACK_TYPE='0402V',
 PART_NUMBER='A36096-030',
 LOCATION='C25P83',
 ROOM='PROC_SIDEBAND',
 GROUP='AST2500',
 SEC='1',
 CDS_LIB='dev_discrete',
 CDS_PART_NAME='CAP_A_0402V-0.1UF,16V,10%,X7R,A',
 VOLTAGE='16V',
 PRIM_FILE='./archive_libs/discrete/cap_a/chips/chips.prt';

PART_NAME
 C25W1 'CAP_0402-1.0UF,16V,10%,X6S,D97A':
 ROOM='VDDQ_KLM_PWR_VR';

SECTION_NUMBER 1
 '@BASEBOARD_FAB2_LIB.BASEBOARD_FAB2(SCH_1):PAGE151_I125@MSTR_DISCRETE.CAP(CHIPS)':
 C_PATH='@baseboard_fab2_lib.baseboard_fab2(sch_1):page151_i125@mstr_discrete.ca~
p(chips)',
 P_PATH='@baseboard_fab2_lib.baseboard_fab2(sch_1):page151_i125@mstr_discrete.ca~
p(chips)',
 PATH='I125',
 DRAWING='@BASEBOARD_FAB2_LIB.BASEBOARD_FAB2(SCH_1):PAGE151',
 TOLERANCE='10%',
 MATERIAL='X6S',
 PHYS_PAGE='151',
 XY='(325,1675)',
 ROT='1',
 VER='1',
 VALUE='1.0UF',
 PACK_TYPE='0402',
 PART_NUMBER='D97712-011',
 LOCATION='C25W1',
 ROOM='VDDQ_KLM_PWR_VR',
 CDS_LIB='mstr_discrete',
 CDS_PART_NAME='CAP_0402-1.0UF,16V,10%,X6S,D97A',
 VOLTAGE='16V',
 PRIM_FILE='./archive_libs/mstr_discrete/cap/chips/chips.prt';

PART_NAME
 C25W2 'CAP_0402-1.0UF,16V,10%,X6S,D97A':
 ROOM='VDDQ_KLM_PWR_VR';

SECTION_NUMBER 1
 '@BASEBOARD_FAB2_LIB.BASEBOARD_FAB2(SCH_1):PAGE151_I139@MSTR_DISCRETE.CAP(CHIPS)':
 C_PATH='@baseboard_fab2_lib.baseboard_fab2(sch_1):page151_i139@mstr_discrete.ca~
p(chips)',
 P_PATH='@baseboard_fab2_lib.baseboard_fab2(sch_1):page151_i139@mstr_discrete.ca~
p(chips)',
 PATH='I139',
 DRAWING='@BASEBOARD_FAB2_LIB.BASEBOARD_FAB2(SCH_1):PAGE151',
 TOLERANCE='10%',
 MATERIAL='X6S',
 PHYS_PAGE='151',
 XY='(325,1425)',
 ROT='1',
 VER='1',
 VALUE='1.0UF',
 PACK_TYPE='0402',
 PART_NUMBER='D97712-011',
 LOCATION='C25W2',
 ROOM='VDDQ_KLM_PWR_VR',
 CDS_LIB='mstr_discrete',
 CDS_PART_NAME='CAP_0402-1.0UF,16V,10%,X6S,D97A',
 VOLTAGE='16V',
 PRIM_FILE='./archive_libs/mstr_discrete/cap/chips/chips.prt';

PART_NAME
 C25W3 'CAP_0402-1.0UF,16V,10%,X6S,D97A':
 ROOM='VDDQ_KLM_PWR_VR';

SECTION_NUMBER 1
 '@BASEBOARD_FAB2_LIB.BASEBOARD_FAB2(SCH_1):PAGE151_I140@MSTR_DISCRETE.CAP(CHIPS)':
 C_PATH='@baseboard_fab2_lib.baseboard_fab2(sch_1):page151_i140@mstr_discrete.ca~
p(chips)',
 P_PATH='@baseboard_fab2_lib.baseboard_fab2(sch_1):page151_i140@mstr_discrete.ca~
p(chips)',
 PATH='I140',
 DRAWING='@BASEBOARD_FAB2_LIB.BASEBOARD_FAB2(SCH_1):PAGE151',
 TOLERANCE='10%',
 MATERIAL='X6S',
 PHYS_PAGE='151',
 XY='(325,1175)',
 ROT='1',
 VER='1',
 VALUE='1.0UF',
 PACK_TYPE='0402',
 PART_NUMBER='D97712-011',
 LOCATION='C25W3',
 ROOM='VDDQ_KLM_PWR_VR',
 CDS_LIB='mstr_discrete',
 CDS_PART_NAME='CAP_0402-1.0UF,16V,10%,X6S,D97A',
 VOLTAGE='16V',
 PRIM_FILE='./archive_libs/mstr_discrete/cap/chips/chips.prt';

PART_NAME
 C25W4 'CAP_0402-1.0UF,16V,10%,X6S,D97A':
 ROOM='VDDQ_KLM_PWR_VR';

SECTION_NUMBER 1
 '@BASEBOARD_FAB2_LIB.BASEBOARD_FAB2(SCH_1):PAGE151_I141@MSTR_DISCRETE.CAP(CHIPS)':
 C_PATH='@baseboard_fab2_lib.baseboard_fab2(sch_1):page151_i141@mstr_discrete.ca~
p(chips)',
 P_PATH='@baseboard_fab2_lib.baseboard_fab2(sch_1):page151_i141@mstr_discrete.ca~
p(chips)',
 PATH='I141',
 DRAWING='@BASEBOARD_FAB2_LIB.BASEBOARD_FAB2(SCH_1):PAGE151',
 TOLERANCE='10%',
 MATERIAL='X6S',
 PHYS_PAGE='151',
 XY='(325,925)',
 ROT='1',
 VER='1',
 VALUE='1.0UF',
 PACK_TYPE='0402',
 PART_NUMBER='D97712-011',
 LOCATION='C25W4',
 ROOM='VDDQ_KLM_PWR_VR',
 CDS_LIB='mstr_discrete',
 CDS_PART_NAME='CAP_0402-1.0UF,16V,10%,X6S,D97A',
 VOLTAGE='16V',
 PRIM_FILE='./archive_libs/mstr_discrete/cap/chips/chips.prt';

PART_NAME
 C25W5 'CAP_0402-1.0UF,16V,10%,X6S,D97A':
 ROOM='VDDQ_KLM_PWR_VR';

SECTION_NUMBER 1
 '@BASEBOARD_FAB2_LIB.BASEBOARD_FAB2(SCH_1):PAGE151_I142@MSTR_DISCRETE.CAP(CHIPS)':
 C_PATH='@baseboard_fab2_lib.baseboard_fab2(sch_1):page151_i142@mstr_discrete.ca~
p(chips)',
 P_PATH='@baseboard_fab2_lib.baseboard_fab2(sch_1):page151_i142@mstr_discrete.ca~
p(chips)',
 PATH='I142',
 DRAWING='@BASEBOARD_FAB2_LIB.BASEBOARD_FAB2(SCH_1):PAGE151',
 TOLERANCE='10%',
 MATERIAL='X6S',
 PHYS_PAGE='151',
 XY='(325,675)',
 ROT='1',
 VER='1',
 VALUE='1.0UF',
 PACK_TYPE='0402',
 PART_NUMBER='D97712-011',
 LOCATION='C25W5',
 ROOM='VDDQ_KLM_PWR_VR',
 CDS_LIB='mstr_discrete',
 CDS_PART_NAME='CAP_0402-1.0UF,16V,10%,X6S,D97A',
 VOLTAGE='16V',
 PRIM_FILE='./archive_libs/mstr_discrete/cap/chips/chips.prt';

PART_NAME
 C25W6 'CAP_0402-1.0UF,16V,10%,X6S,D97A':
 ROOM='VDDQ_KLM_PWR_VR';

SECTION_NUMBER 1
 '@BASEBOARD_FAB2_LIB.BASEBOARD_FAB2(SCH_1):PAGE151_I143@MSTR_DISCRETE.CAP(CHIPS)':
 C_PATH='@baseboard_fab2_lib.baseboard_fab2(sch_1):page151_i143@mstr_discrete.ca~
p(chips)',
 P_PATH='@baseboard_fab2_lib.baseboard_fab2(sch_1):page151_i143@mstr_discrete.ca~
p(chips)',
 PATH='I143',
 DRAWING='@BASEBOARD_FAB2_LIB.BASEBOARD_FAB2(SCH_1):PAGE151',
 TOLERANCE='10%',
 MATERIAL='X6S',
 PHYS_PAGE='151',
 XY='(325,425)',
 ROT='1',
 VER='1',
 VALUE='1.0UF',
 PACK_TYPE='0402',
 PART_NUMBER='D97712-011',
 LOCATION='C25W6',
 ROOM='VDDQ_KLM_PWR_VR',
 CDS_LIB='mstr_discrete',
 CDS_PART_NAME='CAP_0402-1.0UF,16V,10%,X6S,D97A',
 VOLTAGE='16V',
 PRIM_FILE='./archive_libs/mstr_discrete/cap/chips/chips.prt';

PART_NAME
 C25W7 'CAP_A_0402V-0.1UF,16V,10%,X7R,A':
 ROOM='PROC_SIDEBAND';

SECTION_NUMBER 1
 '@BASEBOARD_FAB2_LIB.BASEBOARD_FAB2(SCH_1):PAGE147_I161@DEV_DISCRETE.CAP_A(CHIPS)':
 C_PATH='@baseboard_fab2_lib.baseboard_fab2(sch_1):page147_i161@dev_discrete.cap~
_a(chips)',
 P_PATH='@baseboard_fab2_lib.baseboard_fab2(sch_1):page147_i161@dev_discrete.cap~
_a(chips)',
 PATH='I161',
 DRAWING='@BASEBOARD_FAB2_LIB.BASEBOARD_FAB2(SCH_1):PAGE147',
 TOLERANCE='10%',
 SEC_TYPE='0402V',
 MATERIAL='X7R',
 BOM_COST='PROC_SIDEBAND',
 PHYS_PAGE='147',
 XY='(2000,2300)',
 ROT='1',
 VER='1',
 VALUE='0.1UF',
 PACK_TYPE='0402V',
 PART_NUMBER='A36096-030',
 LOCATION='C25W7',
 ROOM='PROC_SIDEBAND',
 SEC='1',
 CDS_LIB='dev_discrete',
 CDS_PART_NAME='CAP_A_0402V-0.1UF,16V,10%,X7R,A',
 VOLTAGE='16V',
 PRIM_FILE='./archive_libs/discrete/cap_a/chips/chips.prt';

PART_NAME
 C25W8 'CAP_A_0402V-0.1UF,16V,10%,X7R,A':
 ROOM='PROC_SIDEBAND';

SECTION_NUMBER 1
 '@BASEBOARD_FAB2_LIB.BASEBOARD_FAB2(SCH_1):PAGE147_I162@DEV_DISCRETE.CAP_A(CHIPS)':
 C_PATH='@baseboard_fab2_lib.baseboard_fab2(sch_1):page147_i162@dev_discrete.cap~
_a(chips)',
 P_PATH='@baseboard_fab2_lib.baseboard_fab2(sch_1):page147_i162@dev_discrete.cap~
_a(chips)',
 PATH='I162',
 DRAWING='@BASEBOARD_FAB2_LIB.BASEBOARD_FAB2(SCH_1):PAGE147',
 TOLERANCE='10%',
 SEC_TYPE='0402V',
 MATERIAL='X7R',
 BOM_COST='PROC_SIDEBAND',
 PHYS_PAGE='147',
 XY='(2000,1950)',
 ROT='1',
 VER='1',
 VALUE='0.1UF',
 PACK_TYPE='0402V',
 PART_NUMBER='A36096-030',
 LOCATION='C25W8',
 ROOM='PROC_SIDEBAND',
 SEC='1',
 CDS_LIB='dev_discrete',
 CDS_PART_NAME='CAP_A_0402V-0.1UF,16V,10%,X7R,A',
 VOLTAGE='16V',
 PRIM_FILE='./archive_libs/discrete/cap_a/chips/chips.prt';

PART_NAME
 C25W9 'CAP_A_0402V-0.1UF,16V,10%,X7R,A':
 ROOM='PROC_SIDEBAND';

SECTION_NUMBER 1
 '@BASEBOARD_FAB2_LIB.BASEBOARD_FAB2(SCH_1):PAGE147_I160@DEV_DISCRETE.CAP_A(CHIPS)':
 C_PATH='@baseboard_fab2_lib.baseboard_fab2(sch_1):page147_i160@dev_discrete.cap~
_a(chips)',
 P_PATH='@baseboard_fab2_lib.baseboard_fab2(sch_1):page147_i160@dev_discrete.cap~
_a(chips)',
 PATH='I160',
 DRAWING='@BASEBOARD_FAB2_LIB.BASEBOARD_FAB2(SCH_1):PAGE147',
 TOLERANCE='10%',
 SEC_TYPE='0402V',
 MATERIAL='X7R',
 BOM_COST='PROC_SIDEBAND',
 PHYS_PAGE='147',
 XY='(1450,2150)',
 ROT='0',
 VER='1',
 VALUE='0.1UF',
 PACK_TYPE='0402V',
 PART_NUMBER='A36096-030',
 LOCATION='C25W9',
 ROOM='PROC_SIDEBAND',
 SEC='1',
 CDS_LIB='dev_discrete',
 CDS_PART_NAME='CAP_A_0402V-0.1UF,16V,10%,X7R,A',
 VOLTAGE='16V',
 PRIM_FILE='./archive_libs/discrete/cap_a/chips/chips.prt';

PART_NAME
 C25W10 'CAP_A_0402V-0.01UF,25V,10%,X7RA':
 ROOM='DDR4_CH_M';

SECTION_NUMBER 1
 '@BASEBOARD_FAB2_LIB.BASEBOARD_FAB2(SCH_1):PAGE151_I213@DEV_DISCRETE.CAP_A(CHIPS)':
 C_PATH='@baseboard_fab2_lib.baseboard_fab2(sch_1):page151_i213@dev_discrete.cap~
_a(chips)',
 P_PATH='@baseboard_fab2_lib.baseboard_fab2(sch_1):page151_i213@dev_discrete.cap~
_a(chips)',
 PATH='I213',
 DRAWING='@BASEBOARD_FAB2_LIB.BASEBOARD_FAB2(SCH_1):PAGE151',
 POP='NOPOP',
 TOLERANCE='10%',
 SEC_TYPE='0402V',
 MATERIAL='X7R',
 BOM_COST='MEM',
 PHYS_PAGE='151',
 XY='(-2275,-1600)',
 ROT='2',
 VER='1',
 VALUE='0.01UF',
 PACK_TYPE='0402V',
 PART_NUMBER='A36096-045',
 LOCATION='C25W10',
 ROOM='DDR4_CH_M',
 SEC='1',
 CDS_LIB='dev_discrete',
 CDS_PART_NAME='CAP_A_0402V-0.01UF,25V,10%,X7RA',
 VOLTAGE='25V',
 PRIM_FILE='./archive_libs/discrete/cap_a/chips/chips.prt';

PART_NAME
 C25W11 'CAP_A_0402V-0.01UF,25V,10%,X7RA':
 ROOM='DDR4_CH_M';

SECTION_NUMBER 1
 '@BASEBOARD_FAB2_LIB.BASEBOARD_FAB2(SCH_1):PAGE151_I214@DEV_DISCRETE.CAP_A(CHIPS)':
 C_PATH='@baseboard_fab2_lib.baseboard_fab2(sch_1):page151_i214@dev_discrete.cap~
_a(chips)',
 P_PATH='@baseboard_fab2_lib.baseboard_fab2(sch_1):page151_i214@dev_discrete.cap~
_a(chips)',
 PATH='I214',
 DRAWING='@BASEBOARD_FAB2_LIB.BASEBOARD_FAB2(SCH_1):PAGE151',
 TOLERANCE='10%',
 SEC_TYPE='0402V',
 MATERIAL='X7R',
 BOM_COST='MEM',
 PHYS_PAGE='151',
 XY='(-2275,-2000)',
 ROT='2',
 VER='1',
 VALUE='0.01UF',
 PACK_TYPE='0402V',
 PART_NUMBER='A36096-045',
 LOCATION='C25W11',
 ROOM='DDR4_CH_M',
 SEC='1',
 CDS_LIB='dev_discrete',
 CDS_PART_NAME='CAP_A_0402V-0.01UF,25V,10%,X7RA',
 VOLTAGE='25V',
 PRIM_FILE='./archive_libs/discrete/cap_a/chips/chips.prt';

PART_NAME
 C25W12 'CAP_A_0402V-1.0UF,6.3V,10%,X6SA':
 ROOM='VDDQ_KLM_PWR_VR';

SECTION_NUMBER 1
 '@BASEBOARD_FAB2_LIB.BASEBOARD_FAB2(SCH_1):PAGE151_I212@DEV_DISCRETE.CAP_A(CHIPS)':
 C_PATH='@baseboard_fab2_lib.baseboard_fab2(sch_1):page151_i212@dev_discrete.cap~
_a(chips)',
 P_PATH='@baseboard_fab2_lib.baseboard_fab2(sch_1):page151_i212@dev_discrete.cap~
_a(chips)',
 PATH='I212',
 DRAWING='@BASEBOARD_FAB2_LIB.BASEBOARD_FAB2(SCH_1):PAGE151',
 TOLERANCE='10%',
 SEC_TYPE='0402V',
 MATERIAL='X6S',
 PHYS_PAGE='151',
 XY='(-1950,-2000)',
 ROT='0',
 VER='1',
 VALUE='1.0UF',
 PACK_TYPE='0402V',
 PART_NUMBER='D97712-004',
 LOCATION='C25W12',
 ROOM='VDDQ_KLM_PWR_VR',
 SEC='1',
 CDS_LIB='dev_discrete',
 CDS_PART_NAME='CAP_A_0402V-1.0UF,6.3V,10%,X6SA',
 VOLTAGE='6.3V',
 PRIM_FILE='./archive_libs/discrete/cap_a/chips/chips.prt';

PART_NAME
 C25W13 'CAP_A_0402V-0.1UF,16V,10%,X7R,A':
 ROOM='VDDQ_KLM_PWR_VR';

SECTION_NUMBER 1
 '@BASEBOARD_FAB2_LIB.BASEBOARD_FAB2(SCH_1):PAGE151_I217@DEV_DISCRETE.CAP_A(CHIPS)':
 C_PATH='@baseboard_fab2_lib.baseboard_fab2(sch_1):page151_i217@dev_discrete.cap~
_a(chips)',
 P_PATH='@baseboard_fab2_lib.baseboard_fab2(sch_1):page151_i217@dev_discrete.cap~
_a(chips)',
 PATH='I217',
 DRAWING='@BASEBOARD_FAB2_LIB.BASEBOARD_FAB2(SCH_1):PAGE151',
 TOLERANCE='10%',
 SEC_TYPE='0402V',
 MATERIAL='X7R',
 PHYS_PAGE='151',
 XY='(600,-100)',
 ROT='0',
 VER='1',
 VALUE='0.1UF',
 PACK_TYPE='0402V',
 PART_NUMBER='A36096-030',
 LOCATION='C25W13',
 ROOM='VDDQ_KLM_PWR_VR',
 SEC='1',
 CDS_LIB='dev_discrete',
 CDS_PART_NAME='CAP_A_0402V-0.1UF,16V,10%,X7R,A',
 VOLTAGE='16V',
 PRIM_FILE='./archive_libs/discrete/cap_a/chips/chips.prt';

PART_NAME
 C25W14 'CAP_A_0402V-0.1UF,16V,10%,X7R,A':
 ROOM='VDDQ_KLM_PWR_VR';

SECTION_NUMBER 1
 '@BASEBOARD_FAB2_LIB.BASEBOARD_FAB2(SCH_1):PAGE151_I215@DEV_DISCRETE.CAP_A(CHIPS)':
 C_PATH='@baseboard_fab2_lib.baseboard_fab2(sch_1):page151_i215@dev_discrete.cap~
_a(chips)',
 P_PATH='@baseboard_fab2_lib.baseboard_fab2(sch_1):page151_i215@dev_discrete.cap~
_a(chips)',
 PATH='I215',
 DRAWING='@BASEBOARD_FAB2_LIB.BASEBOARD_FAB2(SCH_1):PAGE151',
 TOLERANCE='10%',
 SEC_TYPE='0402V',
 MATERIAL='X7R',
 PHYS_PAGE='151',
 XY='(1100,550)',
 ROT='0',
 VER='1',
 VALUE='0.1UF',
 PACK_TYPE='0402V',
 PART_NUMBER='A36096-030',
 LOCATION='C25W14',
 ROOM='VDDQ_KLM_PWR_VR',
 SEC='1',
 CDS_LIB='dev_discrete',
 CDS_PART_NAME='CAP_A_0402V-0.1UF,16V,10%,X7R,A',
 VOLTAGE='16V',
 PRIM_FILE='./archive_libs/discrete/cap_a/chips/chips.prt';

PART_NAME
 C25W15 'CAP_A_0402V-0.1UF,16V,10%,X7R,A':
 ROOM='VDDQ_KLM_PWR_VR';

SECTION_NUMBER 1
 '@BASEBOARD_FAB2_LIB.BASEBOARD_FAB2(SCH_1):PAGE151_I216@DEV_DISCRETE.CAP_A(CHIPS)':
 C_PATH='@baseboard_fab2_lib.baseboard_fab2(sch_1):page151_i216@dev_discrete.cap~
_a(chips)',
 P_PATH='@baseboard_fab2_lib.baseboard_fab2(sch_1):page151_i216@dev_discrete.cap~
_a(chips)',
 PATH='I216',
 DRAWING='@BASEBOARD_FAB2_LIB.BASEBOARD_FAB2(SCH_1):PAGE151',
 TOLERANCE='10%',
 SEC_TYPE='0402V',
 MATERIAL='X7R',
 PHYS_PAGE='151',
 XY='(1450,550)',
 ROT='0',
 VER='1',
 VALUE='0.1UF',
 PACK_TYPE='0402V',
 PART_NUMBER='A36096-030',
 LOCATION='C25W15',
 ROOM='VDDQ_KLM_PWR_VR',
 SEC='1',
 CDS_LIB='dev_discrete',
 CDS_PART_NAME='CAP_A_0402V-0.1UF,16V,10%,X7R,A',
 VOLTAGE='16V',
 PRIM_FILE='./archive_libs/discrete/cap_a/chips/chips.prt';

PART_NAME
 C25W16 'CAP_0402LF-100.0PF,50V,5%,COG,A':
 ROOM='BMC';

SECTION_NUMBER 1
 '@BASEBOARD_FAB2_LIB.BASEBOARD_FAB2(SCH_1):PAGE151_I58@MSTR_DISCRETE.CAP(CHIPS)':
 C_PATH='@baseboard_fab2_lib.baseboard_fab2(sch_1):page151_i58@mstr_discrete.cap~
(chips)',
 P_PATH='@baseboard_fab2_lib.baseboard_fab2(sch_1):page151_i58@mstr_discrete.cap~
(chips)',
 PATH='I58',
 DRAWING='@BASEBOARD_FAB2_LIB.BASEBOARD_FAB2(SCH_1):PAGE151',
 TOLERANCE='5%',
 SEC_TYPE='0402LF',
 MATERIAL='COG',
 BOM_COST='SM_CONTROLLER',
 PHYS_PAGE='151',
 XY='(-2075,2100)',
 ROT='0',
 VER='1',
 VALUE='100.0PF',
 PACK_TYPE='0402LF',
 PART_NUMBER='A36095-026',
 LOCATION='C25W16',
 ROOM='BMC',
 SEC='1',
 CDS_LIB='mstr_discrete',
 CDS_PART_NAME='CAP_0402LF-100.0PF,50V,5%,COG,A',
 VOLTAGE='50V',
 PRIM_FILE='./archive_libs/mstr_discrete/cap/chips/chips.prt';

PART_NAME
 C25W17 'SC1U16V3KX-2GP_SMD-BCG-SC1U16VA':;

SECTION_NUMBER 1
 '@BASEBOARD_FAB2_LIB.BASEBOARD_FAB2(SCH_1):PAGE151_I120@W_HDL.SC1U16V3KX-2GP(CHIPS)':
 C_PATH='@baseboard_fab2_lib.baseboard_fab2(sch_1):page151_i120@w_hdl.\sc1u16v3k~
x-2gp\(chips)',
 P_PATH='@baseboard_fab2_lib.baseboard_fab2(sch_1):page151_i120@w_hdl.\sc1u16v3k~
x-2gp\(chips)',
 PATH='I120',
 DRAWING='@BASEBOARD_FAB2_LIB.BASEBOARD_FAB2(SCH_1):PAGE151',
 TYPE='X5R',
 PACK_SIZE='0603',
 RATED='16V',
 ATTRIBUTE='1UF',
 TOLERANCE='10%',
 PHYS_PAGE='151',
 XY='(-2500,2100)',
 ROT='0',
 VER='1',
 VALUE='SC1U16V3KX-2GP',
 PACK_TYPE='SMD-BCG',
 PART_NUMBER='78.10521.5BL',
 LOCATION='C25W17',
 CDS_LIB='w_hdl',
 CDS_PART_NAME='SC1U16V3KX-2GP_SMD-BCG-SC1U16VA',
 PRIM_FILE='C:/<user>/w_hdl/sc1u16v3kx#2d2gp/chips/chips.prt';

PART_NAME
 C25W18 'SC1U16V3KX-2GP_SMD-BCG-SC1U16VA':;

SECTION_NUMBER 1
 '@BASEBOARD_FAB2_LIB.BASEBOARD_FAB2(SCH_1):PAGE151_I121@W_HDL.SC1U16V3KX-2GP(CHIPS)':
 C_PATH='@baseboard_fab2_lib.baseboard_fab2(sch_1):page151_i121@w_hdl.\sc1u16v3k~
x-2gp\(chips)',
 P_PATH='@baseboard_fab2_lib.baseboard_fab2(sch_1):page151_i121@w_hdl.\sc1u16v3k~
x-2gp\(chips)',
 PATH='I121',
 DRAWING='@BASEBOARD_FAB2_LIB.BASEBOARD_FAB2(SCH_1):PAGE151',
 TYPE='X5R',
 PACK_SIZE='0603',
 RATED='16V',
 ATTRIBUTE='1UF',
 TOLERANCE='10%',
 PHYS_PAGE='151',
 XY='(-2925,2100)',
 ROT='0',
 VER='1',
 VALUE='SC1U16V3KX-2GP',
 PACK_TYPE='SMD-BCG',
 PART_NUMBER='78.10521.5BL',
 LOCATION='C25W18',
 CDS_LIB='w_hdl',
 CDS_PART_NAME='SC1U16V3KX-2GP_SMD-BCG-SC1U16VA',
 PRIM_FILE='C:/<user>/w_hdl/sc1u16v3kx#2d2gp/chips/chips.prt';

PART_NAME
 C25W19 'CAP_0603-4.7UF,6.3V,10%,X6S,E1A':;

SECTION_NUMBER 1
 '@BASEBOARD_FAB2_LIB.BASEBOARD_FAB2(SCH_1):PAGE151_I123@MSTR_DISCRETE.CAP(CHIPS)':
 C_PATH='@baseboard_fab2_lib.baseboard_fab2(sch_1):page151_i123@mstr_discrete.ca~
p(chips)',
 P_PATH='@baseboard_fab2_lib.baseboard_fab2(sch_1):page151_i123@mstr_discrete.ca~
p(chips)',
 PATH='I123',
 DRAWING='@BASEBOARD_FAB2_LIB.BASEBOARD_FAB2(SCH_1):PAGE151',
 TOLERANCE='10%',
 SEC_TYPE='0603',
 MATERIAL='X6S',
 PHYS_PAGE='151',
 XY='(-3225,2100)',
 ROT='0',
 VER='1',
 VALUE='4.7UF',
 PACK_TYPE='0603',
 PART_NUMBER='E15431-003',
 LOCATION='C25W19',
 SEC='1',
 CDS_LIB='mstr_discrete',
 CDS_PART_NAME='CAP_0603-4.7UF,6.3V,10%,X6S,E1A',
 VOLTAGE='6.3V',
 PRIM_FILE='./archive_libs/mstr_discrete/cap/chips/chips.prt';

PART_NAME
 C25W20 'CAP_A_0402V-0.1UF,16V,10%,X7R,A':
 GROUP='AST2500',
 ROOM='PROC_SIDEBAND';

SECTION_NUMBER 1
 '@BASEBOARD_FAB2_LIB.BASEBOARD_FAB2(SCH_1):PAGE145_I158@DEV_DISCRETE.CAP_A(CHIPS)':
 C_PATH='@baseboard_fab2_lib.baseboard_fab2(sch_1):page145_i158@dev_discrete.cap~
_a(chips)',
 P_PATH='@baseboard_fab2_lib.baseboard_fab2(sch_1):page145_i158@dev_discrete.cap~
_a(chips)',
 PATH='I158',
 DRAWING='@BASEBOARD_FAB2_LIB.BASEBOARD_FAB2(SCH_1):PAGE145',
 TOLERANCE='10%',
 SEC_TYPE='0402V',
 MATERIAL='X7R',
 BOM_COST='PROC_SIDEBAND',
 PHYS_PAGE='145',
 XY='(-1650,-3550)',
 ROT='1',
 VER='1',
 VALUE='0.1UF',
 PACK_TYPE='0402V',
 PART_NUMBER='A36096-030',
 LOCATION='C25W20',
 ROOM='PROC_SIDEBAND',
 GROUP='AST2500',
 SEC='1',
 CDS_LIB='dev_discrete',
 CDS_PART_NAME='CAP_A_0402V-0.1UF,16V,10%,X7R,A',
 VOLTAGE='16V',
 PRIM_FILE='./archive_libs/discrete/cap_a/chips/chips.prt';

PART_NAME
 C25W21 'CAP_A_0402V-0.1UF,16V,10%,X7R,A':
 GROUP='AST2500',
 ROOM='PROC_SIDEBAND';

SECTION_NUMBER 1
 '@BASEBOARD_FAB2_LIB.BASEBOARD_FAB2(SCH_1):PAGE145_I159@DEV_DISCRETE.CAP_A(CHIPS)':
 C_PATH='@baseboard_fab2_lib.baseboard_fab2(sch_1):page145_i159@dev_discrete.cap~
_a(chips)',
 P_PATH='@baseboard_fab2_lib.baseboard_fab2(sch_1):page145_i159@dev_discrete.cap~
_a(chips)',
 PATH='I159',
 DRAWING='@BASEBOARD_FAB2_LIB.BASEBOARD_FAB2(SCH_1):PAGE145',
 TOLERANCE='10%',
 SEC_TYPE='0402V',
 MATERIAL='X7R',
 BOM_COST='PROC_SIDEBAND',
 PHYS_PAGE='145',
 XY='(-1650,-3900)',
 ROT='1',
 VER='1',
 VALUE='0.1UF',
 PACK_TYPE='0402V',
 PART_NUMBER='A36096-030',
 LOCATION='C25W21',
 ROOM='PROC_SIDEBAND',
 GROUP='AST2500',
 SEC='1',
 CDS_LIB='dev_discrete',
 CDS_PART_NAME='CAP_A_0402V-0.1UF,16V,10%,X7R,A',
 VOLTAGE='16V',
 PRIM_FILE='./archive_libs/discrete/cap_a/chips/chips.prt';

PART_NAME
 C25W22 'CAP_A_0402V-0.1UF,16V,10%,X7R,A':
 ROOM='VDDQ_KLM_PWR_VR';

SECTION_NUMBER 1
 '@BASEBOARD_FAB2_LIB.BASEBOARD_FAB2(SCH_1):PAGE143_I67@DEV_DISCRETE.CAP_A(CHIPS)':
 C_PATH='@baseboard_fab2_lib.baseboard_fab2(sch_1):page143_i67@dev_discrete.cap_~
a(chips)',
 P_PATH='@baseboard_fab2_lib.baseboard_fab2(sch_1):page143_i67@dev_discrete.cap_~
a(chips)',
 PATH='I67',
 DRAWING='@BASEBOARD_FAB2_LIB.BASEBOARD_FAB2(SCH_1):PAGE143',
 TOLERANCE='10%',
 SEC_TYPE='0402V',
 MATERIAL='X7R',
 PHYS_PAGE='143',
 XY='(-10550,-2450)',
 ROT='0',
 VER='1',
 VALUE='0.1UF',
 PACK_TYPE='0402V',
 PART_NUMBER='A36096-030',
 LOCATION='C25W22',
 ROOM='VDDQ_KLM_PWR_VR',
 SEC='1',
 CDS_LIB='dev_discrete',
 CDS_PART_NAME='CAP_A_0402V-0.1UF,16V,10%,X7R,A',
 VOLTAGE='16V',
 PRIM_FILE='./archive_libs/discrete/cap_a/chips/chips.prt';

PART_NAME
 C25W23 'CAP_0402-1.0UF,16V,10%,X6S,D97A':
 ROOM='PROC_SIDEBAND';

SECTION_NUMBER 1
 '@BASEBOARD_FAB2_LIB.BASEBOARD_FAB2(SCH_1):PAGE149_I103@MSTR_DISCRETE.CAP(CHIPS)':
 C_PATH='@baseboard_fab2_lib.baseboard_fab2(sch_1):page149_i103@mstr_discrete.ca~
p(chips)',
 P_PATH='@baseboard_fab2_lib.baseboard_fab2(sch_1):page149_i103@mstr_discrete.ca~
p(chips)',
 PATH='I103',
 DRAWING='@BASEBOARD_FAB2_LIB.BASEBOARD_FAB2(SCH_1):PAGE149',
 TOLERANCE='10%',
 MATERIAL='X6S',
 BOM_COST='PROC',
 PHYS_PAGE='149',
 XY='(-2250,5400)',
 ROT='0',
 VER='1',
 VALUE='1.0UF',
 PACK_TYPE='0402',
 PART_NUMBER='D97712-011',
 LOCATION='C25W23',
 ROOM='PROC_SIDEBAND',
 CDS_LIB='mstr_discrete',
 CDS_PART_NAME='CAP_0402-1.0UF,16V,10%,X6S,D97A',
 VOLTAGE='16V',
 PRIM_FILE='./archive_libs/mstr_discrete/cap/chips/chips.prt';

PART_NAME
 C25W24 'CAP_0402-1.0UF,16V,10%,X6S,D97A':
 ROOM='PROC_SIDEBAND';

SECTION_NUMBER 1
 '@BASEBOARD_FAB2_LIB.BASEBOARD_FAB2(SCH_1):PAGE149_I104@MSTR_DISCRETE.CAP(CHIPS)':
 C_PATH='@baseboard_fab2_lib.baseboard_fab2(sch_1):page149_i104@mstr_discrete.ca~
p(chips)',
 P_PATH='@baseboard_fab2_lib.baseboard_fab2(sch_1):page149_i104@mstr_discrete.ca~
p(chips)',
 PATH='I104',
 DRAWING='@BASEBOARD_FAB2_LIB.BASEBOARD_FAB2(SCH_1):PAGE149',
 TOLERANCE='10%',
 MATERIAL='X6S',
 BOM_COST='PROC',
 PHYS_PAGE='149',
 XY='(-1850,5400)',
 ROT='0',
 VER='1',
 VALUE='1.0UF',
 PACK_TYPE='0402',
 PART_NUMBER='D97712-011',
 LOCATION='C25W24',
 ROOM='PROC_SIDEBAND',
 CDS_LIB='mstr_discrete',
 CDS_PART_NAME='CAP_0402-1.0UF,16V,10%,X6S,D97A',
 VOLTAGE='16V',
 PRIM_FILE='./archive_libs/mstr_discrete/cap/chips/chips.prt';

PART_NAME
 C25W25 'CAP_0402-1.0UF,16V,10%,X6S,D97A':
 ROOM='PROC_SIDEBAND';

SECTION_NUMBER 1
 '@BASEBOARD_FAB2_LIB.BASEBOARD_FAB2(SCH_1):PAGE149_I105@MSTR_DISCRETE.CAP(CHIPS)':
 C_PATH='@baseboard_fab2_lib.baseboard_fab2(sch_1):page149_i105@mstr_discrete.ca~
p(chips)',
 P_PATH='@baseboard_fab2_lib.baseboard_fab2(sch_1):page149_i105@mstr_discrete.ca~
p(chips)',
 PATH='I105',
 DRAWING='@BASEBOARD_FAB2_LIB.BASEBOARD_FAB2(SCH_1):PAGE149',
 TOLERANCE='10%',
 MATERIAL='X6S',
 BOM_COST='PROC',
 PHYS_PAGE='149',
 XY='(-1450,5400)',
 ROT='0',
 VER='1',
 VALUE='1.0UF',
 PACK_TYPE='0402',
 PART_NUMBER='D97712-011',
 LOCATION='C25W25',
 ROOM='PROC_SIDEBAND',
 CDS_LIB='mstr_discrete',
 CDS_PART_NAME='CAP_0402-1.0UF,16V,10%,X6S,D97A',
 VOLTAGE='16V',
 PRIM_FILE='./archive_libs/mstr_discrete/cap/chips/chips.prt';

PART_NAME
 C25W26 'CAP_0402-1.0UF,16V,10%,X6S,D97A':
 ROOM='PROC_SIDEBAND';

SECTION_NUMBER 1
 '@BASEBOARD_FAB2_LIB.BASEBOARD_FAB2(SCH_1):PAGE149_I106@MSTR_DISCRETE.CAP(CHIPS)':
 C_PATH='@baseboard_fab2_lib.baseboard_fab2(sch_1):page149_i106@mstr_discrete.ca~
p(chips)',
 P_PATH='@baseboard_fab2_lib.baseboard_fab2(sch_1):page149_i106@mstr_discrete.ca~
p(chips)',
 PATH='I106',
 DRAWING='@BASEBOARD_FAB2_LIB.BASEBOARD_FAB2(SCH_1):PAGE149',
 TOLERANCE='10%',
 MATERIAL='X6S',
 BOM_COST='PROC',
 PHYS_PAGE='149',
 XY='(-1050,5400)',
 ROT='0',
 VER='1',
 VALUE='1.0UF',
 PACK_TYPE='0402',
 PART_NUMBER='D97712-011',
 LOCATION='C25W26',
 ROOM='PROC_SIDEBAND',
 CDS_LIB='mstr_discrete',
 CDS_PART_NAME='CAP_0402-1.0UF,16V,10%,X6S,D97A',
 VOLTAGE='16V',
 PRIM_FILE='./archive_libs/mstr_discrete/cap/chips/chips.prt';

PART_NAME
 C25W27 'CAP_0402-1.0UF,16V,10%,X6S,D97A':
 ROOM='PROC_SIDEBAND';

SECTION_NUMBER 1
 '@BASEBOARD_FAB2_LIB.BASEBOARD_FAB2(SCH_1):PAGE149_I107@MSTR_DISCRETE.CAP(CHIPS)':
 C_PATH='@baseboard_fab2_lib.baseboard_fab2(sch_1):page149_i107@mstr_discrete.ca~
p(chips)',
 P_PATH='@baseboard_fab2_lib.baseboard_fab2(sch_1):page149_i107@mstr_discrete.ca~
p(chips)',
 PATH='I107',
 DRAWING='@BASEBOARD_FAB2_LIB.BASEBOARD_FAB2(SCH_1):PAGE149',
 TOLERANCE='10%',
 MATERIAL='X6S',
 BOM_COST='PROC',
 PHYS_PAGE='149',
 XY='(-650,5400)',
 ROT='0',
 VER='1',
 VALUE='1.0UF',
 PACK_TYPE='0402',
 PART_NUMBER='D97712-011',
 LOCATION='C25W27',
 ROOM='PROC_SIDEBAND',
 CDS_LIB='mstr_discrete',
 CDS_PART_NAME='CAP_0402-1.0UF,16V,10%,X6S,D97A',
 VOLTAGE='16V',
 PRIM_FILE='./archive_libs/mstr_discrete/cap/chips/chips.prt';

PART_NAME
 C25W28 'CAP_0402-1.0UF,16V,10%,X6S,D97A':
 ROOM='PROC_SIDEBAND';

SECTION_NUMBER 1
 '@BASEBOARD_FAB2_LIB.BASEBOARD_FAB2(SCH_1):PAGE149_I108@MSTR_DISCRETE.CAP(CHIPS)':
 C_PATH='@baseboard_fab2_lib.baseboard_fab2(sch_1):page149_i108@mstr_discrete.ca~
p(chips)',
 P_PATH='@baseboard_fab2_lib.baseboard_fab2(sch_1):page149_i108@mstr_discrete.ca~
p(chips)',
 PATH='I108',
 DRAWING='@BASEBOARD_FAB2_LIB.BASEBOARD_FAB2(SCH_1):PAGE149',
 TOLERANCE='10%',
 MATERIAL='X6S',
 BOM_COST='PROC',
 PHYS_PAGE='149',
 XY='(-250,5400)',
 ROT='0',
 VER='1',
 VALUE='1.0UF',
 PACK_TYPE='0402',
 PART_NUMBER='D97712-011',
 LOCATION='C25W28',
 ROOM='PROC_SIDEBAND',
 CDS_LIB='mstr_discrete',
 CDS_PART_NAME='CAP_0402-1.0UF,16V,10%,X6S,D97A',
 VOLTAGE='16V',
 PRIM_FILE='./archive_libs/mstr_discrete/cap/chips/chips.prt';

PART_NAME
 C25W29 'CAP_0603LF-10UF,4V,20%,X6S,E15A':
 ROOM='CPU0';

SECTION_NUMBER 1
 '@BASEBOARD_FAB2_LIB.BASEBOARD_FAB2(SCH_1):PAGE149_I129@MSTR_DISCRETE.CAP(CHIPS)':
 C_PATH='@baseboard_fab2_lib.baseboard_fab2(sch_1):page149_i129@mstr_discrete.ca~
p(chips)',
 P_PATH='@baseboard_fab2_lib.baseboard_fab2(sch_1):page149_i129@mstr_discrete.ca~
p(chips)',
 PATH='I129',
 DRAWING='@BASEBOARD_FAB2_LIB.BASEBOARD_FAB2(SCH_1):PAGE149',
 TOLERANCE='20%',
 SEC_TYPE='0603LF',
 MATERIAL='X6S',
 BOM_COST='PROC_SOCKET',
 PHYS_PAGE='149',
 XY='(150,5400)',
 ROT='0',
 VER='1',
 VALUE='10UF',
 PACK_TYPE='0603LF',
 PART_NUMBER='E15431-001',
 LOCATION='C25W29',
 ROOM='CPU0',
 SEC='1',
 CDS_LIB='mstr_discrete',
 CDS_PART_NAME='CAP_0603LF-10UF,4V,20%,X6S,E15A',
 VOLTAGE='4V',
 PRIM_FILE='./archive_libs/mstr_discrete/cap/chips/chips.prt';

PART_NAME
 C25W30 'CAP_0603-4.7UF,6.3V,10%,X6S,E1A':;

SECTION_NUMBER 1
 '@BASEBOARD_FAB2_LIB.BASEBOARD_FAB2(SCH_1):PAGE149_I1@MSTR_DISCRETE.CAP(CHIPS)':
 C_PATH='@baseboard_fab2_lib.baseboard_fab2(sch_1):page149_i1@mstr_discrete.cap(~
chips)',
 P_PATH='@baseboard_fab2_lib.baseboard_fab2(sch_1):page149_i1@mstr_discrete.cap(~
chips)',
 PATH='I1',
 DRAWING='@BASEBOARD_FAB2_LIB.BASEBOARD_FAB2(SCH_1):PAGE149',
 TOLERANCE='10%',
 MATERIAL='X6S',
 PHYS_PAGE='149',
 XY='(550,5400)',
 ROT='0',
 VER='1',
 VALUE='4.7UF',
 PACK_TYPE='0603',
 PART_NUMBER='E15431-003',
 LOCATION='C25W30',
 CDS_LIB='mstr_discrete',
 CDS_PART_NAME='CAP_0603-4.7UF,6.3V,10%,X6S,E1A',
 VOLTAGE='6.3V',
 PRIM_FILE='./archive_libs/mstr_discrete/cap/chips/chips.prt';

PART_NAME
 C25W31 'CAP_A_0402V-0.1UF,16V,10%,X7R,A':
 ROOM='VDDQ_KLM_PWR_VR';

SECTION_NUMBER 1
 '@BASEBOARD_FAB2_LIB.BASEBOARD_FAB2(SCH_1):PAGE149_I119@DEV_DISCRETE.CAP_A(CHIPS)':
 C_PATH='@baseboard_fab2_lib.baseboard_fab2(sch_1):page149_i119@dev_discrete.cap~
_a(chips)',
 P_PATH='@baseboard_fab2_lib.baseboard_fab2(sch_1):page149_i119@dev_discrete.cap~
_a(chips)',
 PATH='I119',
 DRAWING='@BASEBOARD_FAB2_LIB.BASEBOARD_FAB2(SCH_1):PAGE149',
 TOLERANCE='10%',
 SEC_TYPE='0402V',
 MATERIAL='X7R',
 PHYS_PAGE='149',
 XY='(-1475,4125)',
 ROT='0',
 VER='1',
 VALUE='0.1UF',
 PACK_TYPE='0402V',
 PART_NUMBER='A36096-030',
 LOCATION='C25W31',
 ROOM='VDDQ_KLM_PWR_VR',
 SEC='1',
 CDS_LIB='dev_discrete',
 CDS_PART_NAME='CAP_A_0402V-0.1UF,16V,10%,X7R,A',
 VOLTAGE='16V',
 PRIM_FILE='./archive_libs/discrete/cap_a/chips/chips.prt';

PART_NAME
 C25W32 'CAP_0402-1.0UF,16V,10%,X6S,D97A':
 ROOM='PROC_SIDEBAND';

SECTION_NUMBER 1
 '@BASEBOARD_FAB2_LIB.BASEBOARD_FAB2(SCH_1):PAGE149_I99@MSTR_DISCRETE.CAP(CHIPS)':
 C_PATH='@baseboard_fab2_lib.baseboard_fab2(sch_1):page149_i99@mstr_discrete.cap~
(chips)',
 P_PATH='@baseboard_fab2_lib.baseboard_fab2(sch_1):page149_i99@mstr_discrete.cap~
(chips)',
 PATH='I99',
 DRAWING='@BASEBOARD_FAB2_LIB.BASEBOARD_FAB2(SCH_1):PAGE149',
 TOLERANCE='10%',
 MATERIAL='X6S',
 BOM_COST='PROC',
 PHYS_PAGE='149',
 XY='(-1025,4100)',
 ROT='0',
 VER='1',
 VALUE='1.0UF',
 PACK_TYPE='0402',
 PART_NUMBER='D97712-011',
 LOCATION='C25W32',
 ROOM='PROC_SIDEBAND',
 CDS_LIB='mstr_discrete',
 CDS_PART_NAME='CAP_0402-1.0UF,16V,10%,X6S,D97A',
 VOLTAGE='16V',
 PRIM_FILE='./archive_libs/mstr_discrete/cap/chips/chips.prt';

PART_NAME
 C25W33 'CAP_0402-1.0UF,16V,10%,X6S,D97A':
 ROOM='PROC_SIDEBAND';

SECTION_NUMBER 1
 '@BASEBOARD_FAB2_LIB.BASEBOARD_FAB2(SCH_1):PAGE149_I102@MSTR_DISCRETE.CAP(CHIPS)':
 C_PATH='@baseboard_fab2_lib.baseboard_fab2(sch_1):page149_i102@mstr_discrete.ca~
p(chips)',
 P_PATH='@baseboard_fab2_lib.baseboard_fab2(sch_1):page149_i102@mstr_discrete.ca~
p(chips)',
 PATH='I102',
 DRAWING='@BASEBOARD_FAB2_LIB.BASEBOARD_FAB2(SCH_1):PAGE149',
 TOLERANCE='10%',
 MATERIAL='X6S',
 BOM_COST='PROC',
 PHYS_PAGE='149',
 XY='(-675,4100)',
 ROT='0',
 VER='1',
 VALUE='1.0UF',
 PACK_TYPE='0402',
 PART_NUMBER='D97712-011',
 LOCATION='C25W33',
 ROOM='PROC_SIDEBAND',
 CDS_LIB='mstr_discrete',
 CDS_PART_NAME='CAP_0402-1.0UF,16V,10%,X6S,D97A',
 VOLTAGE='16V',
 PRIM_FILE='./archive_libs/mstr_discrete/cap/chips/chips.prt';

PART_NAME
 C25W34 'CAP_A_0402V-0.1UF,16V,10%,X7R,A':
 ROOM='VDDQ_KLM_PWR_VR';

SECTION_NUMBER 1
 '@BASEBOARD_FAB2_LIB.BASEBOARD_FAB2(SCH_1):PAGE149_I120@DEV_DISCRETE.CAP_A(CHIPS)':
 C_PATH='@baseboard_fab2_lib.baseboard_fab2(sch_1):page149_i120@dev_discrete.cap~
_a(chips)',
 P_PATH='@baseboard_fab2_lib.baseboard_fab2(sch_1):page149_i120@dev_discrete.cap~
_a(chips)',
 PATH='I120',
 DRAWING='@BASEBOARD_FAB2_LIB.BASEBOARD_FAB2(SCH_1):PAGE149',
 TOLERANCE='10%',
 SEC_TYPE='0402V',
 MATERIAL='X7R',
 PHYS_PAGE='149',
 XY='(425,4000)',
 ROT='0',
 VER='1',
 VALUE='0.1UF',
 PACK_TYPE='0402V',
 PART_NUMBER='A36096-030',
 LOCATION='C25W34',
 ROOM='VDDQ_KLM_PWR_VR',
 SEC='1',
 CDS_LIB='dev_discrete',
 CDS_PART_NAME='CAP_A_0402V-0.1UF,16V,10%,X7R,A',
 VOLTAGE='16V',
 PRIM_FILE='./archive_libs/discrete/cap_a/chips/chips.prt';

PART_NAME
 C25W35 'CAP_0402-1.0UF,16V,10%,X6S,D97A':
 ROOM='PROC_SIDEBAND';

SECTION_NUMBER 1
 '@BASEBOARD_FAB2_LIB.BASEBOARD_FAB2(SCH_1):PAGE149_I110@MSTR_DISCRETE.CAP(CHIPS)':
 C_PATH='@baseboard_fab2_lib.baseboard_fab2(sch_1):page149_i110@mstr_discrete.ca~
p(chips)',
 P_PATH='@baseboard_fab2_lib.baseboard_fab2(sch_1):page149_i110@mstr_discrete.ca~
p(chips)',
 PATH='I110',
 DRAWING='@BASEBOARD_FAB2_LIB.BASEBOARD_FAB2(SCH_1):PAGE149',
 TOLERANCE='10%',
 MATERIAL='X6S',
 BOM_COST='PROC',
 PHYS_PAGE='149',
 XY='(775,4000)',
 ROT='0',
 VER='1',
 VALUE='1.0UF',
 PACK_TYPE='0402',
 PART_NUMBER='D97712-011',
 LOCATION='C25W35',
 ROOM='PROC_SIDEBAND',
 CDS_LIB='mstr_discrete',
 CDS_PART_NAME='CAP_0402-1.0UF,16V,10%,X6S,D97A',
 VOLTAGE='16V',
 PRIM_FILE='./archive_libs/mstr_discrete/cap/chips/chips.prt';

PART_NAME
 C25W36 'CAP_0603-4.7UF,6.3V,10%,X6S,E1A':;

SECTION_NUMBER 1
 '@BASEBOARD_FAB2_LIB.BASEBOARD_FAB2(SCH_1):PAGE149_I46@MSTR_DISCRETE.CAP(CHIPS)':
 C_PATH='@baseboard_fab2_lib.baseboard_fab2(sch_1):page149_i46@mstr_discrete.cap~
(chips)',
 P_PATH='@baseboard_fab2_lib.baseboard_fab2(sch_1):page149_i46@mstr_discrete.cap~
(chips)',
 PATH='I46',
 DRAWING='@BASEBOARD_FAB2_LIB.BASEBOARD_FAB2(SCH_1):PAGE149',
 TOLERANCE='10%',
 MATERIAL='X6S',
 PHYS_PAGE='149',
 XY='(1125,4000)',
 ROT='0',
 VER='1',
 VALUE='4.7UF',
 PACK_TYPE='0603',
 PART_NUMBER='E15431-003',
 LOCATION='C25W36',
 CDS_LIB='mstr_discrete',
 CDS_PART_NAME='CAP_0603-4.7UF,6.3V,10%,X6S,E1A',
 VOLTAGE='6.3V',
 PRIM_FILE='./archive_libs/mstr_discrete/cap/chips/chips.prt';

PART_NAME
 C25W37 'CAP_0402-1.0UF,16V,10%,X6S,D97A':
 ROOM='PROC_SIDEBAND';

SECTION_NUMBER 1
 '@BASEBOARD_FAB2_LIB.BASEBOARD_FAB2(SCH_1):PAGE149_I113@MSTR_DISCRETE.CAP(CHIPS)':
 C_PATH='@baseboard_fab2_lib.baseboard_fab2(sch_1):page149_i113@mstr_discrete.ca~
p(chips)',
 P_PATH='@baseboard_fab2_lib.baseboard_fab2(sch_1):page149_i113@mstr_discrete.ca~
p(chips)',
 PATH='I113',
 DRAWING='@BASEBOARD_FAB2_LIB.BASEBOARD_FAB2(SCH_1):PAGE149',
 TOLERANCE='10%',
 MATERIAL='X6S',
 BOM_COST='PROC',
 PHYS_PAGE='149',
 XY='(2775,3975)',
 ROT='0',
 VER='1',
 VALUE='1.0UF',
 PACK_TYPE='0402',
 PART_NUMBER='D97712-011',
 LOCATION='C25W37',
 ROOM='PROC_SIDEBAND',
 CDS_LIB='mstr_discrete',
 CDS_PART_NAME='CAP_0402-1.0UF,16V,10%,X6S,D97A',
 VOLTAGE='16V',
 PRIM_FILE='./archive_libs/mstr_discrete/cap/chips/chips.prt';

PART_NAME
 C25W38 'CAP_A_0402V-0.1UF,16V,10%,X7R,A':
 ROOM='VDDQ_KLM_PWR_VR';

SECTION_NUMBER 1
 '@BASEBOARD_FAB2_LIB.BASEBOARD_FAB2(SCH_1):PAGE149_I121@DEV_DISCRETE.CAP_A(CHIPS)':
 C_PATH='@baseboard_fab2_lib.baseboard_fab2(sch_1):page149_i121@dev_discrete.cap~
_a(chips)',
 P_PATH='@baseboard_fab2_lib.baseboard_fab2(sch_1):page149_i121@dev_discrete.cap~
_a(chips)',
 PATH='I121',
 DRAWING='@BASEBOARD_FAB2_LIB.BASEBOARD_FAB2(SCH_1):PAGE149',
 TOLERANCE='10%',
 SEC_TYPE='0402V',
 MATERIAL='X7R',
 PHYS_PAGE='149',
 XY='(3325,3975)',
 ROT='0',
 VER='1',
 VALUE='0.1UF',
 PACK_TYPE='0402V',
 PART_NUMBER='A36096-030',
 LOCATION='C25W38',
 ROOM='VDDQ_KLM_PWR_VR',
 SEC='1',
 CDS_LIB='dev_discrete',
 CDS_PART_NAME='CAP_A_0402V-0.1UF,16V,10%,X7R,A',
 VOLTAGE='16V',
 PRIM_FILE='./archive_libs/discrete/cap_a/chips/chips.prt';

PART_NAME
 C25W39 'CAP_0603-4.7UF,6.3V,10%,X6S,E1A':;

SECTION_NUMBER 1
 '@BASEBOARD_FAB2_LIB.BASEBOARD_FAB2(SCH_1):PAGE149_I25@MSTR_DISCRETE.CAP(CHIPS)':
 C_PATH='@baseboard_fab2_lib.baseboard_fab2(sch_1):page149_i25@mstr_discrete.cap~
(chips)',
 P_PATH='@baseboard_fab2_lib.baseboard_fab2(sch_1):page149_i25@mstr_discrete.cap~
(chips)',
 PATH='I25',
 DRAWING='@BASEBOARD_FAB2_LIB.BASEBOARD_FAB2(SCH_1):PAGE149',
 TOLERANCE='10%',
 MATERIAL='X6S',
 PHYS_PAGE='149',
 XY='(3725,3975)',
 ROT='0',
 VER='1',
 VALUE='4.7UF',
 PACK_TYPE='0603',
 PART_NUMBER='E15431-003',
 LOCATION='C25W39',
 CDS_LIB='mstr_discrete',
 CDS_PART_NAME='CAP_0603-4.7UF,6.3V,10%,X6S,E1A',
 VOLTAGE='6.3V',
 PRIM_FILE='./archive_libs/mstr_discrete/cap/chips/chips.prt';

PART_NAME
 C25W40 'CAP_0402-1.0UF,16V,10%,X6S,D97A':
 ROOM='PROC_SIDEBAND';

SECTION_NUMBER 1
 '@BASEBOARD_FAB2_LIB.BASEBOARD_FAB2(SCH_1):PAGE149_I96@MSTR_DISCRETE.CAP(CHIPS)':
 C_PATH='@baseboard_fab2_lib.baseboard_fab2(sch_1):page149_i96@mstr_discrete.cap~
(chips)',
 P_PATH='@baseboard_fab2_lib.baseboard_fab2(sch_1):page149_i96@mstr_discrete.cap~
(chips)',
 PATH='I96',
 DRAWING='@BASEBOARD_FAB2_LIB.BASEBOARD_FAB2(SCH_1):PAGE149',
 TOLERANCE='10%',
 MATERIAL='X6S',
 BOM_COST='PROC',
 PHYS_PAGE='149',
 XY='(-1450,2900)',
 ROT='0',
 VER='1',
 VALUE='1.0UF',
 PACK_TYPE='0402',
 PART_NUMBER='D97712-011',
 LOCATION='C25W40',
 ROOM='PROC_SIDEBAND',
 CDS_LIB='mstr_discrete',
 CDS_PART_NAME='CAP_0402-1.0UF,16V,10%,X6S,D97A',
 VOLTAGE='16V',
 PRIM_FILE='./archive_libs/mstr_discrete/cap/chips/chips.prt';

PART_NAME
 C25W41 'CAP_0402-1.0UF,16V,10%,X6S,D97A':
 ROOM='PROC_SIDEBAND';

SECTION_NUMBER 1
 '@BASEBOARD_FAB2_LIB.BASEBOARD_FAB2(SCH_1):PAGE149_I97@MSTR_DISCRETE.CAP(CHIPS)':
 C_PATH='@baseboard_fab2_lib.baseboard_fab2(sch_1):page149_i97@mstr_discrete.cap~
(chips)',
 P_PATH='@baseboard_fab2_lib.baseboard_fab2(sch_1):page149_i97@mstr_discrete.cap~
(chips)',
 PATH='I97',
 DRAWING='@BASEBOARD_FAB2_LIB.BASEBOARD_FAB2(SCH_1):PAGE149',
 TOLERANCE='10%',
 MATERIAL='X6S',
 BOM_COST='PROC',
 PHYS_PAGE='149',
 XY='(-1150,2900)',
 ROT='0',
 VER='1',
 VALUE='1.0UF',
 PACK_TYPE='0402',
 PART_NUMBER='D97712-011',
 LOCATION='C25W41',
 ROOM='PROC_SIDEBAND',
 CDS_LIB='mstr_discrete',
 CDS_PART_NAME='CAP_0402-1.0UF,16V,10%,X6S,D97A',
 VOLTAGE='16V',
 PRIM_FILE='./archive_libs/mstr_discrete/cap/chips/chips.prt';

PART_NAME
 C25W42 'CAP_0402-1.0UF,16V,10%,X6S,D97A':
 ROOM='PROC_SIDEBAND';

SECTION_NUMBER 1
 '@BASEBOARD_FAB2_LIB.BASEBOARD_FAB2(SCH_1):PAGE149_I98@MSTR_DISCRETE.CAP(CHIPS)':
 C_PATH='@baseboard_fab2_lib.baseboard_fab2(sch_1):page149_i98@mstr_discrete.cap~
(chips)',
 P_PATH='@baseboard_fab2_lib.baseboard_fab2(sch_1):page149_i98@mstr_discrete.cap~
(chips)',
 PATH='I98',
 DRAWING='@BASEBOARD_FAB2_LIB.BASEBOARD_FAB2(SCH_1):PAGE149',
 TOLERANCE='10%',
 MATERIAL='X6S',
 BOM_COST='PROC',
 PHYS_PAGE='149',
 XY='(-900,2900)',
 ROT='0',
 VER='1',
 VALUE='1.0UF',
 PACK_TYPE='0402',
 PART_NUMBER='D97712-011',
 LOCATION='C25W42',
 ROOM='PROC_SIDEBAND',
 CDS_LIB='mstr_discrete',
 CDS_PART_NAME='CAP_0402-1.0UF,16V,10%,X6S,D97A',
 VOLTAGE='16V',
 PRIM_FILE='./archive_libs/mstr_discrete/cap/chips/chips.prt';

PART_NAME
 C25W43 'CAP_0402-1.0UF,16V,10%,X6S,D97A':
 ROOM='PROC_SIDEBAND';

SECTION_NUMBER 1
 '@BASEBOARD_FAB2_LIB.BASEBOARD_FAB2(SCH_1):PAGE149_I100@MSTR_DISCRETE.CAP(CHIPS)':
 C_PATH='@baseboard_fab2_lib.baseboard_fab2(sch_1):page149_i100@mstr_discrete.ca~
p(chips)',
 P_PATH='@baseboard_fab2_lib.baseboard_fab2(sch_1):page149_i100@mstr_discrete.ca~
p(chips)',
 PATH='I100',
 DRAWING='@BASEBOARD_FAB2_LIB.BASEBOARD_FAB2(SCH_1):PAGE149',
 TOLERANCE='10%',
 MATERIAL='X6S',
 BOM_COST='PROC',
 PHYS_PAGE='149',
 XY='(-650,2900)',
 ROT='0',
 VER='1',
 VALUE='1.0UF',
 PACK_TYPE='0402',
 PART_NUMBER='D97712-011',
 LOCATION='C25W43',
 ROOM='PROC_SIDEBAND',
 CDS_LIB='mstr_discrete',
 CDS_PART_NAME='CAP_0402-1.0UF,16V,10%,X6S,D97A',
 VOLTAGE='16V',
 PRIM_FILE='./archive_libs/mstr_discrete/cap/chips/chips.prt';

PART_NAME
 C25W44 'CAP_0402-1.0UF,16V,10%,X6S,D97A':
 ROOM='PROC_SIDEBAND';

SECTION_NUMBER 1
 '@BASEBOARD_FAB2_LIB.BASEBOARD_FAB2(SCH_1):PAGE149_I101@MSTR_DISCRETE.CAP(CHIPS)':
 C_PATH='@baseboard_fab2_lib.baseboard_fab2(sch_1):page149_i101@mstr_discrete.ca~
p(chips)',
 P_PATH='@baseboard_fab2_lib.baseboard_fab2(sch_1):page149_i101@mstr_discrete.ca~
p(chips)',
 PATH='I101',
 DRAWING='@BASEBOARD_FAB2_LIB.BASEBOARD_FAB2(SCH_1):PAGE149',
 TOLERANCE='10%',
 MATERIAL='X6S',
 BOM_COST='PROC',
 PHYS_PAGE='149',
 XY='(-350,2900)',
 ROT='0',
 VER='1',
 VALUE='1.0UF',
 PACK_TYPE='0402',
 PART_NUMBER='D97712-011',
 LOCATION='C25W44',
 ROOM='PROC_SIDEBAND',
 CDS_LIB='mstr_discrete',
 CDS_PART_NAME='CAP_0402-1.0UF,16V,10%,X6S,D97A',
 VOLTAGE='16V',
 PRIM_FILE='./archive_libs/mstr_discrete/cap/chips/chips.prt';

PART_NAME
 C25W45 'CAP_A_0402V-0.1UF,16V,10%,X7R,A':
 ROOM='VDDQ_KLM_PWR_VR';

SECTION_NUMBER 1
 '@BASEBOARD_FAB2_LIB.BASEBOARD_FAB2(SCH_1):PAGE149_I122@DEV_DISCRETE.CAP_A(CHIPS)':
 C_PATH='@baseboard_fab2_lib.baseboard_fab2(sch_1):page149_i122@dev_discrete.cap~
_a(chips)',
 P_PATH='@baseboard_fab2_lib.baseboard_fab2(sch_1):page149_i122@dev_discrete.cap~
_a(chips)',
 PATH='I122',
 DRAWING='@BASEBOARD_FAB2_LIB.BASEBOARD_FAB2(SCH_1):PAGE149',
 TOLERANCE='10%',
 SEC_TYPE='0402V',
 MATERIAL='X7R',
 PHYS_PAGE='149',
 XY='(-100,2900)',
 ROT='0',
 VER='1',
 VALUE='0.1UF',
 PACK_TYPE='0402V',
 PART_NUMBER='A36096-030',
 LOCATION='C25W45',
 ROOM='VDDQ_KLM_PWR_VR',
 SEC='1',
 CDS_LIB='dev_discrete',
 CDS_PART_NAME='CAP_A_0402V-0.1UF,16V,10%,X7R,A',
 VOLTAGE='16V',
 PRIM_FILE='./archive_libs/discrete/cap_a/chips/chips.prt';

PART_NAME
 C25W46 'CAP_0805-10UF,16V,10%,X6S,C953A':
 ROOM='BMC';

SECTION_NUMBER 1
 '@BASEBOARD_FAB2_LIB.BASEBOARD_FAB2(SCH_1):PAGE149_I51@MSTR_DISCRETE.CAP(CHIPS)':
 C_PATH='@baseboard_fab2_lib.baseboard_fab2(sch_1):page149_i51@mstr_discrete.cap~
(chips)',
 P_PATH='@baseboard_fab2_lib.baseboard_fab2(sch_1):page149_i51@mstr_discrete.cap~
(chips)',
 PATH='I51',
 DRAWING='@BASEBOARD_FAB2_LIB.BASEBOARD_FAB2(SCH_1):PAGE149',
 TOLERANCE='10%',
 MATERIAL='X6S',
 BOM_COST='SM_CONTROLLER',
 PHYS_PAGE='149',
 XY='(250,2900)',
 ROT='0',
 VER='1',
 VALUE='10UF',
 PACK_TYPE='0805',
 PART_NUMBER='C95333-007',
 LOCATION='C25W46',
 ROOM='BMC',
 CDS_LIB='mstr_discrete',
 CDS_PART_NAME='CAP_0805-10UF,16V,10%,X6S,C953A',
 VOLTAGE='16V',
 PRIM_FILE='./archive_libs/mstr_discrete/cap/chips/chips.prt';

PART_NAME
 C25W47 'CAP_0603-4.7UF,6.3V,10%,X6S,E1A':;

SECTION_NUMBER 1
 '@BASEBOARD_FAB2_LIB.BASEBOARD_FAB2(SCH_1):PAGE149_I50@MSTR_DISCRETE.CAP(CHIPS)':
 C_PATH='@baseboard_fab2_lib.baseboard_fab2(sch_1):page149_i50@mstr_discrete.cap~
(chips)',
 P_PATH='@baseboard_fab2_lib.baseboard_fab2(sch_1):page149_i50@mstr_discrete.cap~
(chips)',
 PATH='I50',
 DRAWING='@BASEBOARD_FAB2_LIB.BASEBOARD_FAB2(SCH_1):PAGE149',
 TOLERANCE='10%',
 MATERIAL='X6S',
 PHYS_PAGE='149',
 XY='(550,2900)',
 ROT='0',
 VER='1',
 VALUE='4.7UF',
 PACK_TYPE='0603',
 PART_NUMBER='E15431-003',
 LOCATION='C25W47',
 CDS_LIB='mstr_discrete',
 CDS_PART_NAME='CAP_0603-4.7UF,6.3V,10%,X6S,E1A',
 VOLTAGE='6.3V',
 PRIM_FILE='./archive_libs/mstr_discrete/cap/chips/chips.prt';

PART_NAME
 C25W48 'CAP_0402-1.0UF,16V,10%,X6S,D97A':
 ROOM='PROC_SIDEBAND';

SECTION_NUMBER 1
 '@BASEBOARD_FAB2_LIB.BASEBOARD_FAB2(SCH_1):PAGE149_I112@MSTR_DISCRETE.CAP(CHIPS)':
 C_PATH='@baseboard_fab2_lib.baseboard_fab2(sch_1):page149_i112@mstr_discrete.ca~
p(chips)',
 P_PATH='@baseboard_fab2_lib.baseboard_fab2(sch_1):page149_i112@mstr_discrete.ca~
p(chips)',
 PATH='I112',
 DRAWING='@BASEBOARD_FAB2_LIB.BASEBOARD_FAB2(SCH_1):PAGE149',
 TOLERANCE='10%',
 MATERIAL='X6S',
 BOM_COST='PROC',
 PHYS_PAGE='149',
 XY='(2325,3000)',
 ROT='0',
 VER='1',
 VALUE='1.0UF',
 PACK_TYPE='0402',
 PART_NUMBER='D97712-011',
 LOCATION='C25W48',
 ROOM='PROC_SIDEBAND',
 CDS_LIB='mstr_discrete',
 CDS_PART_NAME='CAP_0402-1.0UF,16V,10%,X6S,D97A',
 VOLTAGE='16V',
 PRIM_FILE='./archive_libs/mstr_discrete/cap/chips/chips.prt';

PART_NAME
 C25W49 'CAP_A_0402V-0.1UF,16V,10%,X7R,A':
 ROOM='VDDQ_KLM_PWR_VR';

SECTION_NUMBER 1
 '@BASEBOARD_FAB2_LIB.BASEBOARD_FAB2(SCH_1):PAGE149_I123@DEV_DISCRETE.CAP_A(CHIPS)':
 C_PATH='@baseboard_fab2_lib.baseboard_fab2(sch_1):page149_i123@dev_discrete.cap~
_a(chips)',
 P_PATH='@baseboard_fab2_lib.baseboard_fab2(sch_1):page149_i123@dev_discrete.cap~
_a(chips)',
 PATH='I123',
 DRAWING='@BASEBOARD_FAB2_LIB.BASEBOARD_FAB2(SCH_1):PAGE149',
 TOLERANCE='10%',
 SEC_TYPE='0402V',
 MATERIAL='X7R',
 PHYS_PAGE='149',
 XY='(2875,3000)',
 ROT='0',
 VER='1',
 VALUE='0.1UF',
 PACK_TYPE='0402V',
 PART_NUMBER='A36096-030',
 LOCATION='C25W49',
 ROOM='VDDQ_KLM_PWR_VR',
 SEC='1',
 CDS_LIB='dev_discrete',
 CDS_PART_NAME='CAP_A_0402V-0.1UF,16V,10%,X7R,A',
 VOLTAGE='16V',
 PRIM_FILE='./archive_libs/discrete/cap_a/chips/chips.prt';

PART_NAME
 C25W50 'CAP_0603-4.7UF,6.3V,10%,X6S,E1A':;

SECTION_NUMBER 1
 '@BASEBOARD_FAB2_LIB.BASEBOARD_FAB2(SCH_1):PAGE149_I31@MSTR_DISCRETE.CAP(CHIPS)':
 C_PATH='@baseboard_fab2_lib.baseboard_fab2(sch_1):page149_i31@mstr_discrete.cap~
(chips)',
 P_PATH='@baseboard_fab2_lib.baseboard_fab2(sch_1):page149_i31@mstr_discrete.cap~
(chips)',
 PATH='I31',
 DRAWING='@BASEBOARD_FAB2_LIB.BASEBOARD_FAB2(SCH_1):PAGE149',
 TOLERANCE='10%',
 MATERIAL='X6S',
 PHYS_PAGE='149',
 XY='(3275,3000)',
 ROT='0',
 VER='1',
 VALUE='4.7UF',
 PACK_TYPE='0603',
 PART_NUMBER='E15431-003',
 LOCATION='C25W50',
 CDS_LIB='mstr_discrete',
 CDS_PART_NAME='CAP_0603-4.7UF,6.3V,10%,X6S,E1A',
 VOLTAGE='6.3V',
 PRIM_FILE='./archive_libs/mstr_discrete/cap/chips/chips.prt';

PART_NAME
 C25W51 'CAP_0402-1.0UF,16V,10%,X6S,D97A':
 ROOM='PROC_SIDEBAND';

SECTION_NUMBER 1
 '@BASEBOARD_FAB2_LIB.BASEBOARD_FAB2(SCH_1):PAGE149_I114@MSTR_DISCRETE.CAP(CHIPS)':
 C_PATH='@baseboard_fab2_lib.baseboard_fab2(sch_1):page149_i114@mstr_discrete.ca~
p(chips)',
 P_PATH='@baseboard_fab2_lib.baseboard_fab2(sch_1):page149_i114@mstr_discrete.ca~
p(chips)',
 PATH='I114',
 DRAWING='@BASEBOARD_FAB2_LIB.BASEBOARD_FAB2(SCH_1):PAGE149',
 TOLERANCE='10%',
 MATERIAL='X6S',
 BOM_COST='PROC',
 PHYS_PAGE='149',
 XY='(3950,2900)',
 ROT='0',
 VER='1',
 VALUE='1.0UF',
 PACK_TYPE='0402',
 PART_NUMBER='D97712-011',
 LOCATION='C25W51',
 ROOM='PROC_SIDEBAND',
 CDS_LIB='mstr_discrete',
 CDS_PART_NAME='CAP_0402-1.0UF,16V,10%,X6S,D97A',
 VOLTAGE='16V',
 PRIM_FILE='./archive_libs/mstr_discrete/cap/chips/chips.prt';

PART_NAME
 C25W52 'CAP_0402-1.0UF,16V,10%,X6S,D97A':
 ROOM='PROC_SIDEBAND';

SECTION_NUMBER 1
 '@BASEBOARD_FAB2_LIB.BASEBOARD_FAB2(SCH_1):PAGE149_I118@MSTR_DISCRETE.CAP(CHIPS)':
 C_PATH='@baseboard_fab2_lib.baseboard_fab2(sch_1):page149_i118@mstr_discrete.ca~
p(chips)',
 P_PATH='@baseboard_fab2_lib.baseboard_fab2(sch_1):page149_i118@mstr_discrete.ca~
p(chips)',
 PATH='I118',
 DRAWING='@BASEBOARD_FAB2_LIB.BASEBOARD_FAB2(SCH_1):PAGE149',
 TOLERANCE='10%',
 MATERIAL='X6S',
 BOM_COST='PROC',
 PHYS_PAGE='149',
 XY='(4250,2900)',
 ROT='0',
 VER='1',
 VALUE='1.0UF',
 PACK_TYPE='0402',
 PART_NUMBER='D97712-011',
 LOCATION='C25W52',
 ROOM='PROC_SIDEBAND',
 CDS_LIB='mstr_discrete',
 CDS_PART_NAME='CAP_0402-1.0UF,16V,10%,X6S,D97A',
 VOLTAGE='16V',
 PRIM_FILE='./archive_libs/mstr_discrete/cap/chips/chips.prt';

PART_NAME
 C25W53 'CAP_0402-1.0UF,16V,10%,X6S,D97A':
 ROOM='PROC_SIDEBAND';

SECTION_NUMBER 1
 '@BASEBOARD_FAB2_LIB.BASEBOARD_FAB2(SCH_1):PAGE149_I92@MSTR_DISCRETE.CAP(CHIPS)':
 C_PATH='@baseboard_fab2_lib.baseboard_fab2(sch_1):page149_i92@mstr_discrete.cap~
(chips)',
 P_PATH='@baseboard_fab2_lib.baseboard_fab2(sch_1):page149_i92@mstr_discrete.cap~
(chips)',
 PATH='I92',
 DRAWING='@BASEBOARD_FAB2_LIB.BASEBOARD_FAB2(SCH_1):PAGE149',
 TOLERANCE='10%',
 SEC_TYPE='0402',
 MATERIAL='X6S',
 BOM_COST='PROC',
 PHYS_PAGE='149',
 XY='(4500,2900)',
 ROT='0',
 VER='1',
 VALUE='1.0UF',
 PACK_TYPE='0402',
 PART_NUMBER='D97712-011',
 LOCATION='C25W53',
 ROOM='PROC_SIDEBAND',
 SEC='1',
 CDS_LIB='mstr_discrete',
 CDS_PART_NAME='CAP_0402-1.0UF,16V,10%,X6S,D97A',
 VOLTAGE='16V',
 PRIM_FILE='./archive_libs/mstr_discrete/cap/chips/chips.prt';

PART_NAME
 C25W54 'CAP_0402-1.0UF,16V,10%,X6S,D97A':
 ROOM='PROC_SIDEBAND';

SECTION_NUMBER 1
 '@BASEBOARD_FAB2_LIB.BASEBOARD_FAB2(SCH_1):PAGE149_I95@MSTR_DISCRETE.CAP(CHIPS)':
 C_PATH='@baseboard_fab2_lib.baseboard_fab2(sch_1):page149_i95@mstr_discrete.cap~
(chips)',
 P_PATH='@baseboard_fab2_lib.baseboard_fab2(sch_1):page149_i95@mstr_discrete.cap~
(chips)',
 PATH='I95',
 DRAWING='@BASEBOARD_FAB2_LIB.BASEBOARD_FAB2(SCH_1):PAGE149',
 TOLERANCE='10%',
 MATERIAL='X6S',
 BOM_COST='PROC',
 PHYS_PAGE='149',
 XY='(4750,2900)',
 ROT='0',
 VER='1',
 VALUE='1.0UF',
 PACK_TYPE='0402',
 PART_NUMBER='D97712-011',
 LOCATION='C25W54',
 ROOM='PROC_SIDEBAND',
 CDS_LIB='mstr_discrete',
 CDS_PART_NAME='CAP_0402-1.0UF,16V,10%,X6S,D97A',
 VOLTAGE='16V',
 PRIM_FILE='./archive_libs/mstr_discrete/cap/chips/chips.prt';

PART_NAME
 C25W55 'CAP_A_0402V-0.1UF,16V,10%,X7R,A':
 ROOM='VDDQ_KLM_PWR_VR';

SECTION_NUMBER 1
 '@BASEBOARD_FAB2_LIB.BASEBOARD_FAB2(SCH_1):PAGE149_I124@DEV_DISCRETE.CAP_A(CHIPS)':
 C_PATH='@baseboard_fab2_lib.baseboard_fab2(sch_1):page149_i124@dev_discrete.cap~
_a(chips)',
 P_PATH='@baseboard_fab2_lib.baseboard_fab2(sch_1):page149_i124@dev_discrete.cap~
_a(chips)',
 PATH='I124',
 DRAWING='@BASEBOARD_FAB2_LIB.BASEBOARD_FAB2(SCH_1):PAGE149',
 TOLERANCE='10%',
 SEC_TYPE='0402V',
 MATERIAL='X7R',
 PHYS_PAGE='149',
 XY='(5000,2925)',
 ROT='0',
 VER='1',
 VALUE='0.1UF',
 PACK_TYPE='0402V',
 PART_NUMBER='A36096-030',
 LOCATION='C25W55',
 ROOM='VDDQ_KLM_PWR_VR',
 SEC='1',
 CDS_LIB='dev_discrete',
 CDS_PART_NAME='CAP_A_0402V-0.1UF,16V,10%,X7R,A',
 VOLTAGE='16V',
 PRIM_FILE='./archive_libs/discrete/cap_a/chips/chips.prt';

PART_NAME
 C25W56 'CAP_0402-1.0UF,16V,10%,X6S,D97A':
 ROOM='PROC_SIDEBAND';

SECTION_NUMBER 1
 '@BASEBOARD_FAB2_LIB.BASEBOARD_FAB2(SCH_1):PAGE149_I93@MSTR_DISCRETE.CAP(CHIPS)':
 C_PATH='@baseboard_fab2_lib.baseboard_fab2(sch_1):page149_i93@mstr_discrete.cap~
(chips)',
 P_PATH='@baseboard_fab2_lib.baseboard_fab2(sch_1):page149_i93@mstr_discrete.cap~
(chips)',
 PATH='I93',
 DRAWING='@BASEBOARD_FAB2_LIB.BASEBOARD_FAB2(SCH_1):PAGE149',
 TOLERANCE='10%',
 MATERIAL='X6S',
 BOM_COST='PROC',
 PHYS_PAGE='149',
 XY='(-850,1850)',
 ROT='0',
 VER='1',
 VALUE='1.0UF',
 PACK_TYPE='0402',
 PART_NUMBER='D97712-011',
 LOCATION='C25W56',
 ROOM='PROC_SIDEBAND',
 CDS_LIB='mstr_discrete',
 CDS_PART_NAME='CAP_0402-1.0UF,16V,10%,X6S,D97A',
 VOLTAGE='16V',
 PRIM_FILE='./archive_libs/mstr_discrete/cap/chips/chips.prt';

PART_NAME
 C25W57 'CAP_0402LF-100.0PF,50V,5%,COG,A':
 ROOM='BMC';

SECTION_NUMBER 1
 '@BASEBOARD_FAB2_LIB.BASEBOARD_FAB2(SCH_1):PAGE149_I130@MSTR_DISCRETE.CAP(CHIPS)':
 C_PATH='@baseboard_fab2_lib.baseboard_fab2(sch_1):page149_i130@mstr_discrete.ca~
p(chips)',
 P_PATH='@baseboard_fab2_lib.baseboard_fab2(sch_1):page149_i130@mstr_discrete.ca~
p(chips)',
 PATH='I130',
 DRAWING='@BASEBOARD_FAB2_LIB.BASEBOARD_FAB2(SCH_1):PAGE149',
 TOLERANCE='5%',
 SEC_TYPE='0402LF',
 MATERIAL='COG',
 BOM_COST='SM_CONTROLLER',
 PHYS_PAGE='149',
 XY='(-1450,1825)',
 ROT='0',
 VER='1',
 VALUE='100.0PF',
 PACK_TYPE='0402LF',
 PART_NUMBER='A36095-026',
 LOCATION='C25W57',
 ROOM='BMC',
 SEC='1',
 CDS_LIB='mstr_discrete',
 CDS_PART_NAME='CAP_0402LF-100.0PF,50V,5%,COG,A',
 VOLTAGE='50V',
 PRIM_FILE='./archive_libs/mstr_discrete/cap/chips/chips.prt';

PART_NAME
 C25W58 'CAP_A_0402V-0.1UF,16V,10%,X7R,A':
 ROOM='VDDQ_KLM_PWR_VR';

SECTION_NUMBER 1
 '@BASEBOARD_FAB2_LIB.BASEBOARD_FAB2(SCH_1):PAGE149_I125@DEV_DISCRETE.CAP_A(CHIPS)':
 C_PATH='@baseboard_fab2_lib.baseboard_fab2(sch_1):page149_i125@dev_discrete.cap~
_a(chips)',
 P_PATH='@baseboard_fab2_lib.baseboard_fab2(sch_1):page149_i125@dev_discrete.cap~
_a(chips)',
 PATH='I125',
 DRAWING='@BASEBOARD_FAB2_LIB.BASEBOARD_FAB2(SCH_1):PAGE149',
 TOLERANCE='10%',
 SEC_TYPE='0402V',
 MATERIAL='X7R',
 PHYS_PAGE='149',
 XY='(-1150,1850)',
 ROT='0',
 VER='1',
 VALUE='0.1UF',
 PACK_TYPE='0402V',
 PART_NUMBER='A36096-030',
 LOCATION='C25W58',
 ROOM='VDDQ_KLM_PWR_VR',
 SEC='1',
 CDS_LIB='dev_discrete',
 CDS_PART_NAME='CAP_A_0402V-0.1UF,16V,10%,X7R,A',
 VOLTAGE='16V',
 PRIM_FILE='./archive_libs/discrete/cap_a/chips/chips.prt';

PART_NAME
 C25W59 'CAP_0603-4.7UF,6.3V,10%,X6S,E1A':;

SECTION_NUMBER 1
 '@BASEBOARD_FAB2_LIB.BASEBOARD_FAB2(SCH_1):PAGE149_I79@MSTR_DISCRETE.CAP(CHIPS)':
 C_PATH='@baseboard_fab2_lib.baseboard_fab2(sch_1):page149_i79@mstr_discrete.cap~
(chips)',
 P_PATH='@baseboard_fab2_lib.baseboard_fab2(sch_1):page149_i79@mstr_discrete.cap~
(chips)',
 PATH='I79',
 DRAWING='@BASEBOARD_FAB2_LIB.BASEBOARD_FAB2(SCH_1):PAGE149',
 POP='NOPOP',
 TOLERANCE='10%',
 SEC_TYPE='0603',
 MATERIAL='X6S',
 PHYS_PAGE='149',
 XY='(-550,1850)',
 ROT='0',
 VER='1',
 VALUE='4.7UF',
 PACK_TYPE='0603',
 PART_NUMBER='E15431-003',
 LOCATION='C25W59',
 SEC='1',
 CDS_LIB='mstr_discrete',
 CDS_PART_NAME='CAP_0603-4.7UF,6.3V,10%,X6S,E1A',
 VOLTAGE='6.3V',
 PRIM_FILE='./archive_libs/mstr_discrete/cap/chips/chips.prt';

PART_NAME
 C25W60 'CAP_0402-1.0UF,16V,10%,X6S,D97A':
 ROOM='PROC_SIDEBAND';

SECTION_NUMBER 1
 '@BASEBOARD_FAB2_LIB.BASEBOARD_FAB2(SCH_1):PAGE149_I109@MSTR_DISCRETE.CAP(CHIPS)':
 C_PATH='@baseboard_fab2_lib.baseboard_fab2(sch_1):page149_i109@mstr_discrete.ca~
p(chips)',
 P_PATH='@baseboard_fab2_lib.baseboard_fab2(sch_1):page149_i109@mstr_discrete.ca~
p(chips)',
 PATH='I109',
 DRAWING='@BASEBOARD_FAB2_LIB.BASEBOARD_FAB2(SCH_1):PAGE149',
 TOLERANCE='10%',
 MATERIAL='X6S',
 BOM_COST='PROC',
 PHYS_PAGE='149',
 XY='(1475,1725)',
 ROT='0',
 VER='1',
 VALUE='1.0UF',
 PACK_TYPE='0402',
 PART_NUMBER='D97712-011',
 LOCATION='C25W60',
 ROOM='PROC_SIDEBAND',
 CDS_LIB='mstr_discrete',
 CDS_PART_NAME='CAP_0402-1.0UF,16V,10%,X6S,D97A',
 VOLTAGE='16V',
 PRIM_FILE='./archive_libs/mstr_discrete/cap/chips/chips.prt';

PART_NAME
 C25W61 'CAP_A_0402V-0.1UF,16V,10%,X7R,A':
 ROOM='VDDQ_KLM_PWR_VR';

SECTION_NUMBER 1
 '@BASEBOARD_FAB2_LIB.BASEBOARD_FAB2(SCH_1):PAGE149_I126@DEV_DISCRETE.CAP_A(CHIPS)':
 C_PATH='@baseboard_fab2_lib.baseboard_fab2(sch_1):page149_i126@dev_discrete.cap~
_a(chips)',
 P_PATH='@baseboard_fab2_lib.baseboard_fab2(sch_1):page149_i126@dev_discrete.cap~
_a(chips)',
 PATH='I126',
 DRAWING='@BASEBOARD_FAB2_LIB.BASEBOARD_FAB2(SCH_1):PAGE149',
 TOLERANCE='10%',
 SEC_TYPE='0402V',
 MATERIAL='X7R',
 PHYS_PAGE='149',
 XY='(2025,1750)',
 ROT='0',
 VER='1',
 VALUE='0.1UF',
 PACK_TYPE='0402V',
 PART_NUMBER='A36096-030',
 LOCATION='C25W61',
 ROOM='VDDQ_KLM_PWR_VR',
 SEC='1',
 CDS_LIB='dev_discrete',
 CDS_PART_NAME='CAP_A_0402V-0.1UF,16V,10%,X7R,A',
 VOLTAGE='16V',
 PRIM_FILE='./archive_libs/discrete/cap_a/chips/chips.prt';

PART_NAME
 C25W62 'CAP_0603-4.7UF,6.3V,10%,X6S,E1A':;

SECTION_NUMBER 1
 '@BASEBOARD_FAB2_LIB.BASEBOARD_FAB2(SCH_1):PAGE149_I40@MSTR_DISCRETE.CAP(CHIPS)':
 C_PATH='@baseboard_fab2_lib.baseboard_fab2(sch_1):page149_i40@mstr_discrete.cap~
(chips)',
 P_PATH='@baseboard_fab2_lib.baseboard_fab2(sch_1):page149_i40@mstr_discrete.cap~
(chips)',
 PATH='I40',
 DRAWING='@BASEBOARD_FAB2_LIB.BASEBOARD_FAB2(SCH_1):PAGE149',
 TOLERANCE='10%',
 MATERIAL='X6S',
 PHYS_PAGE='149',
 XY='(2425,1750)',
 ROT='0',
 VER='1',
 VALUE='4.7UF',
 PACK_TYPE='0603',
 PART_NUMBER='E15431-003',
 LOCATION='C25W62',
 CDS_LIB='mstr_discrete',
 CDS_PART_NAME='CAP_0603-4.7UF,6.3V,10%,X6S,E1A',
 VOLTAGE='6.3V',
 PRIM_FILE='./archive_libs/mstr_discrete/cap/chips/chips.prt';

PART_NAME
 C25W66 'CAP_0402-1.0UF,16V,10%,X6S,D97A':
 ROOM='PROC_SIDEBAND';

SECTION_NUMBER 1
 '@BASEBOARD_FAB2_LIB.BASEBOARD_FAB2(SCH_1):PAGE149_I116@MSTR_DISCRETE.CAP(CHIPS)':
 C_PATH='@baseboard_fab2_lib.baseboard_fab2(sch_1):page149_i116@mstr_discrete.ca~
p(chips)',
 P_PATH='@baseboard_fab2_lib.baseboard_fab2(sch_1):page149_i116@mstr_discrete.ca~
p(chips)',
 PATH='I116',
 DRAWING='@BASEBOARD_FAB2_LIB.BASEBOARD_FAB2(SCH_1):PAGE149',
 TOLERANCE='10%',
 MATERIAL='X6S',
 BOM_COST='PROC',
 PHYS_PAGE='149',
 XY='(2150,5175)',
 ROT='0',
 VER='1',
 VALUE='1.0UF',
 PACK_TYPE='0402',
 PART_NUMBER='D97712-011',
 LOCATION='C25W66',
 ROOM='PROC_SIDEBAND',
 CDS_LIB='mstr_discrete',
 CDS_PART_NAME='CAP_0402-1.0UF,16V,10%,X6S,D97A',
 VOLTAGE='16V',
 PRIM_FILE='./archive_libs/mstr_discrete/cap/chips/chips.prt';

PART_NAME
 C25W67 'CAP_0402-1.0UF,16V,10%,X6S,D97A':
 ROOM='PROC_SIDEBAND';

SECTION_NUMBER 1
 '@BASEBOARD_FAB2_LIB.BASEBOARD_FAB2(SCH_1):PAGE149_I117@MSTR_DISCRETE.CAP(CHIPS)':
 C_PATH='@baseboard_fab2_lib.baseboard_fab2(sch_1):page149_i117@mstr_discrete.ca~
p(chips)',
 P_PATH='@baseboard_fab2_lib.baseboard_fab2(sch_1):page149_i117@mstr_discrete.ca~
p(chips)',
 PATH='I117',
 DRAWING='@BASEBOARD_FAB2_LIB.BASEBOARD_FAB2(SCH_1):PAGE149',
 TOLERANCE='10%',
 MATERIAL='X6S',
 BOM_COST='PROC',
 PHYS_PAGE='149',
 XY='(2400,5175)',
 ROT='0',
 VER='1',
 VALUE='1.0UF',
 PACK_TYPE='0402',
 PART_NUMBER='D97712-011',
 LOCATION='C25W67',
 ROOM='PROC_SIDEBAND',
 CDS_LIB='mstr_discrete',
 CDS_PART_NAME='CAP_0402-1.0UF,16V,10%,X6S,D97A',
 VOLTAGE='16V',
 PRIM_FILE='./archive_libs/mstr_discrete/cap/chips/chips.prt';

PART_NAME
 C25W68 'CAP_A_0402V-0.1UF,16V,10%,X7R,A':
 ROOM='VDDQ_KLM_PWR_VR';

SECTION_NUMBER 1
 '@BASEBOARD_FAB2_LIB.BASEBOARD_FAB2(SCH_1):PAGE149_I128@DEV_DISCRETE.CAP_A(CHIPS)':
 C_PATH='@baseboard_fab2_lib.baseboard_fab2(sch_1):page149_i128@dev_discrete.cap~
_a(chips)',
 P_PATH='@baseboard_fab2_lib.baseboard_fab2(sch_1):page149_i128@dev_discrete.cap~
_a(chips)',
 PATH='I128',
 DRAWING='@BASEBOARD_FAB2_LIB.BASEBOARD_FAB2(SCH_1):PAGE149',
 TOLERANCE='10%',
 SEC_TYPE='0402V',
 MATERIAL='X7R',
 PHYS_PAGE='149',
 XY='(2700,5175)',
 ROT='0',
 VER='1',
 VALUE='0.1UF',
 PACK_TYPE='0402V',
 PART_NUMBER='A36096-030',
 LOCATION='C25W68',
 ROOM='VDDQ_KLM_PWR_VR',
 SEC='1',
 CDS_LIB='dev_discrete',
 CDS_PART_NAME='CAP_A_0402V-0.1UF,16V,10%,X7R,A',
 VOLTAGE='16V',
 PRIM_FILE='./archive_libs/discrete/cap_a/chips/chips.prt';

PART_NAME
 C25W69 'CAP_0603-4.7UF,6.3V,10%,X6S,E1A':;

SECTION_NUMBER 1
 '@BASEBOARD_FAB2_LIB.BASEBOARD_FAB2(SCH_1):PAGE149_I17@MSTR_DISCRETE.CAP(CHIPS)':
 C_PATH='@baseboard_fab2_lib.baseboard_fab2(sch_1):page149_i17@mstr_discrete.cap~
(chips)',
 P_PATH='@baseboard_fab2_lib.baseboard_fab2(sch_1):page149_i17@mstr_discrete.cap~
(chips)',
 PATH='I17',
 DRAWING='@BASEBOARD_FAB2_LIB.BASEBOARD_FAB2(SCH_1):PAGE149',
 TOLERANCE='10%',
 MATERIAL='X6S',
 PHYS_PAGE='149',
 XY='(3100,5175)',
 ROT='0',
 VER='1',
 VALUE='4.7UF',
 PACK_TYPE='0603',
 PART_NUMBER='E15431-003',
 LOCATION='C25W69',
 CDS_LIB='mstr_discrete',
 CDS_PART_NAME='CAP_0603-4.7UF,6.3V,10%,X6S,E1A',
 VOLTAGE='6.3V',
 PRIM_FILE='./archive_libs/mstr_discrete/cap/chips/chips.prt';

PART_NAME
 C25W70 'CAP_0603-4.7UF,6.3V,10%,X6S,E1A':;

SECTION_NUMBER 1
 '@BASEBOARD_FAB2_LIB.BASEBOARD_FAB2(SCH_1):PAGE149_I5@MSTR_DISCRETE.CAP(CHIPS)':
 C_PATH='@baseboard_fab2_lib.baseboard_fab2(sch_1):page149_i5@mstr_discrete.cap(~
chips)',
 P_PATH='@baseboard_fab2_lib.baseboard_fab2(sch_1):page149_i5@mstr_discrete.cap(~
chips)',
 PATH='I5',
 DRAWING='@BASEBOARD_FAB2_LIB.BASEBOARD_FAB2(SCH_1):PAGE149',
 TOLERANCE='10%',
 MATERIAL='X6S',
 PHYS_PAGE='149',
 XY='(4300,5300)',
 ROT='0',
 VER='1',
 VALUE='4.7UF',
 PACK_TYPE='0603',
 PART_NUMBER='E15431-003',
 LOCATION='C25W70',
 CDS_LIB='mstr_discrete',
 CDS_PART_NAME='CAP_0603-4.7UF,6.3V,10%,X6S,E1A',
 VOLTAGE='6.3V',
 PRIM_FILE='./archive_libs/mstr_discrete/cap/chips/chips.prt';

PART_NAME
 C25W71 'CAP_0402-1.0UF,16V,10%,X6S,D97A':
 ROOM='PROC_SIDEBAND';

SECTION_NUMBER 1
 '@BASEBOARD_FAB2_LIB.BASEBOARD_FAB2(SCH_1):PAGE149_I115@MSTR_DISCRETE.CAP(CHIPS)':
 C_PATH='@baseboard_fab2_lib.baseboard_fab2(sch_1):page149_i115@mstr_discrete.ca~
p(chips)',
 P_PATH='@baseboard_fab2_lib.baseboard_fab2(sch_1):page149_i115@mstr_discrete.ca~
p(chips)',
 PATH='I115',
 DRAWING='@BASEBOARD_FAB2_LIB.BASEBOARD_FAB2(SCH_1):PAGE149',
 TOLERANCE='10%',
 MATERIAL='X6S',
 BOM_COST='PROC',
 PHYS_PAGE='149',
 XY='(4800,5300)',
 ROT='0',
 VER='1',
 VALUE='1.0UF',
 PACK_TYPE='0402',
 PART_NUMBER='D97712-011',
 LOCATION='C25W71',
 ROOM='PROC_SIDEBAND',
 CDS_LIB='mstr_discrete',
 CDS_PART_NAME='CAP_0402-1.0UF,16V,10%,X6S,D97A',
 VOLTAGE='16V',
 PRIM_FILE='./archive_libs/mstr_discrete/cap/chips/chips.prt';

PART_NAME
 C25W72 'CAP_0402LF-12.0PF,50V,5%,COG,AA':
 GROUP='AST2500',
 ROOM='LBG';

SECTION_NUMBER 1
 '@BASEBOARD_FAB2_LIB.BASEBOARD_FAB2(SCH_1):PAGE255_I7@MSTR_DISCRETE.CAP(CHIPS)':
 C_PATH='@baseboard_fab2_lib.baseboard_fab2(sch_1):page255_i7@mstr_discrete.cap(~
chips)',
 P_PATH='@baseboard_fab2_lib.baseboard_fab2(sch_1):page252_i7@mstr_discrete.cap(~
chips)',
 PATH='I7',
 DRAWING='@BASEBOARD_FAB2_LIB.BASEBOARD_FAB2(SCH_1):PAGE255',
 TOLERANCE='5%',
 SEC_TYPE='0402LF',
 MATERIAL='COG',
 BOM_COST='LBG_UART',
 PHYS_PAGE='252',
 XY='(-4900,3450)',
 ROT='0',
 VER='1',
 VALUE='12.0PF',
 PACK_TYPE='0402LF',
 PART_NUMBER='A36095-043',
 LOCATION='C25W72',
 ROOM='LBG',
 GROUP='AST2500',
 SEC='1',
 CDS_LIB='mstr_discrete',
 CDS_PART_NAME='CAP_0402LF-12.0PF,50V,5%,COG,AA',
 VOLTAGE='50V',
 PRIM_FILE='./archive_libs/mstr_discrete/cap/chips/chips.prt';

PART_NAME
 C25W73 'CAP_0402LF-12.0PF,50V,5%,COG,AA':
 GROUP='AST2500',
 ROOM='LBG';

SECTION_NUMBER 1
 '@BASEBOARD_FAB2_LIB.BASEBOARD_FAB2(SCH_1):PAGE255_I11@MSTR_DISCRETE.CAP(CHIPS)':
 C_PATH='@baseboard_fab2_lib.baseboard_fab2(sch_1):page255_i11@mstr_discrete.cap~
(chips)',
 P_PATH='@baseboard_fab2_lib.baseboard_fab2(sch_1):page252_i11@mstr_discrete.cap~
(chips)',
 PATH='I11',
 DRAWING='@BASEBOARD_FAB2_LIB.BASEBOARD_FAB2(SCH_1):PAGE255',
 TOLERANCE='5%',
 SEC_TYPE='0402LF',
 MATERIAL='COG',
 BOM_COST='LBG_UART',
 PHYS_PAGE='252',
 XY='(-4500,3450)',
 ROT='0',
 VER='1',
 VALUE='12.0PF',
 PACK_TYPE='0402LF',
 PART_NUMBER='A36095-043',
 LOCATION='C25W73',
 ROOM='LBG',
 GROUP='AST2500',
 SEC='1',
 CDS_LIB='mstr_discrete',
 CDS_PART_NAME='CAP_0402LF-12.0PF,50V,5%,COG,AA',
 VOLTAGE='50V',
 PRIM_FILE='./archive_libs/mstr_discrete/cap/chips/chips.prt';

PART_NAME
 C25W74 'CAP_0402LF-12.0PF,50V,5%,COG,AA':
 GROUP='AST2500',
 ROOM='LBG';

SECTION_NUMBER 1
 '@BASEBOARD_FAB2_LIB.BASEBOARD_FAB2(SCH_1):PAGE255_I12@MSTR_DISCRETE.CAP(CHIPS)':
 C_PATH='@baseboard_fab2_lib.baseboard_fab2(sch_1):page255_i12@mstr_discrete.cap~
(chips)',
 P_PATH='@baseboard_fab2_lib.baseboard_fab2(sch_1):page252_i12@mstr_discrete.cap~
(chips)',
 PATH='I12',
 DRAWING='@BASEBOARD_FAB2_LIB.BASEBOARD_FAB2(SCH_1):PAGE255',
 TOLERANCE='5%',
 SEC_TYPE='0402LF',
 MATERIAL='COG',
 BOM_COST='LBG_UART',
 PHYS_PAGE='252',
 XY='(-4100,3450)',
 ROT='0',
 VER='1',
 VALUE='12.0PF',
 PACK_TYPE='0402LF',
 PART_NUMBER='A36095-043',
 LOCATION='C25W74',
 ROOM='LBG',
 GROUP='AST2500',
 SEC='1',
 CDS_LIB='mstr_discrete',
 CDS_PART_NAME='CAP_0402LF-12.0PF,50V,5%,COG,AA',
 VOLTAGE='50V',
 PRIM_FILE='./archive_libs/mstr_discrete/cap/chips/chips.prt';

PART_NAME
 C25W75 'CAP_0402LF-12.0PF,50V,5%,COG,AA':
 GROUP='AST2500',
 ROOM='LBG';

SECTION_NUMBER 1
 '@BASEBOARD_FAB2_LIB.BASEBOARD_FAB2(SCH_1):PAGE255_I21@MSTR_DISCRETE.CAP(CHIPS)':
 C_PATH='@baseboard_fab2_lib.baseboard_fab2(sch_1):page255_i21@mstr_discrete.cap~
(chips)',
 P_PATH='@baseboard_fab2_lib.baseboard_fab2(sch_1):page252_i21@mstr_discrete.cap~
(chips)',
 PATH='I21',
 DRAWING='@BASEBOARD_FAB2_LIB.BASEBOARD_FAB2(SCH_1):PAGE255',
 TOLERANCE='5%',
 SEC_TYPE='0402LF',
 MATERIAL='COG',
 BOM_COST='LBG_UART',
 PHYS_PAGE='252',
 XY='(-3050,3450)',
 ROT='0',
 VER='1',
 VALUE='12.0PF',
 PACK_TYPE='0402LF',
 PART_NUMBER='A36095-043',
 LOCATION='C25W75',
 ROOM='LBG',
 GROUP='AST2500',
 SEC='1',
 CDS_LIB='mstr_discrete',
 CDS_PART_NAME='CAP_0402LF-12.0PF,50V,5%,COG,AA',
 VOLTAGE='50V',
 PRIM_FILE='./archive_libs/mstr_discrete/cap/chips/chips.prt';

PART_NAME
 C25W76 'CAP_0402LF-12.0PF,50V,5%,COG,AA':
 GROUP='AST2500',
 ROOM='LBG';

SECTION_NUMBER 1
 '@BASEBOARD_FAB2_LIB.BASEBOARD_FAB2(SCH_1):PAGE255_I18@MSTR_DISCRETE.CAP(CHIPS)':
 C_PATH='@baseboard_fab2_lib.baseboard_fab2(sch_1):page255_i18@mstr_discrete.cap~
(chips)',
 P_PATH='@baseboard_fab2_lib.baseboard_fab2(sch_1):page252_i18@mstr_discrete.cap~
(chips)',
 PATH='I18',
 DRAWING='@BASEBOARD_FAB2_LIB.BASEBOARD_FAB2(SCH_1):PAGE255',
 TOLERANCE='5%',
 SEC_TYPE='0402LF',
 MATERIAL='COG',
 BOM_COST='LBG_UART',
 PHYS_PAGE='252',
 XY='(-2700,3450)',
 ROT='0',
 VER='1',
 VALUE='12.0PF',
 PACK_TYPE='0402LF',
 PART_NUMBER='A36095-043',
 LOCATION='C25W76',
 ROOM='LBG',
 GROUP='AST2500',
 SEC='1',
 CDS_LIB='mstr_discrete',
 CDS_PART_NAME='CAP_0402LF-12.0PF,50V,5%,COG,AA',
 VOLTAGE='50V',
 PRIM_FILE='./archive_libs/mstr_discrete/cap/chips/chips.prt';

PART_NAME
 C25W77 'CAP_0402LF-12.0PF,50V,5%,COG,AA':
 GROUP='AST2500',
 ROOM='LBG';

SECTION_NUMBER 1
 '@BASEBOARD_FAB2_LIB.BASEBOARD_FAB2(SCH_1):PAGE255_I16@MSTR_DISCRETE.CAP(CHIPS)':
 C_PATH='@baseboard_fab2_lib.baseboard_fab2(sch_1):page255_i16@mstr_discrete.cap~
(chips)',
 P_PATH='@baseboard_fab2_lib.baseboard_fab2(sch_1):page252_i16@mstr_discrete.cap~
(chips)',
 PATH='I16',
 DRAWING='@BASEBOARD_FAB2_LIB.BASEBOARD_FAB2(SCH_1):PAGE255',
 TOLERANCE='5%',
 SEC_TYPE='0402LF',
 MATERIAL='COG',
 BOM_COST='LBG_UART',
 PHYS_PAGE='252',
 XY='(-2350,3450)',
 ROT='0',
 VER='1',
 VALUE='12.0PF',
 PACK_TYPE='0402LF',
 PART_NUMBER='A36095-043',
 LOCATION='C25W77',
 ROOM='LBG',
 GROUP='AST2500',
 SEC='1',
 CDS_LIB='mstr_discrete',
 CDS_PART_NAME='CAP_0402LF-12.0PF,50V,5%,COG,AA',
 VOLTAGE='50V',
 PRIM_FILE='./archive_libs/mstr_discrete/cap/chips/chips.prt';

PART_NAME
 C25W78 'CAP_0402LF-100.0PF,50V,5%,COG,A':
 GROUP='AST2500',
 ROOM='PVPP_KLM_VR',
 REUSE_ID='27';

SECTION_NUMBER 1
 '@BASEBOARD_FAB2_LIB.BASEBOARD_FAB2(SCH_1):PAGE255_I35@MSTR_DISCRETE.CAP(CHIPS)':
 C_PATH='@baseboard_fab2_lib.baseboard_fab2(sch_1):page255_i35@mstr_discrete.cap~
(chips)',
 P_PATH='@baseboard_fab2_lib.baseboard_fab2(sch_1):page252_i35@mstr_discrete.cap~
(chips)',
 PATH='I35',
 DRAWING='@BASEBOARD_FAB2_LIB.BASEBOARD_FAB2(SCH_1):PAGE255',
 TOLERANCE='5%',
 SEC_TYPE='0402LF',
 MATERIAL='COG',
 BOM_COST='PVPP_KLM_VR',
 PHYS_PAGE='252',
 REUSE_ID='27',
 XY='(-6550,4550)',
 ROT='3',
 VER='2',
 VALUE='100.0PF',
 PACK_TYPE='0402LF',
 PART_NUMBER='A36095-026',
 LOCATION='C25W78',
 ROOM='PVPP_KLM_VR',
 GROUP='AST2500',
 SEC='1',
 CDS_LIB='mstr_discrete',
 CDS_PART_NAME='CAP_0402LF-100.0PF,50V,5%,COG,A',
 VOLTAGE='50V',
 PRIM_FILE='./archive_libs/mstr_discrete/cap/chips/chips.prt';

PART_NAME
 C25W79 'CAP_0402LF-100.0PF,50V,5%,COG,A':
 GROUP='AST2500',
 ROOM='PVPP_KLM_VR',
 REUSE_ID='27';

SECTION_NUMBER 1
 '@BASEBOARD_FAB2_LIB.BASEBOARD_FAB2(SCH_1):PAGE255_I39@MSTR_DISCRETE.CAP(CHIPS)':
 C_PATH='@baseboard_fab2_lib.baseboard_fab2(sch_1):page255_i39@mstr_discrete.cap~
(chips)',
 P_PATH='@baseboard_fab2_lib.baseboard_fab2(sch_1):page252_i39@mstr_discrete.cap~
(chips)',
 PATH='I39',
 DRAWING='@BASEBOARD_FAB2_LIB.BASEBOARD_FAB2(SCH_1):PAGE255',
 TOLERANCE='5%',
 SEC_TYPE='0402LF',
 MATERIAL='COG',
 BOM_COST='PVPP_KLM_VR',
 PHYS_PAGE='252',
 REUSE_ID='27',
 XY='(-6550,3300)',
 ROT='3',
 VER='2',
 VALUE='100.0PF',
 PACK_TYPE='0402LF',
 PART_NUMBER='A36095-026',
 LOCATION='C25W79',
 ROOM='PVPP_KLM_VR',
 GROUP='AST2500',
 SEC='1',
 CDS_LIB='mstr_discrete',
 CDS_PART_NAME='CAP_0402LF-100.0PF,50V,5%,COG,A',
 VOLTAGE='50V',
 PRIM_FILE='./archive_libs/mstr_discrete/cap/chips/chips.prt';

PART_NAME
 C25W81 'CAP_0402LF-10.0PF,50V,5%,COG,AA':
 GROUP='AST2500',
 ROOM='BMC_VOLT_MONITOR';

SECTION_NUMBER 1
 '@BASEBOARD_FAB2_LIB.BASEBOARD_FAB2(SCH_1):PAGE255_I60@MSTR_DISCRETE.CAP(CHIPS)':
 C_PATH='@baseboard_fab2_lib.baseboard_fab2(sch_1):page255_i60@mstr_discrete.cap~
(chips)',
 P_PATH='@baseboard_fab2_lib.baseboard_fab2(sch_1):page252_i60@mstr_discrete.cap~
(chips)',
 PATH='I60',
 DRAWING='@BASEBOARD_FAB2_LIB.BASEBOARD_FAB2(SCH_1):PAGE255',
 TOLERANCE='5%',
 SEC_TYPE='0402LF',
 MATERIAL='COG',
 BOM_COST='SM_HM',
 PHYS_PAGE='252',
 XY='(-2750,4850)',
 ROT='0',
 VER='1',
 VALUE='10.0PF',
 PACK_TYPE='0402LF',
 PART_NUMBER='A36094-025',
 LOCATION='C25W81',
 ROOM='BMC_VOLT_MONITOR',
 GROUP='AST2500',
 SEC='1',
 CDS_LIB='mstr_discrete',
 CDS_PART_NAME='CAP_0402LF-10.0PF,50V,5%,COG,AA',
 VOLTAGE='50V',
 PRIM_FILE='./archive_libs/mstr_discrete/cap/chips/chips.prt';

PART_NAME
 C25W82 'CAP_0402LF-10.0PF,50V,5%,COG,AA':
 GROUP='AST2500',
 ROOM='BMC_VOLT_MONITOR';

SECTION_NUMBER 1
 '@BASEBOARD_FAB2_LIB.BASEBOARD_FAB2(SCH_1):PAGE255_I62@MSTR_DISCRETE.CAP(CHIPS)':
 C_PATH='@baseboard_fab2_lib.baseboard_fab2(sch_1):page255_i62@mstr_discrete.cap~
(chips)',
 P_PATH='@baseboard_fab2_lib.baseboard_fab2(sch_1):page252_i62@mstr_discrete.cap~
(chips)',
 PATH='I62',
 DRAWING='@BASEBOARD_FAB2_LIB.BASEBOARD_FAB2(SCH_1):PAGE255',
 TOLERANCE='5%',
 SEC_TYPE='0402LF',
 MATERIAL='COG',
 BOM_COST='SM_HM',
 PHYS_PAGE='252',
 XY='(-2750,4300)',
 ROT='0',
 VER='1',
 VALUE='10.0PF',
 PACK_TYPE='0402LF',
 PART_NUMBER='A36094-025',
 LOCATION='C25W82',
 ROOM='BMC_VOLT_MONITOR',
 GROUP='AST2500',
 SEC='1',
 CDS_LIB='mstr_discrete',
 CDS_PART_NAME='CAP_0402LF-10.0PF,50V,5%,COG,AA',
 VOLTAGE='50V',
 PRIM_FILE='./archive_libs/mstr_discrete/cap/chips/chips.prt';

PART_NAME
 C25W90 'CAP_A_0402V-0.1UF,16V,10%,X7R,A':
 GROUP='AST2500',
 ROOM='PROC_SIDEBAND';

SECTION_NUMBER 1
 '@BASEBOARD_FAB2_LIB.BASEBOARD_FAB2(SCH_1):PAGE255_I118@DEV_DISCRETE.CAP_A(CHIPS)':
 C_PATH='@baseboard_fab2_lib.baseboard_fab2(sch_1):page255_i118@dev_discrete.cap~
_a(chips)',
 P_PATH='@baseboard_fab2_lib.baseboard_fab2(sch_1):page252_i118@dev_discrete.cap~
_a(chips)',
 PATH='I118',
 DRAWING='@BASEBOARD_FAB2_LIB.BASEBOARD_FAB2(SCH_1):PAGE255',
 TOLERANCE='10%',
 SEC_TYPE='0402V',
 MATERIAL='X7R',
 BOM_COST='PROC_SIDEBAND',
 PHYS_PAGE='252',
 XY='(-3500,4650)',
 ROT='1',
 VER='1',
 VALUE='0.1UF',
 PACK_TYPE='0402V',
 PART_NUMBER='A36096-030',
 LOCATION='C25W90',
 ROOM='PROC_SIDEBAND',
 GROUP='AST2500',
 SEC='1',
 CDS_LIB='dev_discrete',
 CDS_PART_NAME='CAP_A_0402V-0.1UF,16V,10%,X7R,A',
 VOLTAGE='16V',
 PRIM_FILE='./archive_libs/discrete/cap_a/chips/chips.prt';

PART_NAME
 C25W91 'CAP_A_0402V-1.0UF,6.3V,10%,X6SA':
 ROOM='PROC_RSTS_PGOODS';

SECTION_NUMBER 1
 '@BASEBOARD_FAB2_LIB.BASEBOARD_FAB2(SCH_1):PAGE269_I26@DEV_DISCRETE.CAP_A(CHIPS)':
 C_PATH='@baseboard_fab2_lib.baseboard_fab2(sch_1):page269_i26@dev_discrete.cap_~
a(chips)',
 P_PATH='@baseboard_fab2_lib.baseboard_fab2(sch_1):page254_i26@dev_discrete.cap_~
a(chips)',
 PATH='I26',
 DRAWING='@BASEBOARD_FAB2_LIB.BASEBOARD_FAB2(SCH_1):PAGE269',
 TOLERANCE='10%',
 SEC_TYPE='0402V',
 MATERIAL='X6S',
 BOM_COST='PROC_SIDEBAND',
 PHYS_PAGE='254',
 XY='(-5800,6050)',
 ROT='0',
 VER='1',
 VALUE='1.0UF',
 PACK_TYPE='0402V',
 PART_NUMBER='D97712-004',
 LOCATION='C25W91',
 ROOM='PROC_RSTS_PGOODS',
 SEC='1',
 CDS_LIB='dev_discrete',
 CDS_PART_NAME='CAP_A_0402V-1.0UF,6.3V,10%,X6SA',
 VOLTAGE='6.3V',
 PRIM_FILE='./archive_libs/discrete/cap_a/chips/chips.prt';

PART_NAME
 C25W92 'CAP_0402-1.0UF,16V,10%,X6S,D97A':
 ROOM='PROC_SIDEBAND';

SECTION_NUMBER 1
 '@BASEBOARD_FAB2_LIB.BASEBOARD_FAB2(SCH_1):PAGE268_I23@MSTR_DISCRETE.CAP(CHIPS)':
 C_PATH='@baseboard_fab2_lib.baseboard_fab2(sch_1):page268_i23@mstr_discrete.cap~
(chips)',
 P_PATH='@baseboard_fab2_lib.baseboard_fab2(sch_1):page255_i23@mstr_discrete.cap~
(chips)',
 PATH='I23',
 DRAWING='@BASEBOARD_FAB2_LIB.BASEBOARD_FAB2(SCH_1):PAGE268',
 TOLERANCE='10%',
 SEC_TYPE='0402',
 MATERIAL='X6S',
 BOM_COST='PROC',
 PHYS_PAGE='255',
 XY='(-6550,5800)',
 ROT='0',
 VER='1',
 VALUE='1.0UF',
 PACK_TYPE='0402',
 PART_NUMBER='D97712-011',
 LOCATION='C25W92',
 ROOM='PROC_SIDEBAND',
 SEC='1',
 CDS_LIB='mstr_discrete',
 CDS_PART_NAME='CAP_0402-1.0UF,16V,10%,X6S,D97A',
 VOLTAGE='16V',
 PRIM_FILE='./archive_libs/mstr_discrete/cap/chips/chips.prt';

PART_NAME
 C25W93 'CAP_A_0402V-0.1UF,16V,10%,X7R,A':
 ROOM='PROC_SIDEBAND';

SECTION_NUMBER 1
 '@BASEBOARD_FAB2_LIB.BASEBOARD_FAB2(SCH_1):PAGE268_I27@DEV_DISCRETE.CAP_A(CHIPS)':
 C_PATH='@baseboard_fab2_lib.baseboard_fab2(sch_1):page268_i27@dev_discrete.cap_~
a(chips)',
 P_PATH='@baseboard_fab2_lib.baseboard_fab2(sch_1):page255_i27@dev_discrete.cap_~
a(chips)',
 PATH='I27',
 DRAWING='@BASEBOARD_FAB2_LIB.BASEBOARD_FAB2(SCH_1):PAGE268',
 TOLERANCE='10%',
 SEC_TYPE='0402V',
 MATERIAL='X7R',
 BOM_COST='PROC_SIDEBAND',
 PHYS_PAGE='255',
 XY='(-6050,5850)',
 ROT='0',
 VER='1',
 VALUE='0.1UF',
 PACK_TYPE='0402V',
 PART_NUMBER='A36096-030',
 LOCATION='C25W93',
 ROOM='PROC_SIDEBAND',
 SEC='1',
 CDS_LIB='dev_discrete',
 CDS_PART_NAME='CAP_A_0402V-0.1UF,16V,10%,X7R,A',
 VOLTAGE='16V',
 PRIM_FILE='./archive_libs/discrete/cap_a/chips/chips.prt';

PART_NAME
 C25W94 'CAP_0402-1.0UF,16V,10%,X6S,D97A':
 ROOM='DEBUG';

SECTION_NUMBER 1
 '@BASEBOARD_FAB2_LIB.BASEBOARD_FAB2(SCH_1):PAGE269_I32@MSTR_DISCRETE.CAP(CHIPS)':
 C_PATH='@baseboard_fab2_lib.baseboard_fab2(sch_1):page269_i32@mstr_discrete.cap~
(chips)',
 P_PATH='@baseboard_fab2_lib.baseboard_fab2(sch_1):page254_i32@mstr_discrete.cap~
(chips)',
 PATH='I32',
 DRAWING='@BASEBOARD_FAB2_LIB.BASEBOARD_FAB2(SCH_1):PAGE269',
 TOLERANCE='10%',
 SEC_TYPE='0402',
 MATERIAL='X6S',
 PHYS_PAGE='254',
 XY='(-3050,3000)',
 ROT='0',
 VER='1',
 VALUE='1.0UF',
 PACK_TYPE='0402',
 PART_NUMBER='D97712-011',
 LOCATION='C25W94',
 ROOM='DEBUG',
 SEC='1',
 CDS_LIB='mstr_discrete',
 CDS_PART_NAME='CAP_0402-1.0UF,16V,10%,X6S,D97A',
 VOLTAGE='16V',
 PRIM_FILE='./archive_libs/mstr_discrete/cap/chips/chips.prt';

PART_NAME
 C25W95 'CAP_A_0402V-0.1UF,16V,10%,X7R,A':
 ROOM='UART_MUX';

SECTION_NUMBER 1
 '@BASEBOARD_FAB2_LIB.BASEBOARD_FAB2(SCH_1):PAGE269_I56@DEV_DISCRETE.CAP_A(CHIPS)':
 C_PATH='@baseboard_fab2_lib.baseboard_fab2(sch_1):page269_i56@dev_discrete.cap_~
a(chips)',
 P_PATH='@baseboard_fab2_lib.baseboard_fab2(sch_1):page254_i56@dev_discrete.cap_~
a(chips)',
 PATH='I56',
 DRAWING='@BASEBOARD_FAB2_LIB.BASEBOARD_FAB2(SCH_1):PAGE269',
 TOLERANCE='10%',
 SEC_TYPE='0402V',
 MATERIAL='X7R',
 BOM_COST='DEBUG',
 PHYS_PAGE='254',
 XY='(-8700,3850)',
 ROT='0',
 VER='1',
 VALUE='0.1UF',
 PACK_TYPE='0402V',
 PART_NUMBER='A36096-030',
 LOCATION='C25W95',
 ROOM='UART_MUX',
 SEC='1',
 CDS_LIB='dev_discrete',
 CDS_PART_NAME='CAP_A_0402V-0.1UF,16V,10%,X7R,A',
 VOLTAGE='16V',
 PRIM_FILE='./archive_libs/discrete/cap_a/chips/chips.prt';

PART_NAME
 C25W96 'CAP_A_0402V-0.1UF,16V,10%,X7R,A':
 ROOM='CPU_FANS';

SECTION_NUMBER 1
 '@BASEBOARD_FAB2_LIB.BASEBOARD_FAB2(SCH_1):PAGE268_I9@DEV_DISCRETE.CAP_A(CHIPS)':
 C_PATH='@baseboard_fab2_lib.baseboard_fab2(sch_1):page268_i9@dev_discrete.cap_a~
(chips)',
 P_PATH='@baseboard_fab2_lib.baseboard_fab2(sch_1):page255_i9@dev_discrete.cap_a~
(chips)',
 PATH='I9',
 DRAWING='@BASEBOARD_FAB2_LIB.BASEBOARD_FAB2(SCH_1):PAGE268',
 TOLERANCE='10%',
 SEC_TYPE='0402V',
 MATERIAL='X7R',
 BOM_COST='SM_THERM',
 PHYS_PAGE='255',
 XY='(-6700,4150)',
 ROT='0',
 VER='1',
 VALUE='0.1UF',
 PACK_TYPE='0402V',
 PART_NUMBER='A36096-030',
 LOCATION='C25W96',
 ROOM='CPU_FANS',
 SEC='1',
 CDS_LIB='dev_discrete',
 CDS_PART_NAME='CAP_A_0402V-0.1UF,16V,10%,X7R,A',
 VOLTAGE='16V',
 PRIM_FILE='./archive_libs/discrete/cap_a/chips/chips.prt';

PART_NAME
 C25W97 'CAP_A_0402V-0.1UF,16V,10%,X7R,A':
 ROOM='CPU_FANS';

SECTION_NUMBER 1
 '@BASEBOARD_FAB2_LIB.BASEBOARD_FAB2(SCH_1):PAGE268_I4@DEV_DISCRETE.CAP_A(CHIPS)':
 C_PATH='@baseboard_fab2_lib.baseboard_fab2(sch_1):page268_i4@dev_discrete.cap_a~
(chips)',
 P_PATH='@baseboard_fab2_lib.baseboard_fab2(sch_1):page255_i4@dev_discrete.cap_a~
(chips)',
 PATH='I4',
 DRAWING='@BASEBOARD_FAB2_LIB.BASEBOARD_FAB2(SCH_1):PAGE268',
 TOLERANCE='10%',
 SEC_TYPE='0402V',
 MATERIAL='X7R',
 BOM_COST='SM_THERM',
 PHYS_PAGE='255',
 XY='(-6700,3350)',
 ROT='0',
 VER='1',
 VALUE='0.1UF',
 PACK_TYPE='0402V',
 PART_NUMBER='A36096-030',
 LOCATION='C25W97',
 ROOM='CPU_FANS',
 SEC='1',
 CDS_LIB='dev_discrete',
 CDS_PART_NAME='CAP_A_0402V-0.1UF,16V,10%,X7R,A',
 VOLTAGE='16V',
 PRIM_FILE='./archive_libs/discrete/cap_a/chips/chips.prt';

PART_NAME
 C25W98 'CAP_0402-1.0UF,16V,10%,X6S,D97A':
 ROOM='DEBUG';

SECTION_NUMBER 1
 '@BASEBOARD_FAB2_LIB.BASEBOARD_FAB2(SCH_1):PAGE268_I40@MSTR_DISCRETE.CAP(CHIPS)':
 C_PATH='@baseboard_fab2_lib.baseboard_fab2(sch_1):page268_i40@mstr_discrete.cap~
(chips)',
 P_PATH='@baseboard_fab2_lib.baseboard_fab2(sch_1):page255_i40@mstr_discrete.cap~
(chips)',
 PATH='I40',
 DRAWING='@BASEBOARD_FAB2_LIB.BASEBOARD_FAB2(SCH_1):PAGE268',
 TOLERANCE='10%',
 SEC_TYPE='0402',
 MATERIAL='X6S',
 PHYS_PAGE='255',
 XY='(-2250,4400)',
 ROT='0',
 VER='1',
 VALUE='1.0UF',
 PACK_TYPE='0402',
 PART_NUMBER='D97712-011',
 LOCATION='C25W98',
 ROOM='DEBUG',
 SEC='1',
 CDS_LIB='mstr_discrete',
 CDS_PART_NAME='CAP_0402-1.0UF,16V,10%,X6S,D97A',
 VOLTAGE='16V',
 PRIM_FILE='./archive_libs/mstr_discrete/cap/chips/chips.prt';

PART_NAME
 C25W99 'CAP_A_0402V-0.1UF,16V,10%,X7R,A':
 ROOM='PROC_SIDEBAND';

SECTION_NUMBER 1
 '@BASEBOARD_FAB2_LIB.BASEBOARD_FAB2(SCH_1):PAGE269_I62@DEV_DISCRETE.CAP_A(CHIPS)':
 C_PATH='@baseboard_fab2_lib.baseboard_fab2(sch_1):page269_i62@dev_discrete.cap_~
a(chips)',
 P_PATH='@baseboard_fab2_lib.baseboard_fab2(sch_1):page254_i62@dev_discrete.cap_~
a(chips)',
 PATH='I62',
 DRAWING='@BASEBOARD_FAB2_LIB.BASEBOARD_FAB2(SCH_1):PAGE269',
 TOLERANCE='10%',
 SEC_TYPE='0402V',
 MATERIAL='X7R',
 BOM_COST='PROC_SIDEBAND',
 PHYS_PAGE='254',
 XY='(-5350,4450)',
 ROT='0',
 VER='1',
 VALUE='0.1UF',
 PACK_TYPE='0402V',
 PART_NUMBER='A36096-030',
 LOCATION='C25W99',
 ROOM='PROC_SIDEBAND',
 SEC='1',
 CDS_LIB='dev_discrete',
 CDS_PART_NAME='CAP_A_0402V-0.1UF,16V,10%,X7R,A',
 VOLTAGE='16V',
 PRIM_FILE='./archive_libs/discrete/cap_a/chips/chips.prt';

PART_NAME
 C25W100 'CAP_A_0402V-0.1UF,16V,10%,X7R,A':
 ROOM='PROC_SIDEBAND';

SECTION_NUMBER 1
 '@BASEBOARD_FAB2_LIB.BASEBOARD_FAB2(SCH_1):PAGE268_I60@DEV_DISCRETE.CAP_A(CHIPS)':
 C_PATH='@baseboard_fab2_lib.baseboard_fab2(sch_1):page268_i60@dev_discrete.cap_~
a(chips)',
 P_PATH='@baseboard_fab2_lib.baseboard_fab2(sch_1):page255_i60@dev_discrete.cap_~
a(chips)',
 PATH='I60',
 DRAWING='@BASEBOARD_FAB2_LIB.BASEBOARD_FAB2(SCH_1):PAGE268',
 TOLERANCE='10%',
 SEC_TYPE='0402V',
 MATERIAL='X7R',
 BOM_COST='PROC_SIDEBAND',
 PHYS_PAGE='255',
 XY='(-2700,3800)',
 ROT='0',
 VER='1',
 VALUE='0.1UF',
 PACK_TYPE='0402V',
 PART_NUMBER='A36096-030',
 LOCATION='C25W100',
 ROOM='PROC_SIDEBAND',
 SEC='1',
 CDS_LIB='dev_discrete',
 CDS_PART_NAME='CAP_A_0402V-0.1UF,16V,10%,X7R,A',
 VOLTAGE='16V',
 PRIM_FILE='./archive_libs/discrete/cap_a/chips/chips.prt';

PART_NAME
 C25W101 'CAP_A_0402V-0.1UF,16V,10%,X7R,A':
 ROOM='UART_MUX';

SECTION_NUMBER 1
 '@BASEBOARD_FAB2_LIB.BASEBOARD_FAB2(SCH_1):PAGE269_I79@DEV_DISCRETE.CAP_A(CHIPS)':
 C_PATH='@baseboard_fab2_lib.baseboard_fab2(sch_1):page269_i79@dev_discrete.cap_~
a(chips)',
 P_PATH='@baseboard_fab2_lib.baseboard_fab2(sch_1):page254_i79@dev_discrete.cap_~
a(chips)',
 PATH='I79',
 DRAWING='@BASEBOARD_FAB2_LIB.BASEBOARD_FAB2(SCH_1):PAGE269',
 TOLERANCE='10%',
 SEC_TYPE='0402V',
 MATERIAL='X7R',
 BOM_COST='DEBUG',
 PHYS_PAGE='254',
 XY='(-7050,4700)',
 ROT='0',
 VER='1',
 VALUE='0.1UF',
 PACK_TYPE='0402V',
 PART_NUMBER='A36096-030',
 LOCATION='C25W101',
 ROOM='UART_MUX',
 SEC='1',
 CDS_LIB='dev_discrete',
 CDS_PART_NAME='CAP_A_0402V-0.1UF,16V,10%,X7R,A',
 VOLTAGE='16V',
 PRIM_FILE='./archive_libs/discrete/cap_a/chips/chips.prt';

PART_NAME
 C30W1 'CAP_A_0402V-0.1UF,16V,10%,X7R,A':
 ROOM='PROC_SIDEBAND';

SECTION_NUMBER 1
 '@BASEBOARD_FAB2_LIB.BASEBOARD_FAB2(SCH_1):PAGE253_I20@DEV_DISCRETE.CAP_A(CHIPS)':
 C_PATH='@baseboard_fab2_lib.baseboard_fab2(sch_1):page253_i20@dev_discrete.cap_~
a(chips)',
 P_PATH='@baseboard_fab2_lib.baseboard_fab2(sch_1):page253_i20@dev_discrete.cap_~
a(chips)',
 PATH='I20',
 DRAWING='@BASEBOARD_FAB2_LIB.BASEBOARD_FAB2(SCH_1):PAGE253',
 TOLERANCE='10%',
 SEC_TYPE='0402V',
 MATERIAL='X7R',
 BOM_COST='PROC_SIDEBAND',
 PHYS_PAGE='253',
 XY='(-6275,2050)',
 ROT='1',
 VER='1',
 VALUE='0.1UF',
 PACK_TYPE='0402V',
 PART_NUMBER='A36096-030',
 LOCATION='C30W1',
 ROOM='PROC_SIDEBAND',
 SEC='1',
 CDS_LIB='dev_discrete',
 CDS_PART_NAME='CAP_A_0402V-0.1UF,16V,10%,X7R,A',
 VOLTAGE='16V',
 PRIM_FILE='./archive_libs/discrete/cap_a/chips/chips.prt';

PART_NAME
 C30W2 'CAP_A_0402V-0.1UF,16V,10%,X7R,A':
 ROOM='PROC_SIDEBAND';

SECTION_NUMBER 1
 '@BASEBOARD_FAB2_LIB.BASEBOARD_FAB2(SCH_1):PAGE253_I19@DEV_DISCRETE.CAP_A(CHIPS)':
 C_PATH='@baseboard_fab2_lib.baseboard_fab2(sch_1):page253_i19@dev_discrete.cap_~
a(chips)',
 P_PATH='@baseboard_fab2_lib.baseboard_fab2(sch_1):page253_i19@dev_discrete.cap_~
a(chips)',
 PATH='I19',
 DRAWING='@BASEBOARD_FAB2_LIB.BASEBOARD_FAB2(SCH_1):PAGE253',
 TOLERANCE='10%',
 SEC_TYPE='0402V',
 MATERIAL='X7R',
 BOM_COST='PROC_SIDEBAND',
 PHYS_PAGE='253',
 XY='(-6275,2250)',
 ROT='1',
 VER='1',
 VALUE='0.1UF',
 PACK_TYPE='0402V',
 PART_NUMBER='A36096-030',
 LOCATION='C30W2',
 ROOM='PROC_SIDEBAND',
 SEC='1',
 CDS_LIB='dev_discrete',
 CDS_PART_NAME='CAP_A_0402V-0.1UF,16V,10%,X7R,A',
 VOLTAGE='16V',
 PRIM_FILE='./archive_libs/discrete/cap_a/chips/chips.prt';

PART_NAME
 C30W3 'SC22U16V5MX-4-GP_SMD-BCG5-SC22A':
 GROUP='NO_KR';

SECTION_NUMBER 1
 '@BASEBOARD_FAB2_LIB.BASEBOARD_FAB2(SCH_1):PAGE253_I35@W_HDL.SC22U16V5MX-4-GP(CHIPS)':
 C_PATH='@baseboard_fab2_lib.baseboard_fab2(sch_1):page253_i35@w_hdl.\sc22u16v5m~
x-4-gp\(chips)',
 P_PATH='@baseboard_fab2_lib.baseboard_fab2(sch_1):page253_i35@w_hdl.\sc22u16v5m~
x-4-gp\(chips)',
 PATH='I35',
 DRAWING='@BASEBOARD_FAB2_LIB.BASEBOARD_FAB2(SCH_1):PAGE253',
 TYPE='X6S',
 PACK_SIZE='0805',
 RATED='16V',
 ATTRIBUTE='22UF',
 TOLERANCE='20%',
 SEC_TYPE='SMD-BCG5',
 PHYS_PAGE='253',
 XY='(-4550,4375)',
 ROT='0',
 VER='1',
 VALUE='SC22U16V5MX-4-GP',
 PACK_TYPE='SMD-BCG5',
 PART_NUMBER='078.22611.0811',
 LOCATION='C30W3',
 GROUP='NO_KR',
 SEC='1',
 CDS_LIB='w_hdl',
 CDS_PART_NAME='SC22U16V5MX-4-GP_SMD-BCG5-SC22A',
 PRIM_FILE='C:/<user>/w_hdl/sc22u16v5mx#2d4#2dgp/chips/chips.prt';

PART_NAME
 C30W4 'SC22U16V5MX-4-GP_SMD-BCG5-SC22A':
 GROUP='NO_KR';

SECTION_NUMBER 1
 '@BASEBOARD_FAB2_LIB.BASEBOARD_FAB2(SCH_1):PAGE253_I36@W_HDL.SC22U16V5MX-4-GP(CHIPS)':
 C_PATH='@baseboard_fab2_lib.baseboard_fab2(sch_1):page253_i36@w_hdl.\sc22u16v5m~
x-4-gp\(chips)',
 P_PATH='@baseboard_fab2_lib.baseboard_fab2(sch_1):page253_i36@w_hdl.\sc22u16v5m~
x-4-gp\(chips)',
 PATH='I36',
 DRAWING='@BASEBOARD_FAB2_LIB.BASEBOARD_FAB2(SCH_1):PAGE253',
 TYPE='X6S',
 PACK_SIZE='0805',
 RATED='16V',
 ATTRIBUTE='22UF',
 TOLERANCE='20%',
 SEC_TYPE='SMD-BCG5',
 PHYS_PAGE='253',
 XY='(-4250,4375)',
 ROT='0',
 VER='1',
 VALUE='SC22U16V5MX-4-GP',
 PACK_TYPE='SMD-BCG5',
 PART_NUMBER='078.22611.0811',
 LOCATION='C30W4',
 GROUP='NO_KR',
 SEC='1',
 CDS_LIB='w_hdl',
 CDS_PART_NAME='SC22U16V5MX-4-GP_SMD-BCG5-SC22A',
 PRIM_FILE='C:/<user>/w_hdl/sc22u16v5mx#2d4#2dgp/chips/chips.prt';

PART_NAME
 C30W5 'SC22U16V5MX-4-GP_SMD-BCG5-SC22A':
 GROUP='NO_KR';

SECTION_NUMBER 1
 '@BASEBOARD_FAB2_LIB.BASEBOARD_FAB2(SCH_1):PAGE253_I38@W_HDL.SC22U16V5MX-4-GP(CHIPS)':
 C_PATH='@baseboard_fab2_lib.baseboard_fab2(sch_1):page253_i38@w_hdl.\sc22u16v5m~
x-4-gp\(chips)',
 P_PATH='@baseboard_fab2_lib.baseboard_fab2(sch_1):page253_i38@w_hdl.\sc22u16v5m~
x-4-gp\(chips)',
 PATH='I38',
 DRAWING='@BASEBOARD_FAB2_LIB.BASEBOARD_FAB2(SCH_1):PAGE253',
 TYPE='X6S',
 PACK_SIZE='0805',
 RATED='16V',
 ATTRIBUTE='22UF',
 TOLERANCE='20%',
 SEC_TYPE='SMD-BCG5',
 PHYS_PAGE='253',
 XY='(-3950,4375)',
 ROT='0',
 VER='1',
 VALUE='SC22U16V5MX-4-GP',
 PACK_TYPE='SMD-BCG5',
 PART_NUMBER='078.22611.0811',
 LOCATION='C30W5',
 GROUP='NO_KR',
 SEC='1',
 CDS_LIB='w_hdl',
 CDS_PART_NAME='SC22U16V5MX-4-GP_SMD-BCG5-SC22A',
 PRIM_FILE='C:/<user>/w_hdl/sc22u16v5mx#2d4#2dgp/chips/chips.prt';

PART_NAME
 C30W6 'SC22U16V5MX-4-GP_SMD-BCG5-SC22A':
 GROUP='NO_KR';

SECTION_NUMBER 1
 '@BASEBOARD_FAB2_LIB.BASEBOARD_FAB2(SCH_1):PAGE253_I37@W_HDL.SC22U16V5MX-4-GP(CHIPS)':
 C_PATH='@baseboard_fab2_lib.baseboard_fab2(sch_1):page253_i37@w_hdl.\sc22u16v5m~
x-4-gp\(chips)',
 P_PATH='@baseboard_fab2_lib.baseboard_fab2(sch_1):page253_i37@w_hdl.\sc22u16v5m~
x-4-gp\(chips)',
 PATH='I37',
 DRAWING='@BASEBOARD_FAB2_LIB.BASEBOARD_FAB2(SCH_1):PAGE253',
 TYPE='X6S',
 PACK_SIZE='0805',
 RATED='16V',
 ATTRIBUTE='22UF',
 TOLERANCE='20%',
 SEC_TYPE='SMD-BCG5',
 PHYS_PAGE='253',
 XY='(-3650,4375)',
 ROT='0',
 VER='1',
 VALUE='SC22U16V5MX-4-GP',
 PACK_TYPE='SMD-BCG5',
 PART_NUMBER='078.22611.0811',
 LOCATION='C30W6',
 GROUP='NO_KR',
 SEC='1',
 CDS_LIB='w_hdl',
 CDS_PART_NAME='SC22U16V5MX-4-GP_SMD-BCG5-SC22A',
 PRIM_FILE='C:/<user>/w_hdl/sc22u16v5mx#2d4#2dgp/chips/chips.prt';

PART_NAME
 C30W7 'SC22U16V5MX-4-GP_SMD-BCG5-SC22A':
 GROUP='NO_KR';

SECTION_NUMBER 1
 '@BASEBOARD_FAB2_LIB.BASEBOARD_FAB2(SCH_1):PAGE253_I42@W_HDL.SC22U16V5MX-4-GP(CHIPS)':
 C_PATH='@baseboard_fab2_lib.baseboard_fab2(sch_1):page253_i42@w_hdl.\sc22u16v5m~
x-4-gp\(chips)',
 P_PATH='@baseboard_fab2_lib.baseboard_fab2(sch_1):page253_i42@w_hdl.\sc22u16v5m~
x-4-gp\(chips)',
 PATH='I42',
 DRAWING='@BASEBOARD_FAB2_LIB.BASEBOARD_FAB2(SCH_1):PAGE253',
 TYPE='X6S',
 PACK_SIZE='0805',
 RATED='16V',
 ATTRIBUTE='22UF',
 TOLERANCE='20%',
 SEC_TYPE='SMD-BCG5',
 PHYS_PAGE='253',
 XY='(-3350,4375)',
 ROT='0',
 VER='1',
 VALUE='SC22U16V5MX-4-GP',
 PACK_TYPE='SMD-BCG5',
 PART_NUMBER='078.22611.0811',
 LOCATION='C30W7',
 GROUP='NO_KR',
 SEC='1',
 CDS_LIB='w_hdl',
 CDS_PART_NAME='SC22U16V5MX-4-GP_SMD-BCG5-SC22A',
 PRIM_FILE='C:/<user>/w_hdl/sc22u16v5mx#2d4#2dgp/chips/chips.prt';

PART_NAME
 C30W8 'SC22U16V5MX-4-GP_SMD-BCG5-SC22A':
 GROUP='NO_KR';

SECTION_NUMBER 1
 '@BASEBOARD_FAB2_LIB.BASEBOARD_FAB2(SCH_1):PAGE253_I41@W_HDL.SC22U16V5MX-4-GP(CHIPS)':
 C_PATH='@baseboard_fab2_lib.baseboard_fab2(sch_1):page253_i41@w_hdl.\sc22u16v5m~
x-4-gp\(chips)',
 P_PATH='@baseboard_fab2_lib.baseboard_fab2(sch_1):page253_i41@w_hdl.\sc22u16v5m~
x-4-gp\(chips)',
 PATH='I41',
 DRAWING='@BASEBOARD_FAB2_LIB.BASEBOARD_FAB2(SCH_1):PAGE253',
 TYPE='X6S',
 PACK_SIZE='0805',
 RATED='16V',
 ATTRIBUTE='22UF',
 TOLERANCE='20%',
 SEC_TYPE='SMD-BCG5',
 PHYS_PAGE='253',
 XY='(-3050,4375)',
 ROT='0',
 VER='1',
 VALUE='SC22U16V5MX-4-GP',
 PACK_TYPE='SMD-BCG5',
 PART_NUMBER='078.22611.0811',
 LOCATION='C30W8',
 GROUP='NO_KR',
 SEC='1',
 CDS_LIB='w_hdl',
 CDS_PART_NAME='SC22U16V5MX-4-GP_SMD-BCG5-SC22A',
 PRIM_FILE='C:/<user>/w_hdl/sc22u16v5mx#2d4#2dgp/chips/chips.prt';

PART_NAME
 C30W9 'SC22U16V5MX-4-GP_SMD-BCG5-SC22A':
 GROUP='NO_KR';

SECTION_NUMBER 1
 '@BASEBOARD_FAB2_LIB.BASEBOARD_FAB2(SCH_1):PAGE253_I40@W_HDL.SC22U16V5MX-4-GP(CHIPS)':
 C_PATH='@baseboard_fab2_lib.baseboard_fab2(sch_1):page253_i40@w_hdl.\sc22u16v5m~
x-4-gp\(chips)',
 P_PATH='@baseboard_fab2_lib.baseboard_fab2(sch_1):page253_i40@w_hdl.\sc22u16v5m~
x-4-gp\(chips)',
 PATH='I40',
 DRAWING='@BASEBOARD_FAB2_LIB.BASEBOARD_FAB2(SCH_1):PAGE253',
 TYPE='X6S',
 PACK_SIZE='0805',
 RATED='16V',
 ATTRIBUTE='22UF',
 TOLERANCE='20%',
 SEC_TYPE='SMD-BCG5',
 PHYS_PAGE='253',
 XY='(-2750,4375)',
 ROT='0',
 VER='1',
 VALUE='SC22U16V5MX-4-GP',
 PACK_TYPE='SMD-BCG5',
 PART_NUMBER='078.22611.0811',
 LOCATION='C30W9',
 GROUP='NO_KR',
 SEC='1',
 CDS_LIB='w_hdl',
 CDS_PART_NAME='SC22U16V5MX-4-GP_SMD-BCG5-SC22A',
 PRIM_FILE='C:/<user>/w_hdl/sc22u16v5mx#2d4#2dgp/chips/chips.prt';

PART_NAME
 C32W1 'CAP_A_0402V-0.1UF,16V,10%,X7R,A':
 ROOM='SMB_PE_HP_CPU1';

SECTION_NUMBER 1
 '@BASEBOARD_FAB2_LIB.BASEBOARD_FAB2(SCH_1):PAGE185_I188@DEV_DISCRETE.CAP_A(CHIPS)':
 C_PATH='@baseboard_fab2_lib.baseboard_fab2(sch_1):page185_i188@dev_discrete.cap~
_a(chips)',
 P_PATH='@baseboard_fab2_lib.baseboard_fab2(sch_1):page185_i188@dev_discrete.cap~
_a(chips)',
 PATH='I188',
 DRAWING='@BASEBOARD_FAB2_LIB.BASEBOARD_FAB2(SCH_1):PAGE185',
 TOLERANCE='10%',
 SEC_TYPE='0402V',
 MATERIAL='X7R',
 PHYS_PAGE='185',
 XY='(-2450,3200)',
 ROT='0',
 VER='1',
 VALUE='0.1UF',
 PACK_TYPE='0402V',
 PART_NUMBER='A36096-030',
 LOCATION='C32W1',
 ROOM='SMB_PE_HP_CPU1',
 SEC='1',
 CDS_LIB='dev_discrete',
 CDS_PART_NAME='CAP_A_0402V-0.1UF,16V,10%,X7R,A',
 VOLTAGE='16V',
 PRIM_FILE='./archive_libs/discrete/cap_a/chips/chips.prt';

PART_NAME
 C32W2 'CAP_A_0402V-0.1UF,16V,10%,X7R,A':
 ROOM='SMB_PE_HP_CPU1';

SECTION_NUMBER 1
 '@BASEBOARD_FAB2_LIB.BASEBOARD_FAB2(SCH_1):PAGE185_I193@DEV_DISCRETE.CAP_A(CHIPS)':
 C_PATH='@baseboard_fab2_lib.baseboard_fab2(sch_1):page185_i193@dev_discrete.cap~
_a(chips)',
 P_PATH='@baseboard_fab2_lib.baseboard_fab2(sch_1):page185_i193@dev_discrete.cap~
_a(chips)',
 PATH='I193',
 DRAWING='@BASEBOARD_FAB2_LIB.BASEBOARD_FAB2(SCH_1):PAGE185',
 TOLERANCE='10%',
 SEC_TYPE='0402V',
 MATERIAL='X7R',
 PHYS_PAGE='185',
 XY='(-1150,3200)',
 ROT='0',
 VER='1',
 VALUE='0.1UF',
 PACK_TYPE='0402V',
 PART_NUMBER='A36096-030',
 LOCATION='C32W2',
 ROOM='SMB_PE_HP_CPU1',
 SEC='1',
 CDS_LIB='dev_discrete',
 CDS_PART_NAME='CAP_A_0402V-0.1UF,16V,10%,X7R,A',
 VOLTAGE='16V',
 PRIM_FILE='./archive_libs/discrete/cap_a/chips/chips.prt';

PART_NAME
 C32W3 'CAP_A_0402V-0.1UF,16V,10%,X7R,A':
 ROOM='SMB_PE_HP_CPU1';

SECTION_NUMBER 1
 '@BASEBOARD_FAB2_LIB.BASEBOARD_FAB2(SCH_1):PAGE185_I190@DEV_DISCRETE.CAP_A(CHIPS)':
 C_PATH='@baseboard_fab2_lib.baseboard_fab2(sch_1):page185_i190@dev_discrete.cap~
_a(chips)',
 P_PATH='@baseboard_fab2_lib.baseboard_fab2(sch_1):page185_i190@dev_discrete.cap~
_a(chips)',
 PATH='I190',
 DRAWING='@BASEBOARD_FAB2_LIB.BASEBOARD_FAB2(SCH_1):PAGE185',
 TOLERANCE='10%',
 SEC_TYPE='0402V',
 MATERIAL='X7R',
 PHYS_PAGE='185',
 XY='(-2450,3975)',
 ROT='0',
 VER='1',
 VALUE='0.1UF',
 PACK_TYPE='0402V',
 PART_NUMBER='A36096-030',
 LOCATION='C32W3',
 ROOM='SMB_PE_HP_CPU1',
 SEC='1',
 CDS_LIB='dev_discrete',
 CDS_PART_NAME='CAP_A_0402V-0.1UF,16V,10%,X7R,A',
 VOLTAGE='16V',
 PRIM_FILE='./archive_libs/discrete/cap_a/chips/chips.prt';

PART_NAME
 C32W4 'CAP_A_0402V-0.1UF,16V,10%,X7R,A':
 ROOM='SMB_PE_HP_CPU1';

SECTION_NUMBER 1
 '@BASEBOARD_FAB2_LIB.BASEBOARD_FAB2(SCH_1):PAGE185_I196@DEV_DISCRETE.CAP_A(CHIPS)':
 C_PATH='@baseboard_fab2_lib.baseboard_fab2(sch_1):page185_i196@dev_discrete.cap~
_a(chips)',
 P_PATH='@baseboard_fab2_lib.baseboard_fab2(sch_1):page185_i196@dev_discrete.cap~
_a(chips)',
 PATH='I196',
 DRAWING='@BASEBOARD_FAB2_LIB.BASEBOARD_FAB2(SCH_1):PAGE185',
 TOLERANCE='10%',
 SEC_TYPE='0402V',
 MATERIAL='X7R',
 PHYS_PAGE='185',
 XY='(-1200,4000)',
 ROT='0',
 VER='1',
 VALUE='0.1UF',
 PACK_TYPE='0402V',
 PART_NUMBER='A36096-030',
 LOCATION='C32W4',
 ROOM='SMB_PE_HP_CPU1',
 SEC='1',
 CDS_LIB='dev_discrete',
 CDS_PART_NAME='CAP_A_0402V-0.1UF,16V,10%,X7R,A',
 VOLTAGE='16V',
 PRIM_FILE='./archive_libs/discrete/cap_a/chips/chips.prt';

PART_NAME
 C32W5 'CAP_0402-1.0UF,16V,10%,X6S,D97A':
 ROOM='PROC_SIDEBAND';

SECTION_NUMBER 1
 '@BASEBOARD_FAB2_LIB.BASEBOARD_FAB2(SCH_1):PAGE185_I217@MSTR_DISCRETE.CAP(CHIPS)':
 C_PATH='@baseboard_fab2_lib.baseboard_fab2(sch_1):page185_i217@mstr_discrete.ca~
p(chips)',
 P_PATH='@baseboard_fab2_lib.baseboard_fab2(sch_1):page185_i217@mstr_discrete.ca~
p(chips)',
 PATH='I217',
 DRAWING='@BASEBOARD_FAB2_LIB.BASEBOARD_FAB2(SCH_1):PAGE185',
 POP='NOPOP',
 TOLERANCE='10%',
 SEC_TYPE='0402',
 MATERIAL='X6S',
 BOM_COST='PROC',
 PHYS_PAGE='185',
 XY='(-7300,900)',
 ROT='0',
 VER='1',
 VALUE='1.0UF',
 PACK_TYPE='0402',
 PART_NUMBER='D97712-011',
 LOCATION='C32W5',
 ROOM='PROC_SIDEBAND',
 SEC='1',
 CDS_LIB='mstr_discrete',
 CDS_PART_NAME='CAP_0402-1.0UF,16V,10%,X6S,D97A',
 VOLTAGE='16V',
 PRIM_FILE='./archive_libs/mstr_discrete/cap/chips/chips.prt';

PART_NAME
 C826 'CAP_0402-0.22UF,16V,10%,X7R,A3A':
 GROUP='PCIE_RISER',
 ROOM='OCP_STEERING';

SECTION_NUMBER 1
 '@BASEBOARD_FAB2_LIB.BASEBOARD_FAB2(SCH_1):PAGE244_I24@MSTR_DISCRETE.CAP(CHIPS)':
 C_PATH='@baseboard_fab2_lib.baseboard_fab2(sch_1):page244_i24@mstr_discrete.cap~
(chips)',
 P_PATH='@baseboard_fab2_lib.baseboard_fab2(sch_1):page244_i24@mstr_discrete.cap~
(chips)',
 PATH='I24',
 DRAWING='@BASEBOARD_FAB2_LIB.BASEBOARD_FAB2(SCH_1):PAGE244',
 TOLERANCE='10%',
 SEC_TYPE='0402',
 MATERIAL='X7R',
 PHYS_PAGE='244',
 XY='(-5825,3325)',
 ROT='2',
 VER='1',
 VALUE='0.22UF',
 PACK_TYPE='0402',
 PART_NUMBER='A36096-155',
 ROOM='OCP_STEERING',
 GROUP='PCIE_RISER',
 SEC='1',
 CDS_LIB='mstr_discrete',
 CDS_PART_NAME='CAP_0402-0.22UF,16V,10%,X7R,A3A',
 VOLTAGE='16V',
 PRIM_FILE='./archive_libs/mstr_discrete/cap/chips/chips.prt';

PART_NAME
 C827 'CAP_0402-0.22UF,16V,10%,X7R,A3A':
 GROUP='PCIE_RISER',
 ROOM='OCP_STEERING';

SECTION_NUMBER 1
 '@BASEBOARD_FAB2_LIB.BASEBOARD_FAB2(SCH_1):PAGE244_I12@MSTR_DISCRETE.CAP(CHIPS)':
 C_PATH='@baseboard_fab2_lib.baseboard_fab2(sch_1):page244_i12@mstr_discrete.cap~
(chips)',
 P_PATH='@baseboard_fab2_lib.baseboard_fab2(sch_1):page244_i12@mstr_discrete.cap~
(chips)',
 PATH='I12',
 DRAWING='@BASEBOARD_FAB2_LIB.BASEBOARD_FAB2(SCH_1):PAGE244',
 TOLERANCE='10%',
 SEC_TYPE='0402',
 MATERIAL='X7R',
 PHYS_PAGE='244',
 XY='(-5725,2025)',
 ROT='2',
 VER='1',
 VALUE='0.22UF',
 PACK_TYPE='0402',
 PART_NUMBER='A36096-155',
 ROOM='OCP_STEERING',
 GROUP='PCIE_RISER',
 SEC='1',
 CDS_LIB='mstr_discrete',
 CDS_PART_NAME='CAP_0402-0.22UF,16V,10%,X7R,A3A',
 VOLTAGE='16V',
 PRIM_FILE='./archive_libs/mstr_discrete/cap/chips/chips.prt';

PART_NAME
 C828 'CAP_0402-0.22UF,16V,10%,X7R,A3A':
 GROUP='PCIE_RISER',
 ROOM='OCP_STEERING';

SECTION_NUMBER 1
 '@BASEBOARD_FAB2_LIB.BASEBOARD_FAB2(SCH_1):PAGE244_I28@MSTR_DISCRETE.CAP(CHIPS)':
 C_PATH='@baseboard_fab2_lib.baseboard_fab2(sch_1):page244_i28@mstr_discrete.cap~
(chips)',
 P_PATH='@baseboard_fab2_lib.baseboard_fab2(sch_1):page244_i28@mstr_discrete.cap~
(chips)',
 PATH='I28',
 DRAWING='@BASEBOARD_FAB2_LIB.BASEBOARD_FAB2(SCH_1):PAGE244',
 TOLERANCE='10%',
 SEC_TYPE='0402',
 MATERIAL='X7R',
 PHYS_PAGE='244',
 XY='(-5625,3025)',
 ROT='2',
 VER='1',
 VALUE='0.22UF',
 PACK_TYPE='0402',
 PART_NUMBER='A36096-155',
 ROOM='OCP_STEERING',
 GROUP='PCIE_RISER',
 SEC='1',
 CDS_LIB='mstr_discrete',
 CDS_PART_NAME='CAP_0402-0.22UF,16V,10%,X7R,A3A',
 VOLTAGE='16V',
 PRIM_FILE='./archive_libs/mstr_discrete/cap/chips/chips.prt';

PART_NAME
 C829 'CAP_0402-0.22UF,16V,10%,X7R,A3A':
 GROUP='PCIE_RISER',
 ROOM='OCP_STEERING';

SECTION_NUMBER 1
 '@BASEBOARD_FAB2_LIB.BASEBOARD_FAB2(SCH_1):PAGE244_I5@MSTR_DISCRETE.CAP(CHIPS)':
 C_PATH='@baseboard_fab2_lib.baseboard_fab2(sch_1):page244_i5@mstr_discrete.cap(~
chips)',
 P_PATH='@baseboard_fab2_lib.baseboard_fab2(sch_1):page244_i5@mstr_discrete.cap(~
chips)',
 PATH='I5',
 DRAWING='@BASEBOARD_FAB2_LIB.BASEBOARD_FAB2(SCH_1):PAGE244',
 TOLERANCE='10%',
 SEC_TYPE='0402',
 MATERIAL='X7R',
 PHYS_PAGE='244',
 XY='(-5525,1725)',
 ROT='2',
 VER='1',
 VALUE='0.22UF',
 PACK_TYPE='0402',
 PART_NUMBER='A36096-155',
 ROOM='OCP_STEERING',
 GROUP='PCIE_RISER',
 SEC='1',
 CDS_LIB='mstr_discrete',
 CDS_PART_NAME='CAP_0402-0.22UF,16V,10%,X7R,A3A',
 VOLTAGE='16V',
 PRIM_FILE='./archive_libs/mstr_discrete/cap/chips/chips.prt';

PART_NAME
 C830 'CAP_0402-0.22UF,16V,10%,X7R,A3A':
 GROUP='PCIE_RISER',
 ROOM='OCP_STEERING';

SECTION_NUMBER 1
 '@BASEBOARD_FAB2_LIB.BASEBOARD_FAB2(SCH_1):PAGE244_I23@MSTR_DISCRETE.CAP(CHIPS)':
 C_PATH='@baseboard_fab2_lib.baseboard_fab2(sch_1):page244_i23@mstr_discrete.cap~
(chips)',
 P_PATH='@baseboard_fab2_lib.baseboard_fab2(sch_1):page244_i23@mstr_discrete.cap~
(chips)',
 PATH='I23',
 DRAWING='@BASEBOARD_FAB2_LIB.BASEBOARD_FAB2(SCH_1):PAGE244',
 TOLERANCE='10%',
 SEC_TYPE='0402',
 MATERIAL='X7R',
 PHYS_PAGE='244',
 XY='(-6025,3025)',
 ROT='2',
 VER='1',
 VALUE='0.22UF',
 PACK_TYPE='0402',
 PART_NUMBER='A36096-155',
 ROOM='OCP_STEERING',
 GROUP='PCIE_RISER',
 SEC='1',
 CDS_LIB='mstr_discrete',
 CDS_PART_NAME='CAP_0402-0.22UF,16V,10%,X7R,A3A',
 VOLTAGE='16V',
 PRIM_FILE='./archive_libs/mstr_discrete/cap/chips/chips.prt';

PART_NAME
 C831 'CAP_0402-0.22UF,16V,10%,X7R,A3A':
 GROUP='PCIE_RISER',
 ROOM='OCP_STEERING';

SECTION_NUMBER 1
 '@BASEBOARD_FAB2_LIB.BASEBOARD_FAB2(SCH_1):PAGE244_I2@MSTR_DISCRETE.CAP(CHIPS)':
 C_PATH='@baseboard_fab2_lib.baseboard_fab2(sch_1):page244_i2@mstr_discrete.cap(~
chips)',
 P_PATH='@baseboard_fab2_lib.baseboard_fab2(sch_1):page244_i2@mstr_discrete.cap(~
chips)',
 PATH='I2',
 DRAWING='@BASEBOARD_FAB2_LIB.BASEBOARD_FAB2(SCH_1):PAGE244',
 TOLERANCE='10%',
 SEC_TYPE='0402',
 MATERIAL='X7R',
 PHYS_PAGE='244',
 XY='(-5925,1725)',
 ROT='2',
 VER='1',
 VALUE='0.22UF',
 PACK_TYPE='0402',
 PART_NUMBER='A36096-155',
 ROOM='OCP_STEERING',
 GROUP='PCIE_RISER',
 SEC='1',
 CDS_LIB='mstr_discrete',
 CDS_PART_NAME='CAP_0402-0.22UF,16V,10%,X7R,A3A',
 VOLTAGE='16V',
 PRIM_FILE='./archive_libs/mstr_discrete/cap/chips/chips.prt';

PART_NAME
 C832 'CAP_0402-0.22UF,16V,10%,X7R,A3A':
 GROUP='PCIE_RISER',
 ROOM='OCP_STEERING';

SECTION_NUMBER 1
 '@BASEBOARD_FAB2_LIB.BASEBOARD_FAB2(SCH_1):PAGE244_I30@MSTR_DISCRETE.CAP(CHIPS)':
 C_PATH='@baseboard_fab2_lib.baseboard_fab2(sch_1):page244_i30@mstr_discrete.cap~
(chips)',
 P_PATH='@baseboard_fab2_lib.baseboard_fab2(sch_1):page244_i30@mstr_discrete.cap~
(chips)',
 PATH='I30',
 DRAWING='@BASEBOARD_FAB2_LIB.BASEBOARD_FAB2(SCH_1):PAGE244',
 TOLERANCE='10%',
 SEC_TYPE='0402',
 MATERIAL='X7R',
 PHYS_PAGE='244',
 XY='(-5225,3025)',
 ROT='2',
 VER='1',
 VALUE='0.22UF',
 PACK_TYPE='0402',
 PART_NUMBER='A36096-155',
 ROOM='OCP_STEERING',
 GROUP='PCIE_RISER',
 SEC='1',
 CDS_LIB='mstr_discrete',
 CDS_PART_NAME='CAP_0402-0.22UF,16V,10%,X7R,A3A',
 VOLTAGE='16V',
 PRIM_FILE='./archive_libs/mstr_discrete/cap/chips/chips.prt';

PART_NAME
 C833 'CAP_0402-0.22UF,16V,10%,X7R,A3A':
 GROUP='PCIE_RISER',
 ROOM='OCP_STEERING';

SECTION_NUMBER 1
 '@BASEBOARD_FAB2_LIB.BASEBOARD_FAB2(SCH_1):PAGE244_I8@MSTR_DISCRETE.CAP(CHIPS)':
 C_PATH='@baseboard_fab2_lib.baseboard_fab2(sch_1):page244_i8@mstr_discrete.cap(~
chips)',
 P_PATH='@baseboard_fab2_lib.baseboard_fab2(sch_1):page244_i8@mstr_discrete.cap(~
chips)',
 PATH='I8',
 DRAWING='@BASEBOARD_FAB2_LIB.BASEBOARD_FAB2(SCH_1):PAGE244',
 TOLERANCE='10%',
 SEC_TYPE='0402',
 MATERIAL='X7R',
 PHYS_PAGE='244',
 XY='(-5125,1725)',
 ROT='2',
 VER='1',
 VALUE='0.22UF',
 PACK_TYPE='0402',
 PART_NUMBER='A36096-155',
 ROOM='OCP_STEERING',
 GROUP='PCIE_RISER',
 SEC='1',
 CDS_LIB='mstr_discrete',
 CDS_PART_NAME='CAP_0402-0.22UF,16V,10%,X7R,A3A',
 VOLTAGE='16V',
 PRIM_FILE='./archive_libs/mstr_discrete/cap/chips/chips.prt';

PART_NAME
 C834 'CAP_0402-0.22UF,16V,10%,X7R,A3A':
 GROUP='PCIE_RISER',
 ROOM='OCP_STEERING';

SECTION_NUMBER 1
 '@BASEBOARD_FAB2_LIB.BASEBOARD_FAB2(SCH_1):PAGE244_I50@MSTR_DISCRETE.CAP(CHIPS)':
 C_PATH='@baseboard_fab2_lib.baseboard_fab2(sch_1):page244_i50@mstr_discrete.cap~
(chips)',
 P_PATH='@baseboard_fab2_lib.baseboard_fab2(sch_1):page244_i50@mstr_discrete.cap~
(chips)',
 PATH='I50',
 DRAWING='@BASEBOARD_FAB2_LIB.BASEBOARD_FAB2(SCH_1):PAGE244',
 TOLERANCE='10%',
 SEC_TYPE='0402',
 MATERIAL='X7R',
 PHYS_PAGE='244',
 XY='(-5025,3325)',
 ROT='2',
 VER='1',
 VALUE='0.22UF',
 PACK_TYPE='0402',
 PART_NUMBER='A36096-155',
 ROOM='OCP_STEERING',
 GROUP='PCIE_RISER',
 SEC='1',
 CDS_LIB='mstr_discrete',
 CDS_PART_NAME='CAP_0402-0.22UF,16V,10%,X7R,A3A',
 VOLTAGE='16V',
 PRIM_FILE='./archive_libs/mstr_discrete/cap/chips/chips.prt';

PART_NAME
 C835 'CAP_0402-0.22UF,16V,10%,X7R,A3A':
 GROUP='PCIE_RISER',
 ROOM='OCP_STEERING';

SECTION_NUMBER 1
 '@BASEBOARD_FAB2_LIB.BASEBOARD_FAB2(SCH_1):PAGE244_I41@MSTR_DISCRETE.CAP(CHIPS)':
 C_PATH='@baseboard_fab2_lib.baseboard_fab2(sch_1):page244_i41@mstr_discrete.cap~
(chips)',
 P_PATH='@baseboard_fab2_lib.baseboard_fab2(sch_1):page244_i41@mstr_discrete.cap~
(chips)',
 PATH='I41',
 DRAWING='@BASEBOARD_FAB2_LIB.BASEBOARD_FAB2(SCH_1):PAGE244',
 TOLERANCE='10%',
 SEC_TYPE='0402',
 MATERIAL='X7R',
 PHYS_PAGE='244',
 XY='(-4925,2025)',
 ROT='2',
 VER='1',
 VALUE='0.22UF',
 PACK_TYPE='0402',
 PART_NUMBER='A36096-155',
 ROOM='OCP_STEERING',
 GROUP='PCIE_RISER',
 SEC='1',
 CDS_LIB='mstr_discrete',
 CDS_PART_NAME='CAP_0402-0.22UF,16V,10%,X7R,A3A',
 VOLTAGE='16V',
 PRIM_FILE='./archive_libs/mstr_discrete/cap/chips/chips.prt';

PART_NAME
 C840 'CAP_0402-0.22UF,16V,10%,X7R,A3A':
 GROUP='PCIE_RISER',
 ROOM='OCP_STEERING';

SECTION_NUMBER 1
 '@BASEBOARD_FAB2_LIB.BASEBOARD_FAB2(SCH_1):PAGE244_I29@MSTR_DISCRETE.CAP(CHIPS)':
 C_PATH='@baseboard_fab2_lib.baseboard_fab2(sch_1):page244_i29@mstr_discrete.cap~
(chips)',
 P_PATH='@baseboard_fab2_lib.baseboard_fab2(sch_1):page244_i29@mstr_discrete.cap~
(chips)',
 PATH='I29',
 DRAWING='@BASEBOARD_FAB2_LIB.BASEBOARD_FAB2(SCH_1):PAGE244',
 TOLERANCE='10%',
 SEC_TYPE='0402',
 MATERIAL='X7R',
 PHYS_PAGE='244',
 XY='(-5425,3325)',
 ROT='2',
 VER='1',
 VALUE='0.22UF',
 PACK_TYPE='0402',
 PART_NUMBER='A36096-155',
 ROOM='OCP_STEERING',
 GROUP='PCIE_RISER',
 SEC='1',
 CDS_LIB='mstr_discrete',
 CDS_PART_NAME='CAP_0402-0.22UF,16V,10%,X7R,A3A',
 VOLTAGE='16V',
 PRIM_FILE='./archive_libs/mstr_discrete/cap/chips/chips.prt';

PART_NAME
 C841 'CAP_0402-0.22UF,16V,10%,X7R,A3A':
 GROUP='PCIE_RISER',
 ROOM='OCP_STEERING';

SECTION_NUMBER 1
 '@BASEBOARD_FAB2_LIB.BASEBOARD_FAB2(SCH_1):PAGE244_I17@MSTR_DISCRETE.CAP(CHIPS)':
 C_PATH='@baseboard_fab2_lib.baseboard_fab2(sch_1):page244_i17@mstr_discrete.cap~
(chips)',
 P_PATH='@baseboard_fab2_lib.baseboard_fab2(sch_1):page244_i17@mstr_discrete.cap~
(chips)',
 PATH='I17',
 DRAWING='@BASEBOARD_FAB2_LIB.BASEBOARD_FAB2(SCH_1):PAGE244',
 TOLERANCE='10%',
 SEC_TYPE='0402',
 MATERIAL='X7R',
 PHYS_PAGE='244',
 XY='(-5325,2025)',
 ROT='2',
 VER='1',
 VALUE='0.22UF',
 PACK_TYPE='0402',
 PART_NUMBER='A36096-155',
 ROOM='OCP_STEERING',
 GROUP='PCIE_RISER',
 SEC='1',
 CDS_LIB='mstr_discrete',
 CDS_PART_NAME='CAP_0402-0.22UF,16V,10%,X7R,A3A',
 VOLTAGE='16V',
 PRIM_FILE='./archive_libs/mstr_discrete/cap/chips/chips.prt';

PART_NAME
 C842 'CAP_0402-0.22UF,16V,10%,X7R,A3A':
 GROUP='PCIE_RISER',
 ROOM='OCP_STEERING';

SECTION_NUMBER 1
 '@BASEBOARD_FAB2_LIB.BASEBOARD_FAB2(SCH_1):PAGE244_I52@MSTR_DISCRETE.CAP(CHIPS)':
 C_PATH='@baseboard_fab2_lib.baseboard_fab2(sch_1):page244_i52@mstr_discrete.cap~
(chips)',
 P_PATH='@baseboard_fab2_lib.baseboard_fab2(sch_1):page244_i52@mstr_discrete.cap~
(chips)',
 PATH='I52',
 DRAWING='@BASEBOARD_FAB2_LIB.BASEBOARD_FAB2(SCH_1):PAGE244',
 TOLERANCE='10%',
 SEC_TYPE='0402',
 MATERIAL='X7R',
 PHYS_PAGE='244',
 XY='(-4625,3300)',
 ROT='2',
 VER='1',
 VALUE='0.22UF',
 PACK_TYPE='0402',
 PART_NUMBER='A36096-155',
 ROOM='OCP_STEERING',
 GROUP='PCIE_RISER',
 SEC='1',
 CDS_LIB='mstr_discrete',
 CDS_PART_NAME='CAP_0402-0.22UF,16V,10%,X7R,A3A',
 VOLTAGE='16V',
 PRIM_FILE='./archive_libs/mstr_discrete/cap/chips/chips.prt';

PART_NAME
 C843 'CAP_0402-0.22UF,16V,10%,X7R,A3A':
 GROUP='PCIE_RISER',
 ROOM='OCP_STEERING';

SECTION_NUMBER 1
 '@BASEBOARD_FAB2_LIB.BASEBOARD_FAB2(SCH_1):PAGE244_I47@MSTR_DISCRETE.CAP(CHIPS)':
 C_PATH='@baseboard_fab2_lib.baseboard_fab2(sch_1):page244_i47@mstr_discrete.cap~
(chips)',
 P_PATH='@baseboard_fab2_lib.baseboard_fab2(sch_1):page244_i47@mstr_discrete.cap~
(chips)',
 PATH='I47',
 DRAWING='@BASEBOARD_FAB2_LIB.BASEBOARD_FAB2(SCH_1):PAGE244',
 TOLERANCE='10%',
 SEC_TYPE='0402',
 MATERIAL='X7R',
 PHYS_PAGE='244',
 XY='(-4525,2025)',
 ROT='2',
 VER='1',
 VALUE='0.22UF',
 PACK_TYPE='0402',
 PART_NUMBER='A36096-155',
 ROOM='OCP_STEERING',
 GROUP='PCIE_RISER',
 SEC='1',
 CDS_LIB='mstr_discrete',
 CDS_PART_NAME='CAP_0402-0.22UF,16V,10%,X7R,A3A',
 VOLTAGE='16V',
 PRIM_FILE='./archive_libs/mstr_discrete/cap/chips/chips.prt';

PART_NAME
 C844 'CAP_0402-0.22UF,16V,10%,X7R,A3A':
 GROUP='PCIE_RISER',
 ROOM='OCP_STEERING';

SECTION_NUMBER 1
 '@BASEBOARD_FAB2_LIB.BASEBOARD_FAB2(SCH_1):PAGE244_I51@MSTR_DISCRETE.CAP(CHIPS)':
 C_PATH='@baseboard_fab2_lib.baseboard_fab2(sch_1):page244_i51@mstr_discrete.cap~
(chips)',
 P_PATH='@baseboard_fab2_lib.baseboard_fab2(sch_1):page244_i51@mstr_discrete.cap~
(chips)',
 PATH='I51',
 DRAWING='@BASEBOARD_FAB2_LIB.BASEBOARD_FAB2(SCH_1):PAGE244',
 TOLERANCE='10%',
 SEC_TYPE='0402',
 MATERIAL='X7R',
 PHYS_PAGE='244',
 XY='(-4825,3025)',
 ROT='2',
 VER='1',
 VALUE='0.22UF',
 PACK_TYPE='0402',
 PART_NUMBER='A36096-155',
 ROOM='OCP_STEERING',
 GROUP='PCIE_RISER',
 SEC='1',
 CDS_LIB='mstr_discrete',
 CDS_PART_NAME='CAP_0402-0.22UF,16V,10%,X7R,A3A',
 VOLTAGE='16V',
 PRIM_FILE='./archive_libs/mstr_discrete/cap/chips/chips.prt';

PART_NAME
 C845 'CAP_0402-0.22UF,16V,10%,X7R,A3A':
 GROUP='PCIE_RISER',
 ROOM='OCP_STEERING';

SECTION_NUMBER 1
 '@BASEBOARD_FAB2_LIB.BASEBOARD_FAB2(SCH_1):PAGE244_I35@MSTR_DISCRETE.CAP(CHIPS)':
 C_PATH='@baseboard_fab2_lib.baseboard_fab2(sch_1):page244_i35@mstr_discrete.cap~
(chips)',
 P_PATH='@baseboard_fab2_lib.baseboard_fab2(sch_1):page244_i35@mstr_discrete.cap~
(chips)',
 PATH='I35',
 DRAWING='@BASEBOARD_FAB2_LIB.BASEBOARD_FAB2(SCH_1):PAGE244',
 TOLERANCE='10%',
 SEC_TYPE='0402',
 MATERIAL='X7R',
 PHYS_PAGE='244',
 XY='(-4725,1725)',
 ROT='2',
 VER='1',
 VALUE='0.22UF',
 PACK_TYPE='0402',
 PART_NUMBER='A36096-155',
 ROOM='OCP_STEERING',
 GROUP='PCIE_RISER',
 SEC='1',
 CDS_LIB='mstr_discrete',
 CDS_PART_NAME='CAP_0402-0.22UF,16V,10%,X7R,A3A',
 VOLTAGE='16V',
 PRIM_FILE='./archive_libs/mstr_discrete/cap/chips/chips.prt';

PART_NAME
 CF1 'SC22P50V2JN-4GP_SMD-BCG-SC22P5A':
 GROUP='POWER_FAIR';

SECTION_NUMBER 1
 '@BASEBOARD_FAB2_LIB.BASEBOARD_FAB2(SCH_1):PAGE201_I168@W_HDL.SC22P50V2JN-4GP(CHIPS)':
 C_PATH='@baseboard_fab2_lib.baseboard_fab2(sch_1):page201_i168@w_hdl.\sc22p50v2~
jn-4gp\(chips)',
 P_PATH='@baseboard_fab2_lib.baseboard_fab2(sch_1):page201_i168@w_hdl.\sc22p50v2~
jn-4gp\(chips)',
 PATH='I168',
 DRAWING='@BASEBOARD_FAB2_LIB.BASEBOARD_FAB2(SCH_1):PAGE201',
 TYPE='NPO',
 PACK_SIZE='0402',
 RATED='50V',
 ATTRIBUTE='22PF',
 TOLERANCE='5%',
 PHYS_PAGE='201',
 XY='(-6750,3350)',
 ROT='1',
 VER='1',
 VALUE='SC22P50V2JN-4GP',
 PACK_TYPE='SMD-BCG',
 PART_NUMBER='78.22034.1FL',
 LOCATION='CF1',
 GROUP='POWER_FAIR',
 CDS_LIB='w_hdl',
 CDS_PART_NAME='SC22P50V2JN-4GP_SMD-BCG-SC22P5A',
 PRIM_FILE='C:/<user>/w_hdl/sc22p50v2jn#2d4gp/chips/chips.prt';

PART_NAME
 CF2 'SC22P50V2JN-4GP_SMD-BCG-SC22P5A':
 GROUP='POWER_FAIR';

SECTION_NUMBER 1
 '@BASEBOARD_FAB2_LIB.BASEBOARD_FAB2(SCH_1):PAGE201_I169@W_HDL.SC22P50V2JN-4GP(CHIPS)':
 C_PATH='@baseboard_fab2_lib.baseboard_fab2(sch_1):page201_i169@w_hdl.\sc22p50v2~
jn-4gp\(chips)',
 P_PATH='@baseboard_fab2_lib.baseboard_fab2(sch_1):page201_i169@w_hdl.\sc22p50v2~
jn-4gp\(chips)',
 PATH='I169',
 DRAWING='@BASEBOARD_FAB2_LIB.BASEBOARD_FAB2(SCH_1):PAGE201',
 TYPE='NPO',
 PACK_SIZE='0402',
 RATED='50V',
 ATTRIBUTE='22PF',
 TOLERANCE='5%',
 PHYS_PAGE='201',
 XY='(-6300,3350)',
 ROT='1',
 VER='1',
 VALUE='SC22P50V2JN-4GP',
 PACK_TYPE='SMD-BCG',
 PART_NUMBER='78.22034.1FL',
 LOCATION='CF2',
 GROUP='POWER_FAIR',
 CDS_LIB='w_hdl',
 CDS_PART_NAME='SC22P50V2JN-4GP_SMD-BCG-SC22P5A',
 PRIM_FILE='C:/<user>/w_hdl/sc22p50v2jn#2d4gp/chips/chips.prt';

PART_NAME
 CF3 'SC22P50V2JN-4GP_SMD-BCG-SC22P5A':
 GROUP='POWER_FAIR';

SECTION_NUMBER 1
 '@BASEBOARD_FAB2_LIB.BASEBOARD_FAB2(SCH_1):PAGE201_I170@W_HDL.SC22P50V2JN-4GP(CHIPS)':
 C_PATH='@baseboard_fab2_lib.baseboard_fab2(sch_1):page201_i170@w_hdl.\sc22p50v2~
jn-4gp\(chips)',
 P_PATH='@baseboard_fab2_lib.baseboard_fab2(sch_1):page201_i170@w_hdl.\sc22p50v2~
jn-4gp\(chips)',
 PATH='I170',
 DRAWING='@BASEBOARD_FAB2_LIB.BASEBOARD_FAB2(SCH_1):PAGE201',
 TYPE='NPO',
 PACK_SIZE='0402',
 RATED='50V',
 ATTRIBUTE='22PF',
 TOLERANCE='5%',
 PHYS_PAGE='201',
 XY='(-5825,3350)',
 ROT='1',
 VER='1',
 VALUE='SC22P50V2JN-4GP',
 PACK_TYPE='SMD-BCG',
 PART_NUMBER='78.22034.1FL',
 LOCATION='CF3',
 GROUP='POWER_FAIR',
 CDS_LIB='w_hdl',
 CDS_PART_NAME='SC22P50V2JN-4GP_SMD-BCG-SC22P5A',
 PRIM_FILE='C:/<user>/w_hdl/sc22p50v2jn#2d4gp/chips/chips.prt';

PART_NAME
 CF4 'SC22P50V2JN-4GP_SMD-BCG-SC22P5A':
 GROUP='POWER_FAIR';

SECTION_NUMBER 1
 '@BASEBOARD_FAB2_LIB.BASEBOARD_FAB2(SCH_1):PAGE201_I171@W_HDL.SC22P50V2JN-4GP(CHIPS)':
 C_PATH='@baseboard_fab2_lib.baseboard_fab2(sch_1):page201_i171@w_hdl.\sc22p50v2~
jn-4gp\(chips)',
 P_PATH='@baseboard_fab2_lib.baseboard_fab2(sch_1):page201_i171@w_hdl.\sc22p50v2~
jn-4gp\(chips)',
 PATH='I171',
 DRAWING='@BASEBOARD_FAB2_LIB.BASEBOARD_FAB2(SCH_1):PAGE201',
 TYPE='NPO',
 PACK_SIZE='0402',
 RATED='50V',
 ATTRIBUTE='22PF',
 TOLERANCE='5%',
 PHYS_PAGE='201',
 XY='(-5425,3350)',
 ROT='1',
 VER='1',
 VALUE='SC22P50V2JN-4GP',
 PACK_TYPE='SMD-BCG',
 PART_NUMBER='78.22034.1FL',
 LOCATION='CF4',
 GROUP='POWER_FAIR',
 CDS_LIB='w_hdl',
 CDS_PART_NAME='SC22P50V2JN-4GP_SMD-BCG-SC22P5A',
 PRIM_FILE='C:/<user>/w_hdl/sc22p50v2jn#2d4gp/chips/chips.prt';

PART_NAME
 CF5 'SC22P50V2JN-4GP_SMD-BCG-SC22P5A':
 GROUP='POWER_FAIR';

SECTION_NUMBER 1
 '@BASEBOARD_FAB2_LIB.BASEBOARD_FAB2(SCH_1):PAGE201_I172@W_HDL.SC22P50V2JN-4GP(CHIPS)':
 C_PATH='@baseboard_fab2_lib.baseboard_fab2(sch_1):page201_i172@w_hdl.\sc22p50v2~
jn-4gp\(chips)',
 P_PATH='@baseboard_fab2_lib.baseboard_fab2(sch_1):page201_i172@w_hdl.\sc22p50v2~
jn-4gp\(chips)',
 PATH='I172',
 DRAWING='@BASEBOARD_FAB2_LIB.BASEBOARD_FAB2(SCH_1):PAGE201',
 TYPE='NPO',
 PACK_SIZE='0402',
 RATED='50V',
 ATTRIBUTE='22PF',
 TOLERANCE='5%',
 PHYS_PAGE='201',
 XY='(-5025,3350)',
 ROT='1',
 VER='1',
 VALUE='SC22P50V2JN-4GP',
 PACK_TYPE='SMD-BCG',
 PART_NUMBER='78.22034.1FL',
 LOCATION='CF5',
 GROUP='POWER_FAIR',
 CDS_LIB='w_hdl',
 CDS_PART_NAME='SC22P50V2JN-4GP_SMD-BCG-SC22P5A',
 PRIM_FILE='C:/<user>/w_hdl/sc22p50v2jn#2d4gp/chips/chips.prt';

PART_NAME
 CF6 'SC22P50V2JN-4GP_SMD-BCG-SC22P5A':
 GROUP='POWER_FAIR';

SECTION_NUMBER 1
 '@BASEBOARD_FAB2_LIB.BASEBOARD_FAB2(SCH_1):PAGE201_I173@W_HDL.SC22P50V2JN-4GP(CHIPS)':
 C_PATH='@baseboard_fab2_lib.baseboard_fab2(sch_1):page201_i173@w_hdl.\sc22p50v2~
jn-4gp\(chips)',
 P_PATH='@baseboard_fab2_lib.baseboard_fab2(sch_1):page201_i173@w_hdl.\sc22p50v2~
jn-4gp\(chips)',
 PATH='I173',
 DRAWING='@BASEBOARD_FAB2_LIB.BASEBOARD_FAB2(SCH_1):PAGE201',
 TYPE='NPO',
 PACK_SIZE='0402',
 RATED='50V',
 ATTRIBUTE='22PF',
 TOLERANCE='5%',
 PHYS_PAGE='201',
 XY='(-5800,1325)',
 ROT='1',
 VER='1',
 VALUE='SC22P50V2JN-4GP',
 PACK_TYPE='SMD-BCG',
 PART_NUMBER='78.22034.1FL',
 LOCATION='CF6',
 GROUP='POWER_FAIR',
 CDS_LIB='w_hdl',
 CDS_PART_NAME='SC22P50V2JN-4GP_SMD-BCG-SC22P5A',
 PRIM_FILE='C:/<user>/w_hdl/sc22p50v2jn#2d4gp/chips/chips.prt';

PART_NAME
 CF7 'SC22P50V2JN-4GP_SMD-BCG-SC22P5A':
 GROUP='POWER_FAIR';

SECTION_NUMBER 1
 '@BASEBOARD_FAB2_LIB.BASEBOARD_FAB2(SCH_1):PAGE206_I137@W_HDL.SC22P50V2JN-4GP(CHIPS)':
 C_PATH='@baseboard_fab2_lib.baseboard_fab2(sch_1):page206_i137@w_hdl.\sc22p50v2~
jn-4gp\(chips)',
 P_PATH='@baseboard_fab2_lib.baseboard_fab2(sch_1):page206_i137@w_hdl.\sc22p50v2~
jn-4gp\(chips)',
 PATH='I137',
 DRAWING='@BASEBOARD_FAB2_LIB.BASEBOARD_FAB2(SCH_1):PAGE206',
 TYPE='NPO',
 PACK_SIZE='0402',
 RATED='50V',
 ATTRIBUTE='22PF',
 TOLERANCE='5%',
 PHYS_PAGE='206',
 XY='(-6775,3350)',
 ROT='1',
 VER='1',
 VALUE='SC22P50V2JN-4GP',
 PACK_TYPE='SMD-BCG',
 PART_NUMBER='78.22034.1FL',
 LOCATION='CF7',
 GROUP='POWER_FAIR',
 CDS_LIB='w_hdl',
 CDS_PART_NAME='SC22P50V2JN-4GP_SMD-BCG-SC22P5A',
 PRIM_FILE='C:/<user>/w_hdl/sc22p50v2jn#2d4gp/chips/chips.prt';

PART_NAME
 CF8 'SC22P50V2JN-4GP_SMD-BCG-SC22P5A':
 GROUP='POWER_FAIR';

SECTION_NUMBER 1
 '@BASEBOARD_FAB2_LIB.BASEBOARD_FAB2(SCH_1):PAGE206_I138@W_HDL.SC22P50V2JN-4GP(CHIPS)':
 C_PATH='@baseboard_fab2_lib.baseboard_fab2(sch_1):page206_i138@w_hdl.\sc22p50v2~
jn-4gp\(chips)',
 P_PATH='@baseboard_fab2_lib.baseboard_fab2(sch_1):page206_i138@w_hdl.\sc22p50v2~
jn-4gp\(chips)',
 PATH='I138',
 DRAWING='@BASEBOARD_FAB2_LIB.BASEBOARD_FAB2(SCH_1):PAGE206',
 TYPE='NPO',
 PACK_SIZE='0402',
 RATED='50V',
 ATTRIBUTE='22PF',
 TOLERANCE='5%',
 SEC_TYPE='SMD-BCG',
 PHYS_PAGE='206',
 XY='(-6375,3350)',
 ROT='1',
 VER='1',
 VALUE='SC22P50V2JN-4GP',
 PACK_TYPE='SMD-BCG',
 PART_NUMBER='78.22034.1FL',
 LOCATION='CF8',
 GROUP='POWER_FAIR',
 SEC='1',
 CDS_LIB='w_hdl',
 CDS_PART_NAME='SC22P50V2JN-4GP_SMD-BCG-SC22P5A',
 PRIM_FILE='C:/<user>/w_hdl/sc22p50v2jn#2d4gp/chips/chips.prt';

PART_NAME
 CF9 'SC22P50V2JN-4GP_SMD-BCG-SC22P5A':
 GROUP='POWER_FAIR';

SECTION_NUMBER 1
 '@BASEBOARD_FAB2_LIB.BASEBOARD_FAB2(SCH_1):PAGE206_I139@W_HDL.SC22P50V2JN-4GP(CHIPS)':
 C_PATH='@baseboard_fab2_lib.baseboard_fab2(sch_1):page206_i139@w_hdl.\sc22p50v2~
jn-4gp\(chips)',
 P_PATH='@baseboard_fab2_lib.baseboard_fab2(sch_1):page206_i139@w_hdl.\sc22p50v2~
jn-4gp\(chips)',
 PATH='I139',
 DRAWING='@BASEBOARD_FAB2_LIB.BASEBOARD_FAB2(SCH_1):PAGE206',
 TYPE='NPO',
 PACK_SIZE='0402',
 RATED='50V',
 ATTRIBUTE='22PF',
 TOLERANCE='5%',
 PHYS_PAGE='206',
 XY='(-6000,3350)',
 ROT='1',
 VER='1',
 VALUE='SC22P50V2JN-4GP',
 PACK_TYPE='SMD-BCG',
 PART_NUMBER='78.22034.1FL',
 LOCATION='CF9',
 GROUP='POWER_FAIR',
 CDS_LIB='w_hdl',
 CDS_PART_NAME='SC22P50V2JN-4GP_SMD-BCG-SC22P5A',
 PRIM_FILE='C:/<user>/w_hdl/sc22p50v2jn#2d4gp/chips/chips.prt';

PART_NAME
 CF10 'SC22P50V2JN-4GP_SMD-BCG-SC22P5A':
 GROUP='POWER_FAIR';

SECTION_NUMBER 1
 '@BASEBOARD_FAB2_LIB.BASEBOARD_FAB2(SCH_1):PAGE206_I140@W_HDL.SC22P50V2JN-4GP(CHIPS)':
 C_PATH='@baseboard_fab2_lib.baseboard_fab2(sch_1):page206_i140@w_hdl.\sc22p50v2~
jn-4gp\(chips)',
 P_PATH='@baseboard_fab2_lib.baseboard_fab2(sch_1):page206_i140@w_hdl.\sc22p50v2~
jn-4gp\(chips)',
 PATH='I140',
 DRAWING='@BASEBOARD_FAB2_LIB.BASEBOARD_FAB2(SCH_1):PAGE206',
 TYPE='NPO',
 PACK_SIZE='0402',
 RATED='50V',
 ATTRIBUTE='22PF',
 TOLERANCE='5%',
 PHYS_PAGE='206',
 XY='(-5550,3350)',
 ROT='1',
 VER='1',
 VALUE='SC22P50V2JN-4GP',
 PACK_TYPE='SMD-BCG',
 PART_NUMBER='78.22034.1FL',
 LOCATION='CF10',
 GROUP='POWER_FAIR',
 CDS_LIB='w_hdl',
 CDS_PART_NAME='SC22P50V2JN-4GP_SMD-BCG-SC22P5A',
 PRIM_FILE='C:/<user>/w_hdl/sc22p50v2jn#2d4gp/chips/chips.prt';

PART_NAME
 CF11 'SC22P50V2JN-4GP_SMD-BCG-SC22P5A':
 GROUP='POWER_FAIR';

SECTION_NUMBER 1
 '@BASEBOARD_FAB2_LIB.BASEBOARD_FAB2(SCH_1):PAGE206_I141@W_HDL.SC22P50V2JN-4GP(CHIPS)':
 C_PATH='@baseboard_fab2_lib.baseboard_fab2(sch_1):page206_i141@w_hdl.\sc22p50v2~
jn-4gp\(chips)',
 P_PATH='@baseboard_fab2_lib.baseboard_fab2(sch_1):page206_i141@w_hdl.\sc22p50v2~
jn-4gp\(chips)',
 PATH='I141',
 DRAWING='@BASEBOARD_FAB2_LIB.BASEBOARD_FAB2(SCH_1):PAGE206',
 TYPE='NPO',
 PACK_SIZE='0402',
 RATED='50V',
 ATTRIBUTE='22PF',
 TOLERANCE='5%',
 PHYS_PAGE='206',
 XY='(-5100,3350)',
 ROT='1',
 VER='1',
 VALUE='SC22P50V2JN-4GP',
 PACK_TYPE='SMD-BCG',
 PART_NUMBER='78.22034.1FL',
 LOCATION='CF11',
 GROUP='POWER_FAIR',
 CDS_LIB='w_hdl',
 CDS_PART_NAME='SC22P50V2JN-4GP_SMD-BCG-SC22P5A',
 PRIM_FILE='C:/<user>/w_hdl/sc22p50v2jn#2d4gp/chips/chips.prt';

PART_NAME
 CF12 'SC22P50V2JN-4GP_SMD-BCG-SC22P5A':
 GROUP='POWER_FAIR';

SECTION_NUMBER 1
 '@BASEBOARD_FAB2_LIB.BASEBOARD_FAB2(SCH_1):PAGE206_I142@W_HDL.SC22P50V2JN-4GP(CHIPS)':
 C_PATH='@baseboard_fab2_lib.baseboard_fab2(sch_1):page206_i142@w_hdl.\sc22p50v2~
jn-4gp\(chips)',
 P_PATH='@baseboard_fab2_lib.baseboard_fab2(sch_1):page206_i142@w_hdl.\sc22p50v2~
jn-4gp\(chips)',
 PATH='I142',
 DRAWING='@BASEBOARD_FAB2_LIB.BASEBOARD_FAB2(SCH_1):PAGE206',
 TYPE='NPO',
 PACK_SIZE='0402',
 RATED='50V',
 ATTRIBUTE='22PF',
 TOLERANCE='5%',
 PHYS_PAGE='206',
 XY='(-6525,1275)',
 ROT='1',
 VER='1',
 VALUE='SC22P50V2JN-4GP',
 PACK_TYPE='SMD-BCG',
 PART_NUMBER='78.22034.1FL',
 LOCATION='CF12',
 GROUP='POWER_FAIR',
 CDS_LIB='w_hdl',
 CDS_PART_NAME='SC22P50V2JN-4GP_SMD-BCG-SC22P5A',
 PRIM_FILE='C:/<user>/w_hdl/sc22p50v2jn#2d4gp/chips/chips.prt';

PART_NAME
 CF13 'SC22P50V2JN-4GP_SMD-BCG-SC22P5A':
 GROUP='POWER_FAIR';

SECTION_NUMBER 1
 '@BASEBOARD_FAB2_LIB.BASEBOARD_FAB2(SCH_1):PAGE211_I95@W_HDL.SC22P50V2JN-4GP(CHIPS)':
 C_PATH='@baseboard_fab2_lib.baseboard_fab2(sch_1):page211_i95@w_hdl.\sc22p50v2j~
n-4gp\(chips)',
 P_PATH='@baseboard_fab2_lib.baseboard_fab2(sch_1):page211_i95@w_hdl.\sc22p50v2j~
n-4gp\(chips)',
 PATH='I95',
 DRAWING='@BASEBOARD_FAB2_LIB.BASEBOARD_FAB2(SCH_1):PAGE211',
 TYPE='NPO',
 PACK_SIZE='0402',
 RATED='50V',
 ATTRIBUTE='22PF',
 TOLERANCE='5%',
 PHYS_PAGE='211',
 XY='(-1975,3600)',
 ROT='1',
 VER='1',
 VALUE='SC22P50V2JN-4GP',
 PACK_TYPE='SMD-BCG',
 PART_NUMBER='78.22034.1FL',
 LOCATION='CF13',
 GROUP='POWER_FAIR',
 CDS_LIB='w_hdl',
 CDS_PART_NAME='SC22P50V2JN-4GP_SMD-BCG-SC22P5A',
 PRIM_FILE='C:/<user>/w_hdl/sc22p50v2jn#2d4gp/chips/chips.prt';

PART_NAME
 CF14 'SC22P50V2JN-4GP_SMD-BCG-SC22P5A':
 GROUP='POWER_FAIR';

SECTION_NUMBER 1
 '@BASEBOARD_FAB2_LIB.BASEBOARD_FAB2(SCH_1):PAGE213_I98@W_HDL.SC22P50V2JN-4GP(CHIPS)':
 C_PATH='@baseboard_fab2_lib.baseboard_fab2(sch_1):page213_i98@w_hdl.\sc22p50v2j~
n-4gp\(chips)',
 P_PATH='@baseboard_fab2_lib.baseboard_fab2(sch_1):page213_i98@w_hdl.\sc22p50v2j~
n-4gp\(chips)',
 PATH='I98',
 DRAWING='@BASEBOARD_FAB2_LIB.BASEBOARD_FAB2(SCH_1):PAGE213',
 TYPE='NPO',
 PACK_SIZE='0402',
 RATED='50V',
 ATTRIBUTE='22PF',
 TOLERANCE='5%',
 PHYS_PAGE='213',
 XY='(-1900,3500)',
 ROT='1',
 VER='1',
 VALUE='SC22P50V2JN-4GP',
 PACK_TYPE='SMD-BCG',
 PART_NUMBER='78.22034.1FL',
 LOCATION='CF14',
 GROUP='POWER_FAIR',
 CDS_LIB='w_hdl',
 CDS_PART_NAME='SC22P50V2JN-4GP_SMD-BCG-SC22P5A',
 PRIM_FILE='C:/<user>/w_hdl/sc22p50v2jn#2d4gp/chips/chips.prt';

PART_NAME
 CF15 'SC22P50V2JN-4GP_SMD-BCG-SC22P5A':
 GROUP='POWER_FAIR';

SECTION_NUMBER 1
 '@BASEBOARD_FAB2_LIB.BASEBOARD_FAB2(SCH_1):PAGE215_I16@W_HDL.SC22P50V2JN-4GP(CHIPS)':
 C_PATH='@baseboard_fab2_lib.baseboard_fab2(sch_1):page215_i16@w_hdl.\sc22p50v2j~
n-4gp\(chips)',
 P_PATH='@baseboard_fab2_lib.baseboard_fab2(sch_1):page215_i16@w_hdl.\sc22p50v2j~
n-4gp\(chips)',
 PATH='I16',
 DRAWING='@BASEBOARD_FAB2_LIB.BASEBOARD_FAB2(SCH_1):PAGE215',
 TYPE='NPO',
 PACK_SIZE='0402',
 RATED='50V',
 ATTRIBUTE='22PF',
 TOLERANCE='5%',
 PHYS_PAGE='215',
 XY='(-275,2325)',
 ROT='1',
 VER='1',
 VALUE='SC22P50V2JN-4GP',
 PACK_TYPE='SMD-BCG',
 PART_NUMBER='78.22034.1FL',
 LOCATION='CF15',
 GROUP='POWER_FAIR',
 CDS_LIB='w_hdl',
 CDS_PART_NAME='SC22P50V2JN-4GP_SMD-BCG-SC22P5A',
 PRIM_FILE='C:/<user>/w_hdl/sc22p50v2jn#2d4gp/chips/chips.prt';

PART_NAME
 CF16 'SC22P50V2JN-4GP_SMD-BCG-SC22P5A':
 GROUP='POWER_FAIR';

SECTION_NUMBER 1
 '@BASEBOARD_FAB2_LIB.BASEBOARD_FAB2(SCH_1):PAGE215_I26@W_HDL.SC22P50V2JN-4GP(CHIPS)':
 C_PATH='@baseboard_fab2_lib.baseboard_fab2(sch_1):page215_i26@w_hdl.\sc22p50v2j~
n-4gp\(chips)',
 P_PATH='@baseboard_fab2_lib.baseboard_fab2(sch_1):page215_i26@w_hdl.\sc22p50v2j~
n-4gp\(chips)',
 PATH='I26',
 DRAWING='@BASEBOARD_FAB2_LIB.BASEBOARD_FAB2(SCH_1):PAGE215',
 TYPE='NPO',
 PACK_SIZE='0402',
 RATED='50V',
 ATTRIBUTE='22PF',
 BOM_SS='NOPOP',
 TOLERANCE='5%',
 PHYS_PAGE='215',
 XY='(625,2450)',
 ROT='1',
 VER='1',
 VALUE='SC22P50V2JN-4GP',
 PACK_TYPE='SMD-BCG',
 PART_NUMBER='78.22034.1FL',
 LOCATION='CF16',
 GROUP='POWER_FAIR',
 CDS_LIB='w_hdl',
 CDS_PART_NAME='SC22P50V2JN-4GP_SMD-BCG-SC22P5A',
 PRIM_FILE='C:/<user>/w_hdl/sc22p50v2jn#2d4gp/chips/chips.prt';

PART_NAME
 CF17 'SC22P50V2JN-4GP_SMD-BCG-SC22P5A':
 GROUP='POWER_FAIR';

SECTION_NUMBER 1
 '@BASEBOARD_FAB2_LIB.BASEBOARD_FAB2(SCH_1):PAGE218_I17@W_HDL.SC22P50V2JN-4GP(CHIPS)':
 C_PATH='@baseboard_fab2_lib.baseboard_fab2(sch_1):page218_i17@w_hdl.\sc22p50v2j~
n-4gp\(chips)',
 P_PATH='@baseboard_fab2_lib.baseboard_fab2(sch_1):page218_i17@w_hdl.\sc22p50v2j~
n-4gp\(chips)',
 PATH='I17',
 DRAWING='@BASEBOARD_FAB2_LIB.BASEBOARD_FAB2(SCH_1):PAGE218',
 TYPE='NPO',
 PACK_SIZE='0402',
 RATED='50V',
 ATTRIBUTE='22PF',
 TOLERANCE='5%',
 PHYS_PAGE='218',
 XY='(-2200,2250)',
 ROT='1',
 VER='1',
 VALUE='SC22P50V2JN-4GP',
 PACK_TYPE='SMD-BCG',
 PART_NUMBER='78.22034.1FL',
 LOCATION='CF17',
 GROUP='POWER_FAIR',
 CDS_LIB='w_hdl',
 CDS_PART_NAME='SC22P50V2JN-4GP_SMD-BCG-SC22P5A',
 PRIM_FILE='C:/<user>/w_hdl/sc22p50v2jn#2d4gp/chips/chips.prt';

PART_NAME
 CF18 'SC22P50V2JN-4GP_SMD-BCG-SC22P5A':
 GROUP='POWER_FAIR';

SECTION_NUMBER 1
 '@BASEBOARD_FAB2_LIB.BASEBOARD_FAB2(SCH_1):PAGE218_I20@W_HDL.SC22P50V2JN-4GP(CHIPS)':
 C_PATH='@baseboard_fab2_lib.baseboard_fab2(sch_1):page218_i20@w_hdl.\sc22p50v2j~
n-4gp\(chips)',
 P_PATH='@baseboard_fab2_lib.baseboard_fab2(sch_1):page218_i20@w_hdl.\sc22p50v2j~
n-4gp\(chips)',
 PATH='I20',
 DRAWING='@BASEBOARD_FAB2_LIB.BASEBOARD_FAB2(SCH_1):PAGE218',
 TYPE='NPO',
 PACK_SIZE='0402',
 RATED='50V',
 ATTRIBUTE='22PF',
 BOM_SS='NOPOP',
 TOLERANCE='5%',
 PHYS_PAGE='218',
 XY='(-1550,2250)',
 ROT='1',
 VER='1',
 VALUE='SC22P50V2JN-4GP',
 PACK_TYPE='SMD-BCG',
 PART_NUMBER='78.22034.1FL',
 LOCATION='CF18',
 GROUP='POWER_FAIR',
 CDS_LIB='w_hdl',
 CDS_PART_NAME='SC22P50V2JN-4GP_SMD-BCG-SC22P5A',
 PRIM_FILE='C:/<user>/w_hdl/sc22p50v2jn#2d4gp/chips/chips.prt';

PART_NAME
 CF19 'SC22P50V2JN-4GP_SMD-BCG-SC22P5A':
 GROUP='POWER_FAIR';

SECTION_NUMBER 1
 '@BASEBOARD_FAB2_LIB.BASEBOARD_FAB2(SCH_1):PAGE223_I15@W_HDL.SC22P50V2JN-4GP(CHIPS)':
 C_PATH='@baseboard_fab2_lib.baseboard_fab2(sch_1):page223_i15@w_hdl.\sc22p50v2j~
n-4gp\(chips)',
 P_PATH='@baseboard_fab2_lib.baseboard_fab2(sch_1):page223_i15@w_hdl.\sc22p50v2j~
n-4gp\(chips)',
 PATH='I15',
 DRAWING='@BASEBOARD_FAB2_LIB.BASEBOARD_FAB2(SCH_1):PAGE223',
 TYPE='NPO',
 PACK_SIZE='0402',
 RATED='50V',
 ATTRIBUTE='22PF',
 TOLERANCE='5%',
 PHYS_PAGE='223',
 XY='(-1100,2275)',
 ROT='1',
 VER='1',
 VALUE='SC22P50V2JN-4GP',
 PACK_TYPE='SMD-BCG',
 PART_NUMBER='78.22034.1FL',
 LOCATION='CF19',
 GROUP='POWER_FAIR',
 CDS_LIB='w_hdl',
 CDS_PART_NAME='SC22P50V2JN-4GP_SMD-BCG-SC22P5A',
 PRIM_FILE='C:/<user>/w_hdl/sc22p50v2jn#2d4gp/chips/chips.prt';

PART_NAME
 CF20 'SC22P50V2JN-4GP_SMD-BCG-SC22P5A':
 GROUP='POWER_FAIR';

SECTION_NUMBER 1
 '@BASEBOARD_FAB2_LIB.BASEBOARD_FAB2(SCH_1):PAGE223_I17@W_HDL.SC22P50V2JN-4GP(CHIPS)':
 C_PATH='@baseboard_fab2_lib.baseboard_fab2(sch_1):page223_i17@w_hdl.\sc22p50v2j~
n-4gp\(chips)',
 P_PATH='@baseboard_fab2_lib.baseboard_fab2(sch_1):page223_i17@w_hdl.\sc22p50v2j~
n-4gp\(chips)',
 PATH='I17',
 DRAWING='@BASEBOARD_FAB2_LIB.BASEBOARD_FAB2(SCH_1):PAGE223',
 TYPE='NPO',
 PACK_SIZE='0402',
 RATED='50V',
 ATTRIBUTE='22PF',
 BOM_SS='NOPOP',
 TOLERANCE='5%',
 PHYS_PAGE='223',
 XY='(-225,2275)',
 ROT='1',
 VER='1',
 VALUE='SC22P50V2JN-4GP',
 PACK_TYPE='SMD-BCG',
 PART_NUMBER='78.22034.1FL',
 LOCATION='CF20',
 GROUP='POWER_FAIR',
 CDS_LIB='w_hdl',
 CDS_PART_NAME='SC22P50V2JN-4GP_SMD-BCG-SC22P5A',
 PRIM_FILE='C:/<user>/w_hdl/sc22p50v2jn#2d4gp/chips/chips.prt';

PART_NAME
 CF21 'SC22P50V2JN-4GP_SMD-BCG-SC22P5A':
 GROUP='POWER_FAIR';

SECTION_NUMBER 1
 '@BASEBOARD_FAB2_LIB.BASEBOARD_FAB2(SCH_1):PAGE226_I15@W_HDL.SC22P50V2JN-4GP(CHIPS)':
 C_PATH='@baseboard_fab2_lib.baseboard_fab2(sch_1):page226_i15@w_hdl.\sc22p50v2j~
n-4gp\(chips)',
 P_PATH='@baseboard_fab2_lib.baseboard_fab2(sch_1):page226_i15@w_hdl.\sc22p50v2j~
n-4gp\(chips)',
 PATH='I15',
 DRAWING='@BASEBOARD_FAB2_LIB.BASEBOARD_FAB2(SCH_1):PAGE226',
 TYPE='NPO',
 PACK_SIZE='0402',
 RATED='50V',
 ATTRIBUTE='22PF',
 TOLERANCE='5%',
 PHYS_PAGE='226',
 XY='(-1550,1850)',
 ROT='1',
 VER='1',
 VALUE='SC22P50V2JN-4GP',
 PACK_TYPE='SMD-BCG',
 PART_NUMBER='78.22034.1FL',
 LOCATION='CF21',
 GROUP='POWER_FAIR',
 CDS_LIB='w_hdl',
 CDS_PART_NAME='SC22P50V2JN-4GP_SMD-BCG-SC22P5A',
 PRIM_FILE='C:/<user>/w_hdl/sc22p50v2jn#2d4gp/chips/chips.prt';

PART_NAME
 CF22 'SC22P50V2JN-4GP_SMD-BCG-SC22P5A':
 GROUP='POWER_FAIR';

SECTION_NUMBER 1
 '@BASEBOARD_FAB2_LIB.BASEBOARD_FAB2(SCH_1):PAGE226_I17@W_HDL.SC22P50V2JN-4GP(CHIPS)':
 C_PATH='@baseboard_fab2_lib.baseboard_fab2(sch_1):page226_i17@w_hdl.\sc22p50v2j~
n-4gp\(chips)',
 P_PATH='@baseboard_fab2_lib.baseboard_fab2(sch_1):page226_i17@w_hdl.\sc22p50v2j~
n-4gp\(chips)',
 PATH='I17',
 DRAWING='@BASEBOARD_FAB2_LIB.BASEBOARD_FAB2(SCH_1):PAGE226',
 TYPE='NPO',
 PACK_SIZE='0402',
 RATED='50V',
 ATTRIBUTE='22PF',
 BOM_SS='NOPOP',
 TOLERANCE='5%',
 PHYS_PAGE='226',
 XY='(-750,1850)',
 ROT='1',
 VER='1',
 VALUE='SC22P50V2JN-4GP',
 PACK_TYPE='SMD-BCG',
 PART_NUMBER='78.22034.1FL',
 LOCATION='CF22',
 GROUP='POWER_FAIR',
 CDS_LIB='w_hdl',
 CDS_PART_NAME='SC22P50V2JN-4GP_SMD-BCG-SC22P5A',
 PRIM_FILE='C:/<user>/w_hdl/sc22p50v2jn#2d4gp/chips/chips.prt';

PART_NAME
 CF23 'SC22P50V2JN-4GP_SMD-BCG-SC22P5A':
 GROUP='POWER_FAIR';

SECTION_NUMBER 1
 '@BASEBOARD_FAB2_LIB.BASEBOARD_FAB2(SCH_1):PAGE235_I239@W_HDL.SC22P50V2JN-4GP(CHIPS)':
 C_PATH='@baseboard_fab2_lib.baseboard_fab2(sch_1):page235_i239@w_hdl.\sc22p50v2~
jn-4gp\(chips)',
 P_PATH='@baseboard_fab2_lib.baseboard_fab2(sch_1):page235_i239@w_hdl.\sc22p50v2~
jn-4gp\(chips)',
 PATH='I239',
 DRAWING='@BASEBOARD_FAB2_LIB.BASEBOARD_FAB2(SCH_1):PAGE235',
 TYPE='NPO',
 PACK_SIZE='0402',
 RATED='50V',
 ATTRIBUTE='22PF',
 TOLERANCE='5%',
 PHYS_PAGE='235',
 XY='(-11800,4450)',
 ROT='1',
 VER='1',
 VALUE='SC22P50V2JN-4GP',
 PACK_TYPE='SMD-BCG',
 PART_NUMBER='78.22034.1FL',
 LOCATION='CF23',
 GROUP='POWER_FAIR',
 CDS_LIB='w_hdl',
 CDS_PART_NAME='SC22P50V2JN-4GP_SMD-BCG-SC22P5A',
 PRIM_FILE='C:/<user>/w_hdl/sc22p50v2jn#2d4gp/chips/chips.prt';

PART_NAME
 CF24 'SC22P50V2JN-4GP_SMD-BCG-SC22P5A':
 GROUP='POWER_FAIR';

SECTION_NUMBER 1
 '@BASEBOARD_FAB2_LIB.BASEBOARD_FAB2(SCH_1):PAGE235_I240@W_HDL.SC22P50V2JN-4GP(CHIPS)':
 C_PATH='@baseboard_fab2_lib.baseboard_fab2(sch_1):page235_i240@w_hdl.\sc22p50v2~
jn-4gp\(chips)',
 P_PATH='@baseboard_fab2_lib.baseboard_fab2(sch_1):page235_i240@w_hdl.\sc22p50v2~
jn-4gp\(chips)',
 PATH='I240',
 DRAWING='@BASEBOARD_FAB2_LIB.BASEBOARD_FAB2(SCH_1):PAGE235',
 TYPE='NPO',
 PACK_SIZE='0402',
 RATED='50V',
 ATTRIBUTE='22PF',
 TOLERANCE='5%',
 PHYS_PAGE='235',
 XY='(-11100,2900)',
 ROT='1',
 VER='1',
 VALUE='SC22P50V2JN-4GP',
 PACK_TYPE='SMD-BCG',
 PART_NUMBER='78.22034.1FL',
 LOCATION='CF24',
 GROUP='POWER_FAIR',
 CDS_LIB='w_hdl',
 CDS_PART_NAME='SC22P50V2JN-4GP_SMD-BCG-SC22P5A',
 PRIM_FILE='C:/<user>/w_hdl/sc22p50v2jn#2d4gp/chips/chips.prt';

PART_NAME
 CN8F1 'CAP_A_0402V-1.0UF,6.3V,10%,X6SA':
 ROOM='VDDQ_KLM_PWR_VR';

SECTION_NUMBER 1
 '@BASEBOARD_FAB2_LIB.BASEBOARD_FAB2(SCH_1):PAGE246_I21@DEV_DISCRETE.CAP_A(CHIPS)':
 C_PATH='@baseboard_fab2_lib.baseboard_fab2(sch_1):page246_i21@dev_discrete.cap_~
a(chips)',
 P_PATH='@baseboard_fab2_lib.baseboard_fab2(sch_1):page246_i21@dev_discrete.cap_~
a(chips)',
 PATH='I21',
 DRAWING='@BASEBOARD_FAB2_LIB.BASEBOARD_FAB2(SCH_1):PAGE246',
 TOLERANCE='10%',
 SEC_TYPE='0402V',
 MATERIAL='X6S',
 PHYS_PAGE='246',
 XY='(-3000,3275)',
 ROT='0',
 VER='1',
 VALUE='1.0UF',
 PACK_TYPE='0402V',
 PART_NUMBER='D97712-004',
 LOCATION='CN8F1',
 ROOM='VDDQ_KLM_PWR_VR',
 SEC='1',
 CDS_LIB='dev_discrete',
 CDS_PART_NAME='CAP_A_0402V-1.0UF,6.3V,10%,X6SA',
 VOLTAGE='6.3V',
 PRIM_FILE='./archive_libs/discrete/cap_a/chips/chips.prt';

PART_NAME
 CN8F2 'CAP_A_0402V-0.01UF,25V,10%,X7RA':
 ROOM='DDR4_CH_M';

SECTION_NUMBER 1
 '@BASEBOARD_FAB2_LIB.BASEBOARD_FAB2(SCH_1):PAGE246_I22@DEV_DISCRETE.CAP_A(CHIPS)':
 C_PATH='@baseboard_fab2_lib.baseboard_fab2(sch_1):page246_i22@dev_discrete.cap_~
a(chips)',
 P_PATH='@baseboard_fab2_lib.baseboard_fab2(sch_1):page246_i22@dev_discrete.cap_~
a(chips)',
 PATH='I22',
 DRAWING='@BASEBOARD_FAB2_LIB.BASEBOARD_FAB2(SCH_1):PAGE246',
 TOLERANCE='10%',
 SEC_TYPE='0402V',
 MATERIAL='X7R',
 BOM_COST='MEM',
 PHYS_PAGE='246',
 XY='(-2700,3275)',
 ROT='2',
 VER='1',
 VALUE='0.01UF',
 PACK_TYPE='0402V',
 PART_NUMBER='A36096-045',
 LOCATION='CN8F2',
 ROOM='DDR4_CH_M',
 SEC='1',
 CDS_LIB='dev_discrete',
 CDS_PART_NAME='CAP_A_0402V-0.01UF,25V,10%,X7RA',
 VOLTAGE='25V',
 PRIM_FILE='./archive_libs/discrete/cap_a/chips/chips.prt';

PART_NAME
 CONX8 'SMC-CONN60A-22-GP_CONN-G7-SMC-A':;

SECTION_NUMBER 1
 '@BASEBOARD_FAB2_LIB.BASEBOARD_FAB2(SCH_1):PAGE245_I48@W_HDL.SMC-CONN60A-22-GP(CHIPS)':
 C_PATH='@baseboard_fab2_lib.baseboard_fab2(sch_1):page245_i48@w_hdl.\smc-conn60~
a-22-gp\(chips)',
 P_PATH='@baseboard_fab2_lib.baseboard_fab2(sch_1):page245_i48@w_hdl.\smc-conn60~
a-22-gp\(chips)',
 PATH='I48',
 DRAWING='@BASEBOARD_FAB2_LIB.BASEBOARD_FAB2(SCH_1):PAGE245',
 PHYS_PAGE='245',
 XY='(-4000,3775)',
 ROT='0',
 VER='1',
 VALUE='SMC-CONN60A-22-GP',
 PACK_TYPE='CONN-G7',
 PART_NUMBER='020.C0082.0060',
 LOCATION='CONX8',
 CDS_LIB='w_hdl',
 CDS_PART_NAME='SMC-CONN60A-22-GP_CONN-G7-SMC-A',
 PRIM_FILE='C:/<user>/w_hdl/smc#2dconn60a#2d22#2dgp/chips/chips.prt';

PART_NAME
 CR1B1 'DIODE_SM-SDMK0340L,EMPTY,H7179A':
 ROOM='CPU_FANS';

SECTION_NUMBER 1
 '@BASEBOARD_FAB2_LIB.BASEBOARD_FAB2(SCH_1):PAGE161_I64@MSTR_DISCRETE.DIODE(CHIPS)':
 C_PATH='@baseboard_fab2_lib.baseboard_fab2(sch_1):page161_i64@mstr_discrete.dio~
de(chips)',
 P_PATH='@baseboard_fab2_lib.baseboard_fab2(sch_1):page161_i64@mstr_discrete.dio~
de(chips)',
 PATH='I64',
 DRAWING='@BASEBOARD_FAB2_LIB.BASEBOARD_FAB2(SCH_1):PAGE161',
 SEC_TYPE='SM',
 MATERIAL='EMPTY',
 BOM_COST='SM_THERM',
 PHYS_PAGE='161',
 XY='(-2100,1250)',
 ROT='0',
 VER='4',
 VALUE='SDMK0340L',
 PACK_TYPE='SM',
 PART_NUMBER='H71799-001',
 LOCATION='CR1B1',
 ROOM='CPU_FANS',
 SEC='1',
 CDS_LIB='mstr_discrete',
 CDS_PART_NAME='DIODE_SM-SDMK0340L,EMPTY,H7179A',
 PRIM_FILE='./archive_libs/mstr_discrete/diode/chips/chips.prt';

PART_NAME
 CR1B2 'DIODE_SM-SDMK0340L,IC,H71799-0A':
 ROOM='CPU_FANS';

SECTION_NUMBER 1
 '@BASEBOARD_FAB2_LIB.BASEBOARD_FAB2(SCH_1):PAGE161_I62@MSTR_DISCRETE.DIODE(CHIPS)':
 C_PATH='@baseboard_fab2_lib.baseboard_fab2(sch_1):page161_i62@mstr_discrete.dio~
de(chips)',
 P_PATH='@baseboard_fab2_lib.baseboard_fab2(sch_1):page161_i62@mstr_discrete.dio~
de(chips)',
 PATH='I62',
 DRAWING='@BASEBOARD_FAB2_LIB.BASEBOARD_FAB2(SCH_1):PAGE161',
 SEC_TYPE='SM',
 MATERIAL='IC',
 BOM_COST='SM_THERM',
 PHYS_PAGE='161',
 XY='(-1825,1750)',
 ROT='0',
 VER='1',
 VALUE='SDMK0340L',
 PACK_TYPE='SM',
 PART_NUMBER='H71799-001',
 LOCATION='CR1B2',
 ROOM='CPU_FANS',
 SEC='1',
 CDS_LIB='mstr_discrete',
 CDS_PART_NAME='DIODE_SM-SDMK0340L,IC,H71799-0A',
 PRIM_FILE='./archive_libs/mstr_discrete/diode/chips/chips.prt';

PART_NAME
 CR1E1 'DIODE_SM-SDMK0340L,EMPTY,H7179A':
 ROOM='CPU_FANS';

SECTION_NUMBER 1
 '@BASEBOARD_FAB2_LIB.BASEBOARD_FAB2(SCH_1):PAGE161_I50@MSTR_DISCRETE.DIODE(CHIPS)':
 C_PATH='@baseboard_fab2_lib.baseboard_fab2(sch_1):page161_i50@mstr_discrete.dio~
de(chips)',
 P_PATH='@baseboard_fab2_lib.baseboard_fab2(sch_1):page161_i50@mstr_discrete.dio~
de(chips)',
 PATH='I50',
 DRAWING='@BASEBOARD_FAB2_LIB.BASEBOARD_FAB2(SCH_1):PAGE161',
 SEC_TYPE='SM',
 MATERIAL='EMPTY',
 BOM_COST='SM_THERM',
 PHYS_PAGE='161',
 XY='(-1950,3325)',
 ROT='0',
 VER='4',
 VALUE='SDMK0340L',
 PACK_TYPE='SM',
 PART_NUMBER='H71799-001',
 LOCATION='CR1E1',
 ROOM='CPU_FANS',
 SEC='1',
 CDS_LIB='mstr_discrete',
 CDS_PART_NAME='DIODE_SM-SDMK0340L,EMPTY,H7179A',
 PRIM_FILE='./archive_libs/mstr_discrete/diode/chips/chips.prt';

PART_NAME
 CR1F1 'DIODE_SM-SDMK0340L,IC,H71799-0A':
 ROOM='CPU_FANS';

SECTION_NUMBER 1
 '@BASEBOARD_FAB2_LIB.BASEBOARD_FAB2(SCH_1):PAGE161_I42@MSTR_DISCRETE.DIODE(CHIPS)':
 C_PATH='@baseboard_fab2_lib.baseboard_fab2(sch_1):page161_i42@mstr_discrete.dio~
de(chips)',
 P_PATH='@baseboard_fab2_lib.baseboard_fab2(sch_1):page161_i42@mstr_discrete.dio~
de(chips)',
 PATH='I42',
 DRAWING='@BASEBOARD_FAB2_LIB.BASEBOARD_FAB2(SCH_1):PAGE161',
 SEC_TYPE='SM',
 MATERIAL='IC',
 BOM_COST='SM_THERM',
 PHYS_PAGE='161',
 XY='(-1675,3825)',
 ROT='0',
 VER='1',
 VALUE='SDMK0340L',
 PACK_TYPE='SM',
 PART_NUMBER='H71799-001',
 LOCATION='CR1F1',
 ROOM='CPU_FANS',
 SEC='1',
 CDS_LIB='mstr_discrete',
 CDS_PART_NAME='DIODE_SM-SDMK0340L,IC,H71799-0A',
 PRIM_FILE='./archive_libs/mstr_discrete/diode/chips/chips.prt';

PART_NAME
 CR1F3 'DIODE_SM-SDMK0340L,IC,H71799-0A':
 ROOM='IO_SLOT';

SECTION_NUMBER 1
 '@BASEBOARD_FAB2_LIB.BASEBOARD_FAB2(SCH_1):PAGE181_I37@MSTR_DISCRETE.DIODE(CHIPS)':
 C_PATH='@baseboard_fab2_lib.baseboard_fab2(sch_1):page181_i37@mstr_discrete.dio~
de(chips)',
 P_PATH='@baseboard_fab2_lib.baseboard_fab2(sch_1):page181_i37@mstr_discrete.dio~
de(chips)',
 PATH='I37',
 DRAWING='@BASEBOARD_FAB2_LIB.BASEBOARD_FAB2(SCH_1):PAGE181',
 SEC_TYPE='SM',
 MATERIAL='IC',
 BOM_COST='IO_SLOT',
 PHYS_PAGE='181',
 XY='(-425,1550)',
 ROT='0',
 VER='1',
 VALUE='SDMK0340L',
 PACK_TYPE='SM',
 PART_NUMBER='H71799-001',
 LOCATION='CR1F3',
 ROOM='IO_SLOT',
 SEC='1',
 CDS_LIB='mstr_discrete',
 CDS_PART_NAME='DIODE_SM-SDMK0340L,IC,H71799-0A',
 PRIM_FILE='./archive_libs/mstr_discrete/diode/chips/chips.prt';

PART_NAME
 CR1F4 'DIODE_SM-SDMK0340L,IC,H71799-0A':
 ROOM='IO_SLOT';

SECTION_NUMBER 1
 '@BASEBOARD_FAB2_LIB.BASEBOARD_FAB2(SCH_1):PAGE181_I5@MSTR_DISCRETE.DIODE(CHIPS)':
 C_PATH='@baseboard_fab2_lib.baseboard_fab2(sch_1):page181_i5@mstr_discrete.diod~
e(chips)',
 P_PATH='@baseboard_fab2_lib.baseboard_fab2(sch_1):page181_i5@mstr_discrete.diod~
e(chips)',
 PATH='I5',
 DRAWING='@BASEBOARD_FAB2_LIB.BASEBOARD_FAB2(SCH_1):PAGE181',
 SEC_TYPE='SM',
 MATERIAL='IC',
 BOM_COST='IO_SLOT',
 PHYS_PAGE='181',
 XY='(-1550,1550)',
 ROT='0',
 VER='1',
 VALUE='SDMK0340L',
 PACK_TYPE='SM',
 PART_NUMBER='H71799-001',
 LOCATION='CR1F4',
 ROOM='IO_SLOT',
 SEC='1',
 CDS_LIB='mstr_discrete',
 CDS_PART_NAME='DIODE_SM-SDMK0340L,IC,H71799-0A',
 PRIM_FILE='./archive_libs/mstr_discrete/diode/chips/chips.prt';

PART_NAME
 CR1F5 'DIODE_SM-MBRS340T3G,EMPTY,C819A':;

SECTION_NUMBER 1
 '@BASEBOARD_FAB2_LIB.BASEBOARD_FAB2(SCH_1):PAGE200_I220@MSTR_DISCRETE.DIODE(CHIPS)':
 C_PATH='@baseboard_fab2_lib.baseboard_fab2(sch_1):page200_i220@mstr_discrete.di~
ode(chips)',
 P_PATH='@baseboard_fab2_lib.baseboard_fab2(sch_1):page200_i220@mstr_discrete.di~
ode(chips)',
 PATH='I220',
 DRAWING='@BASEBOARD_FAB2_LIB.BASEBOARD_FAB2(SCH_1):PAGE200',
 SEC_TYPE='SM',
 MATERIAL='EMPTY',
 PHYS_PAGE='200',
 XY='(2750,3275)',
 ROT='1',
 VER='1',
 VALUE='MBRS340T3G',
 PACK_TYPE='SM',
 PART_NUMBER='C81983-002',
 LOCATION='CR1F5',
 SEC='1',
 CDS_LIB='mstr_discrete',
 CDS_PART_NAME='DIODE_SM-MBRS340T3G,EMPTY,C819A',
 PRIM_FILE='./archive_libs/mstr_discrete/diode/chips/chips.prt';

PART_NAME
 CR1L1 'DIODE_SM-1N4148W,IC,D89194-001':
 ROOM='UART_MUX';

SECTION_NUMBER 1
 '@BASEBOARD_FAB2_LIB.BASEBOARD_FAB2(SCH_1):PAGE168_I2@MSTR_DISCRETE.DIODE(CHIPS)':
 C_PATH='@baseboard_fab2_lib.baseboard_fab2(sch_1):page168_i2@mstr_discrete.diod~
e(chips)',
 P_PATH='@baseboard_fab2_lib.baseboard_fab2(sch_1):page168_i2@mstr_discrete.diod~
e(chips)',
 PATH='I2',
 DRAWING='@BASEBOARD_FAB2_LIB.BASEBOARD_FAB2(SCH_1):PAGE168',
 SEC_TYPE='SM',
 MATERIAL='IC',
 BOM_COST='DEBUG',
 PHYS_PAGE='168',
 XY='(-6325,2750)',
 ROT='0',
 VER='1',
 VALUE='1N4148W',
 PACK_TYPE='SM',
 PART_NUMBER='D89194-001',
 LOCATION='CR1L1',
 ROOM='UART_MUX',
 SEC='1',
 CDS_LIB='mstr_discrete',
 CDS_PART_NAME='DIODE_SM-1N4148W,IC,D89194-001',
 PRIM_FILE='./archive_libs/mstr_discrete/diode/chips/chips.prt';

PART_NAME
 CR1L2 'DIODE_SM-1N4148W,IC,D89194-001':
 ROOM='UART_MUX';

SECTION_NUMBER 1
 '@BASEBOARD_FAB2_LIB.BASEBOARD_FAB2(SCH_1):PAGE168_I3@MSTR_DISCRETE.DIODE(CHIPS)':
 C_PATH='@baseboard_fab2_lib.baseboard_fab2(sch_1):page168_i3@mstr_discrete.diod~
e(chips)',
 P_PATH='@baseboard_fab2_lib.baseboard_fab2(sch_1):page168_i3@mstr_discrete.diod~
e(chips)',
 PATH='I3',
 DRAWING='@BASEBOARD_FAB2_LIB.BASEBOARD_FAB2(SCH_1):PAGE168',
 SEC_TYPE='SM',
 MATERIAL='IC',
 BOM_COST='DEBUG',
 PHYS_PAGE='168',
 XY='(-5675,2750)',
 ROT='0',
 VER='1',
 VALUE='1N4148W',
 PACK_TYPE='SM',
 PART_NUMBER='D89194-001',
 LOCATION='CR1L2',
 ROOM='UART_MUX',
 SEC='1',
 CDS_LIB='mstr_discrete',
 CDS_PART_NAME='DIODE_SM-1N4148W,IC,D89194-001',
 PRIM_FILE='./archive_libs/mstr_discrete/diode/chips/chips.prt';

PART_NAME
 CR1L3 'DIODE_SM-1N4148W,IC,D89194-001':
 ROOM='UART_MUX';

SECTION_NUMBER 1
 '@BASEBOARD_FAB2_LIB.BASEBOARD_FAB2(SCH_1):PAGE168_I4@MSTR_DISCRETE.DIODE(CHIPS)':
 C_PATH='@baseboard_fab2_lib.baseboard_fab2(sch_1):page168_i4@mstr_discrete.diod~
e(chips)',
 P_PATH='@baseboard_fab2_lib.baseboard_fab2(sch_1):page168_i4@mstr_discrete.diod~
e(chips)',
 PATH='I4',
 DRAWING='@BASEBOARD_FAB2_LIB.BASEBOARD_FAB2(SCH_1):PAGE168',
 SEC_TYPE='SM',
 MATERIAL='IC',
 BOM_COST='DEBUG',
 PHYS_PAGE='168',
 XY='(-4975,2750)',
 ROT='0',
 VER='1',
 VALUE='1N4148W',
 PACK_TYPE='SM',
 PART_NUMBER='D89194-001',
 LOCATION='CR1L3',
 ROOM='UART_MUX',
 SEC='1',
 CDS_LIB='mstr_discrete',
 CDS_PART_NAME='DIODE_SM-1N4148W,IC,D89194-001',
 PRIM_FILE='./archive_libs/mstr_discrete/diode/chips/chips.prt';

PART_NAME
 CR1L4 'DIODE_SM-1N4148W,IC,D89194-001':
 ROOM='UART_MUX';

SECTION_NUMBER 1
 '@BASEBOARD_FAB2_LIB.BASEBOARD_FAB2(SCH_1):PAGE168_I5@MSTR_DISCRETE.DIODE(CHIPS)':
 C_PATH='@baseboard_fab2_lib.baseboard_fab2(sch_1):page168_i5@mstr_discrete.diod~
e(chips)',
 P_PATH='@baseboard_fab2_lib.baseboard_fab2(sch_1):page168_i5@mstr_discrete.diod~
e(chips)',
 PATH='I5',
 DRAWING='@BASEBOARD_FAB2_LIB.BASEBOARD_FAB2(SCH_1):PAGE168',
 SEC_TYPE='SM',
 MATERIAL='IC',
 BOM_COST='DEBUG',
 PHYS_PAGE='168',
 XY='(-4225,2750)',
 ROT='0',
 VER='1',
 VALUE='1N4148W',
 PACK_TYPE='SM',
 PART_NUMBER='D89194-001',
 LOCATION='CR1L4',
 ROOM='UART_MUX',
 SEC='1',
 CDS_LIB='mstr_discrete',
 CDS_PART_NAME='DIODE_SM-1N4148W,IC,D89194-001',
 PRIM_FILE='./archive_libs/mstr_discrete/diode/chips/chips.prt';

PART_NAME
 CR1M2 'DIODEAC_DUAL_ARRAY_SM9-ESD3V3UA':
 ROOM='USB_REAR';

SECTION_NUMBER 1
 '@BASEBOARD_FAB2_LIB.BASEBOARD_FAB2(SCH_1):PAGE176_I98@MSTR_DISCRETE.DIODEAC_DUAL_ARRAY(CHIPS)':
 C_PATH='@baseboard_fab2_lib.baseboard_fab2(sch_1):page176_i98@mstr_discrete.dio~
deac_dual_array(chips)',
 P_PATH='@baseboard_fab2_lib.baseboard_fab2(sch_1):page176_i98@mstr_discrete.dio~
deac_dual_array(chips)',
 PATH='I98',
 DRAWING='@BASEBOARD_FAB2_LIB.BASEBOARD_FAB2(SCH_1):PAGE176',
 SEC_TYPE='SM9',
 MATERIAL='IC',
 BOM_COST='MIO_USB',
 PHYS_PAGE='176',
 XY='(-3950,4500)',
 ROT='0',
 VER='7',
 VALUE='ESD3V3U4ULC',
 PACK_TYPE='SM9',
 PART_NUMBER='G18435-001',
 LOCATION='CR1M2',
 ROOM='USB_REAR',
 SEC='1',
 CDS_LIB='mstr_discrete',
 CDS_PART_NAME='DIODEAC_DUAL_ARRAY_SM9-ESD3V3UA',
 PRIM_FILE='./archive_libs/mstr_discrete/diodeac_dual_array/chips/chips.prt';

PART_NAME
 CR2U1 'DIODE2A_DUAL_SMLF-BAS70-05,DIOA':
 ROOM='SB_VRD';

SECTION_NUMBER 1
 '@BASEBOARD_FAB2_LIB.BASEBOARD_FAB2(SCH_1):PAGE196_I53@MSTR_DISCRETE.DIODE2A_DUAL(CHIPS)':
 C_PATH='@baseboard_fab2_lib.baseboard_fab2(sch_1):page196_i53@mstr_discrete.dio~
de2a_dual(chips)',
 P_PATH='@baseboard_fab2_lib.baseboard_fab2(sch_1):page196_i53@mstr_discrete.dio~
de2a_dual(chips)',
 PATH='I53',
 DRAWING='@BASEBOARD_FAB2_LIB.BASEBOARD_FAB2(SCH_1):PAGE196',
 SEC_TYPE='SMLF',
 MATERIAL='DIO',
 PHYS_PAGE='196',
 XY='(-2700,4650)',
 ROT='0',
 VER='1',
 VALUE='BAS70-05',
 PACK_TYPE='SMLF',
 PART_NUMBER='C90169-001',
 LOCATION='CR2U1',
 ROOM='SB_VRD',
 SEC='1',
 CDS_LIB='mstr_discrete',
 CDS_PART_NAME='DIODE2A_DUAL_SMLF-BAS70-05,DIOA',
 PRIM_FILE='./archive_libs/mstr_discrete/diode2a_dual/chips/chips.prt';

PART_NAME
 CR3U1 'DIODE_SMLF-1N5819HW,IC,D55839-A':
 ROOM='BMC_DEBUG_HEADER';

SECTION_NUMBER 1
 '@BASEBOARD_FAB2_LIB.BASEBOARD_FAB2(SCH_1):PAGE189_I49@MSTR_DISCRETE.DIODE(CHIPS)':
 C_PATH='@baseboard_fab2_lib.baseboard_fab2(sch_1):page189_i49@mstr_discrete.dio~
de(chips)',
 P_PATH='@baseboard_fab2_lib.baseboard_fab2(sch_1):page189_i49@mstr_discrete.dio~
de(chips)',
 PATH='I49',
 DRAWING='@BASEBOARD_FAB2_LIB.BASEBOARD_FAB2(SCH_1):PAGE189',
 SEC_TYPE='SMLF',
 MATERIAL='IC',
 BOM_COST='DEBUG',
 PHYS_PAGE='189',
 XY='(3500,3525)',
 ROT='0',
 VER='1',
 VALUE='1N5819HW',
 PACK_TYPE='SMLF',
 PART_NUMBER='D55839-001',
 LOCATION='CR3U1',
 ROOM='BMC_DEBUG_HEADER',
 SEC='1',
 CDS_LIB='mstr_discrete',
 CDS_PART_NAME='DIODE_SMLF-1N5819HW,IC,D55839-A',
 PRIM_FILE='./archive_libs/mstr_discrete/diode/chips/chips.prt';

PART_NAME
 CR3W1 'DIODE_SMLF-BAT54WS,IC,C73510-0A':;

SECTION_NUMBER 1
 '@BASEBOARD_FAB2_LIB.BASEBOARD_FAB2(SCH_1):PAGE249_I55@MSTR_DISCRETE.DIODE(CHIPS)':
 C_PATH='@baseboard_fab2_lib.baseboard_fab2(sch_1):page249_i55@mstr_discrete.dio~
de(chips)',
 P_PATH='@baseboard_fab2_lib.baseboard_fab2(sch_1):page249_i55@mstr_discrete.dio~
de(chips)',
 PATH='I55',
 DRAWING='@BASEBOARD_FAB2_LIB.BASEBOARD_FAB2(SCH_1):PAGE249',
 SEC_TYPE='SMLF',
 MATERIAL='IC',
 PHYS_PAGE='249',
 XY='(-7050,2150)',
 ROT='6',
 VER='1',
 VALUE='BAT54WS',
 PACK_TYPE='SMLF',
 PART_NUMBER='C73510-001',
 LOCATION='CR3W1',
 SEC='1',
 CDS_LIB='mstr_discrete',
 CDS_PART_NAME='DIODE_SMLF-BAT54WS,IC,C73510-0A',
 PRIM_FILE='./archive_libs/mstr_discrete/diode/chips/chips.prt';

PART_NAME
 CR6W1 'DIODE_SMLF-BAT54WS,IC,C73510-0A':;

SECTION_NUMBER 1
 '@BASEBOARD_FAB2_LIB.BASEBOARD_FAB2(SCH_1):PAGE247_I157@MSTR_DISCRETE.DIODE(CHIPS)':
 C_PATH='@baseboard_fab2_lib.baseboard_fab2(sch_1):page247_i157@mstr_discrete.di~
ode(chips)',
 P_PATH='@baseboard_fab2_lib.baseboard_fab2(sch_1):page247_i157@mstr_discrete.di~
ode(chips)',
 PATH='I157',
 DRAWING='@BASEBOARD_FAB2_LIB.BASEBOARD_FAB2(SCH_1):PAGE247',
 SEC_TYPE='SMLF',
 MATERIAL='IC',
 PHYS_PAGE='247',
 XY='(-1350,3650)',
 ROT='6',
 VER='1',
 VALUE='BAT54WS',
 PACK_TYPE='SMLF',
 PART_NUMBER='C73510-001',
 LOCATION='CR6W1',
 SEC='1',
 CDS_LIB='mstr_discrete',
 CDS_PART_NAME='DIODE_SMLF-BAT54WS,IC,C73510-0A',
 PRIM_FILE='./archive_libs/mstr_discrete/diode/chips/chips.prt';

PART_NAME
 CR6W2 'DIODE_SMLF-BAT54WS,IC,C73510-0A':;

SECTION_NUMBER 1
 '@BASEBOARD_FAB2_LIB.BASEBOARD_FAB2(SCH_1):PAGE247_I158@MSTR_DISCRETE.DIODE(CHIPS)':
 C_PATH='@baseboard_fab2_lib.baseboard_fab2(sch_1):page247_i158@mstr_discrete.di~
ode(chips)',
 P_PATH='@baseboard_fab2_lib.baseboard_fab2(sch_1):page247_i158@mstr_discrete.di~
ode(chips)',
 PATH='I158',
 DRAWING='@BASEBOARD_FAB2_LIB.BASEBOARD_FAB2(SCH_1):PAGE247',
 SEC_TYPE='SMLF',
 MATERIAL='IC',
 PHYS_PAGE='247',
 XY='(-1350,3450)',
 ROT='6',
 VER='1',
 VALUE='BAT54WS',
 PACK_TYPE='SMLF',
 PART_NUMBER='C73510-001',
 LOCATION='CR6W2',
 SEC='1',
 CDS_LIB='mstr_discrete',
 CDS_PART_NAME='DIODE_SMLF-BAT54WS,IC,C73510-0A',
 PRIM_FILE='./archive_libs/mstr_discrete/diode/chips/chips.prt';

PART_NAME
 CR7E1 'DIODE_SMLF-BAT54WS,IC,C73510-0A':;

SECTION_NUMBER 1
 '@BASEBOARD_FAB2_LIB.BASEBOARD_FAB2(SCH_1):PAGE196_I103@MSTR_DISCRETE.DIODE(CHIPS)':
 C_PATH='@baseboard_fab2_lib.baseboard_fab2(sch_1):page196_i103@mstr_discrete.di~
ode(chips)',
 P_PATH='@baseboard_fab2_lib.baseboard_fab2(sch_1):page196_i103@mstr_discrete.di~
ode(chips)',
 PATH='I103',
 DRAWING='@BASEBOARD_FAB2_LIB.BASEBOARD_FAB2(SCH_1):PAGE196',
 SEC_TYPE='SMLF',
 MATERIAL='IC',
 PHYS_PAGE='196',
 XY='(825,3650)',
 ROT='0',
 VER='3',
 VALUE='BAT54WS',
 PACK_TYPE='SMLF',
 PART_NUMBER='C73510-001',
 LOCATION='CR7E1',
 SEC='1',
 CDS_LIB='mstr_discrete',
 CDS_PART_NAME='DIODE_SMLF-BAT54WS,IC,C73510-0A',
 PRIM_FILE='./archive_libs/mstr_discrete/diode/chips/chips.prt';

PART_NAME
 CR8E1 'DIODE_SMLF-BAT54WS,IC,C73510-0A':;

SECTION_NUMBER 1
 '@BASEBOARD_FAB2_LIB.BASEBOARD_FAB2(SCH_1):PAGE196_I128@MSTR_DISCRETE.DIODE(CHIPS)':
 C_PATH='@baseboard_fab2_lib.baseboard_fab2(sch_1):page196_i128@mstr_discrete.di~
ode(chips)',
 P_PATH='@baseboard_fab2_lib.baseboard_fab2(sch_1):page196_i128@mstr_discrete.di~
ode(chips)',
 PATH='I128',
 DRAWING='@BASEBOARD_FAB2_LIB.BASEBOARD_FAB2(SCH_1):PAGE196',
 SEC_TYPE='SMLF',
 MATERIAL='IC',
 PHYS_PAGE='196',
 XY='(1050,3400)',
 ROT='0',
 VER='3',
 VALUE='BAT54WS',
 PACK_TYPE='SMLF',
 PART_NUMBER='C73510-001',
 LOCATION='CR8E1',
 SEC='1',
 CDS_LIB='mstr_discrete',
 CDS_PART_NAME='DIODE_SMLF-BAT54WS,IC,C73510-0A',
 PRIM_FILE='./archive_libs/mstr_discrete/diode/chips/chips.prt';

PART_NAME
 CR9P1 'DIODE_SMLF-BAT54WS,IC,C73510-0A':;

SECTION_NUMBER 1
 '@BASEBOARD_FAB2_LIB.BASEBOARD_FAB2(SCH_1):PAGE200_I214@MSTR_DISCRETE.DIODE(CHIPS)':
 C_PATH='@baseboard_fab2_lib.baseboard_fab2(sch_1):page200_i214@mstr_discrete.di~
ode(chips)',
 P_PATH='@baseboard_fab2_lib.baseboard_fab2(sch_1):page200_i214@mstr_discrete.di~
ode(chips)',
 PATH='I214',
 DRAWING='@BASEBOARD_FAB2_LIB.BASEBOARD_FAB2(SCH_1):PAGE200',
 POP='NOPOP',
 SEC_TYPE='SMLF',
 MATERIAL='IC',
 PHYS_PAGE='200',
 XY='(1050,175)',
 ROT='2',
 VER='1',
 VALUE='BAT54WS',
 PACK_TYPE='SMLF',
 PART_NUMBER='C73510-001',
 LOCATION='CR9P1',
 SEC='1',
 CDS_LIB='mstr_discrete',
 CDS_PART_NAME='DIODE_SMLF-BAT54WS,IC,C73510-0A',
 PRIM_FILE='./archive_libs/mstr_discrete/diode/chips/chips.prt';

PART_NAME
 CR9P2 'DIODE_SMLF-BAT54WS,IC,C73510-0A':;

SECTION_NUMBER 1
 '@BASEBOARD_FAB2_LIB.BASEBOARD_FAB2(SCH_1):PAGE200_I213@MSTR_DISCRETE.DIODE(CHIPS)':
 C_PATH='@baseboard_fab2_lib.baseboard_fab2(sch_1):page200_i213@mstr_discrete.di~
ode(chips)',
 P_PATH='@baseboard_fab2_lib.baseboard_fab2(sch_1):page200_i213@mstr_discrete.di~
ode(chips)',
 PATH='I213',
 DRAWING='@BASEBOARD_FAB2_LIB.BASEBOARD_FAB2(SCH_1):PAGE200',
 SEC_TYPE='SMLF',
 MATERIAL='IC',
 PHYS_PAGE='200',
 XY='(1000,675)',
 ROT='2',
 VER='1',
 VALUE='BAT54WS',
 PACK_TYPE='SMLF',
 PART_NUMBER='C73510-001',
 LOCATION='CR9P2',
 SEC='1',
 CDS_LIB='mstr_discrete',
 CDS_PART_NAME='DIODE_SMLF-BAT54WS,IC,C73510-0A',
 PRIM_FILE='./archive_libs/mstr_discrete/diode/chips/chips.prt';

PART_NAME
 CR9W1 'DIODE_SMLF-BAT54WS,IC,C73510-0A':;

SECTION_NUMBER 1
 '@BASEBOARD_FAB2_LIB.BASEBOARD_FAB2(SCH_1):PAGE155_I202@MSTR_DISCRETE.DIODE(CHIPS)':
 C_PATH='@baseboard_fab2_lib.baseboard_fab2(sch_1):page155_i202@mstr_discrete.di~
ode(chips)',
 P_PATH='@baseboard_fab2_lib.baseboard_fab2(sch_1):page155_i202@mstr_discrete.di~
ode(chips)',
 PATH='I202',
 DRAWING='@BASEBOARD_FAB2_LIB.BASEBOARD_FAB2(SCH_1):PAGE155',
 SEC_TYPE='SMLF',
 MATERIAL='IC',
 PHYS_PAGE='155',
 XY='(-2900,1400)',
 ROT='0',
 VER='3',
 VALUE='BAT54WS',
 PACK_TYPE='SMLF',
 PART_NUMBER='C73510-001',
 LOCATION='CR9W1',
 SEC='1',
 CDS_LIB='mstr_discrete',
 CDS_PART_NAME='DIODE_SMLF-BAT54WS,IC,C73510-0A',
 PRIM_FILE='./archive_libs/mstr_discrete/diode/chips/chips.prt';

PART_NAME
 CR10W1 'DIODE_SM-SDMK0340L,IC,H71799-0A':
 ROOM='CPU_FANS';

SECTION_NUMBER 1
 '@BASEBOARD_FAB2_LIB.BASEBOARD_FAB2(SCH_1):PAGE251_I12@MSTR_DISCRETE.DIODE(CHIPS)':
 C_PATH='@baseboard_fab2_lib.baseboard_fab2(sch_1):page251_i12@mstr_discrete.dio~
de(chips)',
 P_PATH='@baseboard_fab2_lib.baseboard_fab2(sch_1):page251_i12@mstr_discrete.dio~
de(chips)',
 PATH='I12',
 DRAWING='@BASEBOARD_FAB2_LIB.BASEBOARD_FAB2(SCH_1):PAGE251',
 SEC_TYPE='SM',
 MATERIAL='IC',
 BOM_COST='SM_THERM',
 PHYS_PAGE='251',
 XY='(-3200,5250)',
 ROT='0',
 VER='1',
 VALUE='SDMK0340L',
 PACK_TYPE='SM',
 PART_NUMBER='H71799-001',
 LOCATION='CR10W1',
 ROOM='CPU_FANS',
 SEC='1',
 CDS_LIB='mstr_discrete',
 CDS_PART_NAME='DIODE_SM-SDMK0340L,IC,H71799-0A',
 PRIM_FILE='./archive_libs/mstr_discrete/diode/chips/chips.prt';

PART_NAME
 CR10W2 'DIODE_SM-SDMK0340L,EMPTY,H7179A':
 ROOM='CPU_FANS';

SECTION_NUMBER 1
 '@BASEBOARD_FAB2_LIB.BASEBOARD_FAB2(SCH_1):PAGE251_I10@MSTR_DISCRETE.DIODE(CHIPS)':
 C_PATH='@baseboard_fab2_lib.baseboard_fab2(sch_1):page251_i10@mstr_discrete.dio~
de(chips)',
 P_PATH='@baseboard_fab2_lib.baseboard_fab2(sch_1):page251_i10@mstr_discrete.dio~
de(chips)',
 PATH='I10',
 DRAWING='@BASEBOARD_FAB2_LIB.BASEBOARD_FAB2(SCH_1):PAGE251',
 SEC_TYPE='SM',
 MATERIAL='EMPTY',
 BOM_COST='SM_THERM',
 PHYS_PAGE='251',
 XY='(-3000,4625)',
 ROT='0',
 VER='4',
 VALUE='SDMK0340L',
 PACK_TYPE='SM',
 PART_NUMBER='H71799-001',
 LOCATION='CR10W2',
 ROOM='CPU_FANS',
 SEC='1',
 CDS_LIB='mstr_discrete',
 CDS_PART_NAME='DIODE_SM-SDMK0340L,EMPTY,H7179A',
 PRIM_FILE='./archive_libs/mstr_discrete/diode/chips/chips.prt';

PART_NAME
 CR10W3 'DIODE_SM-SDMK0340L,IC,H71799-0A':
 ROOM='CPU_FANS';

SECTION_NUMBER 1
 '@BASEBOARD_FAB2_LIB.BASEBOARD_FAB2(SCH_1):PAGE251_I26@MSTR_DISCRETE.DIODE(CHIPS)':
 C_PATH='@baseboard_fab2_lib.baseboard_fab2(sch_1):page251_i26@mstr_discrete.dio~
de(chips)',
 P_PATH='@baseboard_fab2_lib.baseboard_fab2(sch_1):page251_i26@mstr_discrete.dio~
de(chips)',
 PATH='I26',
 DRAWING='@BASEBOARD_FAB2_LIB.BASEBOARD_FAB2(SCH_1):PAGE251',
 SEC_TYPE='SM',
 MATERIAL='IC',
 BOM_COST='SM_THERM',
 PHYS_PAGE='251',
 XY='(-3200,3700)',
 ROT='0',
 VER='1',
 VALUE='SDMK0340L',
 PACK_TYPE='SM',
 PART_NUMBER='H71799-001',
 LOCATION='CR10W3',
 ROOM='CPU_FANS',
 SEC='1',
 CDS_LIB='mstr_discrete',
 CDS_PART_NAME='DIODE_SM-SDMK0340L,IC,H71799-0A',
 PRIM_FILE='./archive_libs/mstr_discrete/diode/chips/chips.prt';

PART_NAME
 CR25W1 'DIODEAC_DUAL_ARRAY_SM9-ESD3V3UA':
 GROUP='AST2500',
 ROOM='USB_REAR';

SECTION_NUMBER 1
 '@BASEBOARD_FAB2_LIB.BASEBOARD_FAB2(SCH_1):PAGE255_I129@MSTR_DISCRETE.DIODEAC_DUAL_ARRAY(CHIPS)':
 C_PATH='@baseboard_fab2_lib.baseboard_fab2(sch_1):page255_i129@mstr_discrete.di~
odeac_dual_array(chips)',
 P_PATH='@baseboard_fab2_lib.baseboard_fab2(sch_1):page252_i129@mstr_discrete.di~
odeac_dual_array(chips)',
 PATH='I129',
 DRAWING='@BASEBOARD_FAB2_LIB.BASEBOARD_FAB2(SCH_1):PAGE255',
 SEC_TYPE='SM9',
 MATERIAL='IC',
 BOM_COST='MIO_USB',
 PHYS_PAGE='252',
 XY='(-7000,5750)',
 ROT='0',
 VER='7',
 VALUE='ESD3V3U4ULC',
 PACK_TYPE='SM9',
 PART_NUMBER='G18435-001',
 LOCATION='CR25W1',
 ROOM='USB_REAR',
 GROUP='AST2500',
 SEC='1',
 CDS_LIB='mstr_discrete',
 CDS_PART_NAME='DIODEAC_DUAL_ARRAY_SM9-ESD3V3UA',
 PRIM_FILE='./archive_libs/mstr_discrete/diodeac_dual_array/chips/chips.prt';

PART_NAME
 CR25W2 'DIODEAC_DUAL_ARRAY_SM9-ESD3V3UA':
 GROUP='AST2500',
 ROOM='USB_REAR';

SECTION_NUMBER 1
 '@BASEBOARD_FAB2_LIB.BASEBOARD_FAB2(SCH_1):PAGE255_I131@MSTR_DISCRETE.DIODEAC_DUAL_ARRAY(CHIPS)':
 C_PATH='@baseboard_fab2_lib.baseboard_fab2(sch_1):page255_i131@mstr_discrete.di~
odeac_dual_array(chips)',
 P_PATH='@baseboard_fab2_lib.baseboard_fab2(sch_1):page252_i131@mstr_discrete.di~
odeac_dual_array(chips)',
 PATH='I131',
 DRAWING='@BASEBOARD_FAB2_LIB.BASEBOARD_FAB2(SCH_1):PAGE255',
 SEC_TYPE='SM9',
 MATERIAL='IC',
 BOM_COST='MIO_USB',
 PHYS_PAGE='252',
 XY='(-4350,5750)',
 ROT='0',
 VER='7',
 VALUE='ESD3V3U4ULC',
 PACK_TYPE='SM9',
 PART_NUMBER='G18435-001',
 LOCATION='CR25W2',
 ROOM='USB_REAR',
 GROUP='AST2500',
 SEC='1',
 CDS_LIB='mstr_discrete',
 CDS_PART_NAME='DIODEAC_DUAL_ARRAY_SM9-ESD3V3UA',
 PRIM_FILE='./archive_libs/mstr_discrete/diodeac_dual_array/chips/chips.prt';

PART_NAME
 CR30W1 'DIODEAC_DUAL_ARRAY_SM9-ESD3V3UA':
 ROOM='USB_REAR';

SECTION_NUMBER 1
 '@BASEBOARD_FAB2_LIB.BASEBOARD_FAB2(SCH_1):PAGE253_I5@MSTR_DISCRETE.DIODEAC_DUAL_ARRAY(CHIPS)':
 C_PATH='@baseboard_fab2_lib.baseboard_fab2(sch_1):page253_i5@mstr_discrete.diod~
eac_dual_array(chips)',
 P_PATH='@baseboard_fab2_lib.baseboard_fab2(sch_1):page253_i5@mstr_discrete.diod~
eac_dual_array(chips)',
 PATH='I5',
 DRAWING='@BASEBOARD_FAB2_LIB.BASEBOARD_FAB2(SCH_1):PAGE253',
 SEC_TYPE='SM9',
 MATERIAL='IC',
 BOM_COST='MIO_USB',
 PHYS_PAGE='253',
 XY='(-3300,2300)',
 ROT='0',
 VER='7',
 VALUE='ESD3V3U4ULC',
 PACK_TYPE='SM9',
 PART_NUMBER='G18435-001',
 LOCATION='CR30W1',
 ROOM='USB_REAR',
 SEC='1',
 CDS_LIB='mstr_discrete',
 CDS_PART_NAME='DIODEAC_DUAL_ARRAY_SM9-ESD3V3UA',
 PRIM_FILE='./archive_libs/mstr_discrete/diodeac_dual_array/chips/chips.prt';

PART_NAME
 CT1 'CAP_A_0402V-0.1UF,16V,10%,X7R,A':
 ROOM='PVCCIN_CPU0_PWR_VR';

SECTION_NUMBER 1
 '@BASEBOARD_FAB2_LIB.BASEBOARD_FAB2(SCH_1):PAGE202_I70@DEV_DISCRETE.CAP_A(CHIPS)':
 C_PATH='@baseboard_fab2_lib.baseboard_fab2(sch_1):page202_i70@dev_discrete.cap_~
a(chips)',
 P_PATH='@baseboard_fab2_lib.baseboard_fab2(sch_1):page202_i70@dev_discrete.cap_~
a(chips)',
 PATH='I70',
 DRAWING='@BASEBOARD_FAB2_LIB.BASEBOARD_FAB2(SCH_1):PAGE202',
 POP='NOPOP',
 TOLERANCE='10%',
 SEC_TYPE='0402V',
 MATERIAL='X7R',
 PHYS_PAGE='202',
 XY='(-4125,3300)',
 ROT='0',
 VER='1',
 VALUE='0.1UF',
 PACK_TYPE='0402V',
 PART_NUMBER='A36096-030',
 LOCATION='CT1',
 ROOM='PVCCIN_CPU0_PWR_VR',
 SEC='1',
 CDS_LIB='dev_discrete',
 CDS_PART_NAME='CAP_A_0402V-0.1UF,16V,10%,X7R,A',
 VOLTAGE='16V',
 PRIM_FILE='./archive_libs/discrete/cap_a/chips/chips.prt';

PART_NAME
 CT2 'CAP_0402LF-1000PF,50V,10%,X7R,A':
 ROOM='VDDQ_KLM_PWR_VR';

SECTION_NUMBER 1
 '@BASEBOARD_FAB2_LIB.BASEBOARD_FAB2(SCH_1):PAGE202_I78@MSTR_DISCRETE.CAP(CHIPS)':
 C_PATH='@baseboard_fab2_lib.baseboard_fab2(sch_1):page202_i78@mstr_discrete.cap~
(chips)',
 P_PATH='@baseboard_fab2_lib.baseboard_fab2(sch_1):page202_i78@mstr_discrete.cap~
(chips)',
 PATH='I78',
 DRAWING='@BASEBOARD_FAB2_LIB.BASEBOARD_FAB2(SCH_1):PAGE202',
 POP='NOPOP',
 TOLERANCE='10%',
 SEC_TYPE='0402LF',
 MATERIAL='X7R',
 PHYS_PAGE='202',
 XY='(-2350,3875)',
 ROT='0',
 VER='1',
 VALUE='1000PF',
 PACK_TYPE='0402LF',
 PART_NUMBER='A36096-046',
 LOCATION='CT2',
 ROOM='VDDQ_KLM_PWR_VR',
 SEC='1',
 CDS_LIB='mstr_discrete',
 CDS_PART_NAME='CAP_0402LF-1000PF,50V,10%,X7R,A',
 VOLTAGE='50V',
 PRIM_FILE='./archive_libs/mstr_discrete/cap/chips/chips.prt';

PART_NAME
 CT3 'CAP_0402LF-1000PF,50V,10%,X7R,A':
 ROOM='VDDQ_KLM_PWR_VR';

SECTION_NUMBER 1
 '@BASEBOARD_FAB2_LIB.BASEBOARD_FAB2(SCH_1):PAGE202_I97@MSTR_DISCRETE.CAP(CHIPS)':
 C_PATH='@baseboard_fab2_lib.baseboard_fab2(sch_1):page202_i97@mstr_discrete.cap~
(chips)',
 P_PATH='@baseboard_fab2_lib.baseboard_fab2(sch_1):page202_i97@mstr_discrete.cap~
(chips)',
 PATH='I97',
 DRAWING='@BASEBOARD_FAB2_LIB.BASEBOARD_FAB2(SCH_1):PAGE202',
 POP='NOPOP',
 TOLERANCE='10%',
 SEC_TYPE='0402LF',
 MATERIAL='X7R',
 PHYS_PAGE='202',
 XY='(-2550,3325)',
 ROT='0',
 VER='1',
 VALUE='1000PF',
 PACK_TYPE='0402LF',
 PART_NUMBER='A36096-046',
 LOCATION='CT3',
 ROOM='VDDQ_KLM_PWR_VR',
 SEC='1',
 CDS_LIB='mstr_discrete',
 CDS_PART_NAME='CAP_0402LF-1000PF,50V,10%,X7R,A',
 VOLTAGE='50V',
 PRIM_FILE='./archive_libs/mstr_discrete/cap/chips/chips.prt';

PART_NAME
 CT4 'CAP_0402LF-1000PF,50V,10%,X7R,A':
 ROOM='VDDQ_KLM_PWR_VR';

SECTION_NUMBER 1
 '@BASEBOARD_FAB2_LIB.BASEBOARD_FAB2(SCH_1):PAGE202_I87@MSTR_DISCRETE.CAP(CHIPS)':
 C_PATH='@baseboard_fab2_lib.baseboard_fab2(sch_1):page202_i87@mstr_discrete.cap~
(chips)',
 P_PATH='@baseboard_fab2_lib.baseboard_fab2(sch_1):page202_i87@mstr_discrete.cap~
(chips)',
 PATH='I87',
 DRAWING='@BASEBOARD_FAB2_LIB.BASEBOARD_FAB2(SCH_1):PAGE202',
 POP='NOPOP',
 TOLERANCE='10%',
 SEC_TYPE='0402LF',
 MATERIAL='X7R',
 PHYS_PAGE='202',
 XY='(-2450,1250)',
 ROT='0',
 VER='1',
 VALUE='1000PF',
 PACK_TYPE='0402LF',
 PART_NUMBER='A36096-046',
 LOCATION='CT4',
 ROOM='VDDQ_KLM_PWR_VR',
 SEC='1',
 CDS_LIB='mstr_discrete',
 CDS_PART_NAME='CAP_0402LF-1000PF,50V,10%,X7R,A',
 VOLTAGE='50V',
 PRIM_FILE='./archive_libs/mstr_discrete/cap/chips/chips.prt';

PART_NAME
 CT5 'CAP_0402LF-1000PF,50V,10%,X7R,A':
 ROOM='VDDQ_KLM_PWR_VR';

SECTION_NUMBER 1
 '@BASEBOARD_FAB2_LIB.BASEBOARD_FAB2(SCH_1):PAGE202_I98@MSTR_DISCRETE.CAP(CHIPS)':
 C_PATH='@baseboard_fab2_lib.baseboard_fab2(sch_1):page202_i98@mstr_discrete.cap~
(chips)',
 P_PATH='@baseboard_fab2_lib.baseboard_fab2(sch_1):page202_i98@mstr_discrete.cap~
(chips)',
 PATH='I98',
 DRAWING='@BASEBOARD_FAB2_LIB.BASEBOARD_FAB2(SCH_1):PAGE202',
 POP='NOPOP',
 TOLERANCE='10%',
 SEC_TYPE='0402LF',
 MATERIAL='X7R',
 PHYS_PAGE='202',
 XY='(-2550,825)',
 ROT='0',
 VER='1',
 VALUE='1000PF',
 PACK_TYPE='0402LF',
 PART_NUMBER='A36096-046',
 LOCATION='CT5',
 ROOM='VDDQ_KLM_PWR_VR',
 SEC='1',
 CDS_LIB='mstr_discrete',
 CDS_PART_NAME='CAP_0402LF-1000PF,50V,10%,X7R,A',
 VOLTAGE='50V',
 PRIM_FILE='./archive_libs/mstr_discrete/cap/chips/chips.prt';

PART_NAME
 CT6 'CAP_A_0402V-0.1UF,16V,10%,X7R,A':
 ROOM='PVCCIN_CPU0_PWR_VR';

SECTION_NUMBER 1
 '@BASEBOARD_FAB2_LIB.BASEBOARD_FAB2(SCH_1):PAGE202_I81@DEV_DISCRETE.CAP_A(CHIPS)':
 C_PATH='@baseboard_fab2_lib.baseboard_fab2(sch_1):page202_i81@dev_discrete.cap_~
a(chips)',
 P_PATH='@baseboard_fab2_lib.baseboard_fab2(sch_1):page202_i81@dev_discrete.cap_~
a(chips)',
 PATH='I81',
 DRAWING='@BASEBOARD_FAB2_LIB.BASEBOARD_FAB2(SCH_1):PAGE202',
 POP='NOPOP',
 TOLERANCE='10%',
 SEC_TYPE='0402V',
 MATERIAL='X7R',
 PHYS_PAGE='202',
 XY='(-4175,675)',
 ROT='0',
 VER='1',
 VALUE='0.1UF',
 PACK_TYPE='0402V',
 PART_NUMBER='A36096-030',
 LOCATION='CT6',
 ROOM='PVCCIN_CPU0_PWR_VR',
 SEC='1',
 CDS_LIB='dev_discrete',
 CDS_PART_NAME='CAP_A_0402V-0.1UF,16V,10%,X7R,A',
 VOLTAGE='16V',
 PRIM_FILE='./archive_libs/discrete/cap_a/chips/chips.prt';

PART_NAME
 CT7 'CAP_A_0402V-0.1UF,16V,10%,X7R,A':
 ROOM='PVCCIN_CPU0_PWR_VR';

SECTION_NUMBER 1
 '@BASEBOARD_FAB2_LIB.BASEBOARD_FAB2(SCH_1):PAGE227_I109@DEV_DISCRETE.CAP_A(CHIPS)':
 C_PATH='@baseboard_fab2_lib.baseboard_fab2(sch_1):page227_i109@dev_discrete.cap~
_a(chips)',
 P_PATH='@baseboard_fab2_lib.baseboard_fab2(sch_1):page227_i109@dev_discrete.cap~
_a(chips)',
 PATH='I109',
 DRAWING='@BASEBOARD_FAB2_LIB.BASEBOARD_FAB2(SCH_1):PAGE227',
 POP='NOPOP',
 TOLERANCE='10%',
 SEC_TYPE='0402V',
 MATERIAL='X7R',
 PHYS_PAGE='227',
 XY='(1150,1725)',
 ROT='0',
 VER='1',
 VALUE='0.1UF',
 PACK_TYPE='0402V',
 PART_NUMBER='A36096-030',
 LOCATION='CT7',
 ROOM='PVCCIN_CPU0_PWR_VR',
 SEC='1',
 CDS_LIB='dev_discrete',
 CDS_PART_NAME='CAP_A_0402V-0.1UF,16V,10%,X7R,A',
 VOLTAGE='16V',
 PRIM_FILE='./archive_libs/discrete/cap_a/chips/chips.prt';

PART_NAME
 CT8 'CAP_0402LF-1000PF,50V,10%,X7R,A':
 ROOM='VDDQ_KLM_PWR_VR';

SECTION_NUMBER 1
 '@BASEBOARD_FAB2_LIB.BASEBOARD_FAB2(SCH_1):PAGE227_I114@MSTR_DISCRETE.CAP(CHIPS)':
 C_PATH='@baseboard_fab2_lib.baseboard_fab2(sch_1):page227_i114@mstr_discrete.ca~
p(chips)',
 P_PATH='@baseboard_fab2_lib.baseboard_fab2(sch_1):page227_i114@mstr_discrete.ca~
p(chips)',
 PATH='I114',
 DRAWING='@BASEBOARD_FAB2_LIB.BASEBOARD_FAB2(SCH_1):PAGE227',
 POP='NOPOP',
 TOLERANCE='10%',
 SEC_TYPE='0402LF',
 MATERIAL='X7R',
 PHYS_PAGE='227',
 XY='(3050,2200)',
 ROT='0',
 VER='1',
 VALUE='1000PF',
 PACK_TYPE='0402LF',
 PART_NUMBER='A36096-046',
 LOCATION='CT8',
 ROOM='VDDQ_KLM_PWR_VR',
 SEC='1',
 CDS_LIB='mstr_discrete',
 CDS_PART_NAME='CAP_0402LF-1000PF,50V,10%,X7R,A',
 VOLTAGE='50V',
 PRIM_FILE='./archive_libs/mstr_discrete/cap/chips/chips.prt';

PART_NAME
 CT9 'CAP_0402LF-1000PF,50V,10%,X7R,A':
 ROOM='VDDQ_KLM_PWR_VR';

SECTION_NUMBER 1
 '@BASEBOARD_FAB2_LIB.BASEBOARD_FAB2(SCH_1):PAGE227_I134@MSTR_DISCRETE.CAP(CHIPS)':
 C_PATH='@baseboard_fab2_lib.baseboard_fab2(sch_1):page227_i134@mstr_discrete.ca~
p(chips)',
 P_PATH='@baseboard_fab2_lib.baseboard_fab2(sch_1):page227_i134@mstr_discrete.ca~
p(chips)',
 PATH='I134',
 DRAWING='@BASEBOARD_FAB2_LIB.BASEBOARD_FAB2(SCH_1):PAGE227',
 POP='NOPOP',
 TOLERANCE='10%',
 SEC_TYPE='0402LF',
 MATERIAL='X7R',
 PHYS_PAGE='227',
 XY='(2825,1750)',
 ROT='0',
 VER='1',
 VALUE='1000PF',
 PACK_TYPE='0402LF',
 PART_NUMBER='A36096-046',
 LOCATION='CT9',
 ROOM='VDDQ_KLM_PWR_VR',
 SEC='1',
 CDS_LIB='mstr_discrete',
 CDS_PART_NAME='CAP_0402LF-1000PF,50V,10%,X7R,A',
 VOLTAGE='50V',
 PRIM_FILE='./archive_libs/mstr_discrete/cap/chips/chips.prt';

PART_NAME
 CT10 'CAP_0402LF-1000PF,50V,10%,X7R,A':
 ROOM='VDDQ_KLM_PWR_VR';

SECTION_NUMBER 1
 '@BASEBOARD_FAB2_LIB.BASEBOARD_FAB2(SCH_1):PAGE227_I119@MSTR_DISCRETE.CAP(CHIPS)':
 C_PATH='@baseboard_fab2_lib.baseboard_fab2(sch_1):page227_i119@mstr_discrete.ca~
p(chips)',
 P_PATH='@baseboard_fab2_lib.baseboard_fab2(sch_1):page227_i119@mstr_discrete.ca~
p(chips)',
 PATH='I119',
 DRAWING='@BASEBOARD_FAB2_LIB.BASEBOARD_FAB2(SCH_1):PAGE227',
 BOM_SS='NOPOP',
 POP='NOPOP',
 TOLERANCE='10%',
 SEC_TYPE='0402LF',
 MATERIAL='X7R',
 PHYS_PAGE='227',
 XY='(2950,25)',
 ROT='0',
 VER='1',
 VALUE='1000PF',
 PACK_TYPE='0402LF',
 PART_NUMBER='A36096-046',
 LOCATION='CT10',
 ROOM='VDDQ_KLM_PWR_VR',
 SEC='1',
 CDS_LIB='mstr_discrete',
 CDS_PART_NAME='CAP_0402LF-1000PF,50V,10%,X7R,A',
 VOLTAGE='50V',
 PRIM_FILE='./archive_libs/mstr_discrete/cap/chips/chips.prt';

PART_NAME
 CT11 'CAP_0402LF-1000PF,50V,10%,X7R,A':
 ROOM='VDDQ_KLM_PWR_VR';

SECTION_NUMBER 1
 '@BASEBOARD_FAB2_LIB.BASEBOARD_FAB2(SCH_1):PAGE227_I135@MSTR_DISCRETE.CAP(CHIPS)':
 C_PATH='@baseboard_fab2_lib.baseboard_fab2(sch_1):page227_i135@mstr_discrete.ca~
p(chips)',
 P_PATH='@baseboard_fab2_lib.baseboard_fab2(sch_1):page227_i135@mstr_discrete.ca~
p(chips)',
 PATH='I135',
 DRAWING='@BASEBOARD_FAB2_LIB.BASEBOARD_FAB2(SCH_1):PAGE227',
 BOM_SS='NOPOP',
 POP='NOPOP',
 TOLERANCE='10%',
 SEC_TYPE='0402LF',
 MATERIAL='X7R',
 PHYS_PAGE='227',
 XY='(2925,-475)',
 ROT='0',
 VER='1',
 VALUE='1000PF',
 PACK_TYPE='0402LF',
 PART_NUMBER='A36096-046',
 LOCATION='CT11',
 ROOM='VDDQ_KLM_PWR_VR',
 SEC='1',
 CDS_LIB='mstr_discrete',
 CDS_PART_NAME='CAP_0402LF-1000PF,50V,10%,X7R,A',
 VOLTAGE='50V',
 PRIM_FILE='./archive_libs/mstr_discrete/cap/chips/chips.prt';

PART_NAME
 CT12 'CAP_A_0402V-0.1UF,16V,10%,X7R,A':
 ROOM='PVCCIN_CPU0_PWR_VR';

SECTION_NUMBER 1
 '@BASEBOARD_FAB2_LIB.BASEBOARD_FAB2(SCH_1):PAGE227_I122@DEV_DISCRETE.CAP_A(CHIPS)':
 C_PATH='@baseboard_fab2_lib.baseboard_fab2(sch_1):page227_i122@dev_discrete.cap~
_a(chips)',
 P_PATH='@baseboard_fab2_lib.baseboard_fab2(sch_1):page227_i122@dev_discrete.cap~
_a(chips)',
 PATH='I122',
 DRAWING='@BASEBOARD_FAB2_LIB.BASEBOARD_FAB2(SCH_1):PAGE227',
 BOM_SS='NOPOP',
 POP='NOPOP',
 TOLERANCE='10%',
 SEC_TYPE='0402V',
 MATERIAL='X7R',
 PHYS_PAGE='227',
 XY='(1150,-800)',
 ROT='0',
 VER='1',
 VALUE='0.1UF',
 PACK_TYPE='0402V',
 PART_NUMBER='A36096-030',
 LOCATION='CT12',
 ROOM='PVCCIN_CPU0_PWR_VR',
 SEC='1',
 CDS_LIB='dev_discrete',
 CDS_PART_NAME='CAP_A_0402V-0.1UF,16V,10%,X7R,A',
 VOLTAGE='16V',
 PRIM_FILE='./archive_libs/discrete/cap_a/chips/chips.prt';

PART_NAME
 CT13 'CAP_A_0402V-0.1UF,16V,10%,X7R,A':
 ROOM='PVCCIN_CPU0_PWR_VR';

SECTION_NUMBER 1
 '@BASEBOARD_FAB2_LIB.BASEBOARD_FAB2(SCH_1):PAGE209_I62@DEV_DISCRETE.CAP_A(CHIPS)':
 C_PATH='@baseboard_fab2_lib.baseboard_fab2(sch_1):page209_i62@dev_discrete.cap_~
a(chips)',
 P_PATH='@baseboard_fab2_lib.baseboard_fab2(sch_1):page209_i62@dev_discrete.cap_~
a(chips)',
 PATH='I62',
 DRAWING='@BASEBOARD_FAB2_LIB.BASEBOARD_FAB2(SCH_1):PAGE209',
 POP='NOPOP',
 TOLERANCE='10%',
 SEC_TYPE='0402V',
 MATERIAL='X7R',
 PHYS_PAGE='209',
 XY='(-3950,3275)',
 ROT='0',
 VER='1',
 VALUE='0.1UF',
 PACK_TYPE='0402V',
 PART_NUMBER='A36096-030',
 LOCATION='CT13',
 ROOM='PVCCIN_CPU0_PWR_VR',
 SEC='1',
 CDS_LIB='dev_discrete',
 CDS_PART_NAME='CAP_A_0402V-0.1UF,16V,10%,X7R,A',
 VOLTAGE='16V',
 PRIM_FILE='./archive_libs/discrete/cap_a/chips/chips.prt';

PART_NAME
 CT14 'CAP_0402LF-1000PF,50V,10%,X7R,A':
 ROOM='VDDQ_KLM_PWR_VR';

SECTION_NUMBER 1
 '@BASEBOARD_FAB2_LIB.BASEBOARD_FAB2(SCH_1):PAGE209_I73@MSTR_DISCRETE.CAP(CHIPS)':
 C_PATH='@baseboard_fab2_lib.baseboard_fab2(sch_1):page209_i73@mstr_discrete.cap~
(chips)',
 P_PATH='@baseboard_fab2_lib.baseboard_fab2(sch_1):page209_i73@mstr_discrete.cap~
(chips)',
 PATH='I73',
 DRAWING='@BASEBOARD_FAB2_LIB.BASEBOARD_FAB2(SCH_1):PAGE209',
 POP='NOPOP',
 TOLERANCE='10%',
 SEC_TYPE='0402LF',
 MATERIAL='X7R',
 PHYS_PAGE='209',
 XY='(-2400,3300)',
 ROT='0',
 VER='1',
 VALUE='1000PF',
 PACK_TYPE='0402LF',
 PART_NUMBER='A36096-046',
 LOCATION='CT14',
 ROOM='VDDQ_KLM_PWR_VR',
 SEC='1',
 CDS_LIB='mstr_discrete',
 CDS_PART_NAME='CAP_0402LF-1000PF,50V,10%,X7R,A',
 VOLTAGE='50V',
 PRIM_FILE='./archive_libs/mstr_discrete/cap/chips/chips.prt';

PART_NAME
 CT15 'CAP_0402LF-1000PF,50V,10%,X7R,A':
 ROOM='VDDQ_KLM_PWR_VR';

SECTION_NUMBER 1
 '@BASEBOARD_FAB2_LIB.BASEBOARD_FAB2(SCH_1):PAGE209_I67@MSTR_DISCRETE.CAP(CHIPS)':
 C_PATH='@baseboard_fab2_lib.baseboard_fab2(sch_1):page209_i67@mstr_discrete.cap~
(chips)',
 P_PATH='@baseboard_fab2_lib.baseboard_fab2(sch_1):page209_i67@mstr_discrete.cap~
(chips)',
 PATH='I67',
 DRAWING='@BASEBOARD_FAB2_LIB.BASEBOARD_FAB2(SCH_1):PAGE209',
 POP='NOPOP',
 TOLERANCE='10%',
 SEC_TYPE='0402LF',
 MATERIAL='X7R',
 PHYS_PAGE='209',
 XY='(-1950,3825)',
 ROT='0',
 VER='1',
 VALUE='1000PF',
 PACK_TYPE='0402LF',
 PART_NUMBER='A36096-046',
 LOCATION='CT15',
 ROOM='VDDQ_KLM_PWR_VR',
 SEC='1',
 CDS_LIB='mstr_discrete',
 CDS_PART_NAME='CAP_0402LF-1000PF,50V,10%,X7R,A',
 VOLTAGE='50V',
 PRIM_FILE='./archive_libs/mstr_discrete/cap/chips/chips.prt';

PART_NAME
 CT16 'CAP_A_0402V-0.1UF,16V,10%,X7R,A':
 ROOM='PVCCIN_CPU0_PWR_VR';

SECTION_NUMBER 1
 '@BASEBOARD_FAB2_LIB.BASEBOARD_FAB2(SCH_1):PAGE208_I80@DEV_DISCRETE.CAP_A(CHIPS)':
 C_PATH='@baseboard_fab2_lib.baseboard_fab2(sch_1):page208_i80@dev_discrete.cap_~
a(chips)',
 P_PATH='@baseboard_fab2_lib.baseboard_fab2(sch_1):page208_i80@dev_discrete.cap_~
a(chips)',
 PATH='I80',
 DRAWING='@BASEBOARD_FAB2_LIB.BASEBOARD_FAB2(SCH_1):PAGE208',
 POP='NOPOP',
 TOLERANCE='10%',
 SEC_TYPE='0402V',
 MATERIAL='X7R',
 PHYS_PAGE='208',
 XY='(-3975,3375)',
 ROT='0',
 VER='1',
 VALUE='0.1UF',
 PACK_TYPE='0402V',
 PART_NUMBER='A36096-030',
 LOCATION='CT16',
 ROOM='PVCCIN_CPU0_PWR_VR',
 SEC='1',
 CDS_LIB='dev_discrete',
 CDS_PART_NAME='CAP_A_0402V-0.1UF,16V,10%,X7R,A',
 VOLTAGE='16V',
 PRIM_FILE='./archive_libs/discrete/cap_a/chips/chips.prt';

PART_NAME
 CT18 'CAP_0402LF-1000PF,50V,10%,X7R,A':
 ROOM='VDDQ_KLM_PWR_VR';

SECTION_NUMBER 1
 '@BASEBOARD_FAB2_LIB.BASEBOARD_FAB2(SCH_1):PAGE208_I104@MSTR_DISCRETE.CAP(CHIPS)':
 C_PATH='@baseboard_fab2_lib.baseboard_fab2(sch_1):page208_i104@mstr_discrete.ca~
p(chips)',
 P_PATH='@baseboard_fab2_lib.baseboard_fab2(sch_1):page208_i104@mstr_discrete.ca~
p(chips)',
 PATH='I104',
 DRAWING='@BASEBOARD_FAB2_LIB.BASEBOARD_FAB2(SCH_1):PAGE208',
 POP='NOPOP',
 TOLERANCE='10%',
 SEC_TYPE='0402LF',
 MATERIAL='X7R',
 PHYS_PAGE='208',
 XY='(-2225,3500)',
 ROT='0',
 VER='1',
 VALUE='1000PF',
 PACK_TYPE='0402LF',
 PART_NUMBER='A36096-046',
 LOCATION='CT18',
 ROOM='VDDQ_KLM_PWR_VR',
 SEC='1',
 CDS_LIB='mstr_discrete',
 CDS_PART_NAME='CAP_0402LF-1000PF,50V,10%,X7R,A',
 VOLTAGE='50V',
 PRIM_FILE='./archive_libs/mstr_discrete/cap/chips/chips.prt';

PART_NAME
 CT19 'CAP_0402LF-1000PF,50V,10%,X7R,A':
 ROOM='VDDQ_KLM_PWR_VR';

SECTION_NUMBER 1
 '@BASEBOARD_FAB2_LIB.BASEBOARD_FAB2(SCH_1):PAGE208_I90@MSTR_DISCRETE.CAP(CHIPS)':
 C_PATH='@baseboard_fab2_lib.baseboard_fab2(sch_1):page208_i90@mstr_discrete.cap~
(chips)',
 P_PATH='@baseboard_fab2_lib.baseboard_fab2(sch_1):page208_i90@mstr_discrete.cap~
(chips)',
 PATH='I90',
 DRAWING='@BASEBOARD_FAB2_LIB.BASEBOARD_FAB2(SCH_1):PAGE208',
 POP='NOPOP',
 TOLERANCE='10%',
 SEC_TYPE='0402LF',
 MATERIAL='X7R',
 PHYS_PAGE='208',
 XY='(-2000,1300)',
 ROT='0',
 VER='1',
 VALUE='1000PF',
 PACK_TYPE='0402LF',
 PART_NUMBER='A36096-046',
 LOCATION='CT19',
 ROOM='VDDQ_KLM_PWR_VR',
 SEC='1',
 CDS_LIB='mstr_discrete',
 CDS_PART_NAME='CAP_0402LF-1000PF,50V,10%,X7R,A',
 VOLTAGE='50V',
 PRIM_FILE='./archive_libs/mstr_discrete/cap/chips/chips.prt';

PART_NAME
 CT20 'CAP_0402LF-1000PF,50V,10%,X7R,A':
 ROOM='VDDQ_KLM_PWR_VR';

SECTION_NUMBER 1
 '@BASEBOARD_FAB2_LIB.BASEBOARD_FAB2(SCH_1):PAGE208_I105@MSTR_DISCRETE.CAP(CHIPS)':
 C_PATH='@baseboard_fab2_lib.baseboard_fab2(sch_1):page208_i105@mstr_discrete.ca~
p(chips)',
 P_PATH='@baseboard_fab2_lib.baseboard_fab2(sch_1):page208_i105@mstr_discrete.ca~
p(chips)',
 PATH='I105',
 DRAWING='@BASEBOARD_FAB2_LIB.BASEBOARD_FAB2(SCH_1):PAGE208',
 POP='NOPOP',
 TOLERANCE='10%',
 SEC_TYPE='0402LF',
 MATERIAL='X7R',
 PHYS_PAGE='208',
 XY='(-2075,875)',
 ROT='0',
 VER='1',
 VALUE='1000PF',
 PACK_TYPE='0402LF',
 PART_NUMBER='A36096-046',
 LOCATION='CT20',
 ROOM='VDDQ_KLM_PWR_VR',
 SEC='1',
 CDS_LIB='mstr_discrete',
 CDS_PART_NAME='CAP_0402LF-1000PF,50V,10%,X7R,A',
 VOLTAGE='50V',
 PRIM_FILE='./archive_libs/mstr_discrete/cap/chips/chips.prt';

PART_NAME
 CT21 'CAP_A_0402V-0.1UF,16V,10%,X7R,A':
 ROOM='PVCCIN_CPU0_PWR_VR';

SECTION_NUMBER 1
 '@BASEBOARD_FAB2_LIB.BASEBOARD_FAB2(SCH_1):PAGE208_I87@DEV_DISCRETE.CAP_A(CHIPS)':
 C_PATH='@baseboard_fab2_lib.baseboard_fab2(sch_1):page208_i87@dev_discrete.cap_~
a(chips)',
 P_PATH='@baseboard_fab2_lib.baseboard_fab2(sch_1):page208_i87@dev_discrete.cap_~
a(chips)',
 PATH='I87',
 DRAWING='@BASEBOARD_FAB2_LIB.BASEBOARD_FAB2(SCH_1):PAGE208',
 POP='NOPOP',
 TOLERANCE='10%',
 SEC_TYPE='0402V',
 MATERIAL='X7R',
 PHYS_PAGE='208',
 XY='(-3850,775)',
 ROT='0',
 VER='1',
 VALUE='0.1UF',
 PACK_TYPE='0402V',
 PART_NUMBER='A36096-030',
 LOCATION='CT21',
 ROOM='PVCCIN_CPU0_PWR_VR',
 SEC='1',
 CDS_LIB='dev_discrete',
 CDS_PART_NAME='CAP_A_0402V-0.1UF,16V,10%,X7R,A',
 VOLTAGE='16V',
 PRIM_FILE='./archive_libs/discrete/cap_a/chips/chips.prt';

PART_NAME
 CT22 'CAP_0402LF-1000PF,50V,10%,X7R,A':
 ROOM='VDDQ_KLM_PWR_VR';

SECTION_NUMBER 1
 '@BASEBOARD_FAB2_LIB.BASEBOARD_FAB2(SCH_1):PAGE207_I74@MSTR_DISCRETE.CAP(CHIPS)':
 C_PATH='@baseboard_fab2_lib.baseboard_fab2(sch_1):page207_i74@mstr_discrete.cap~
(chips)',
 P_PATH='@baseboard_fab2_lib.baseboard_fab2(sch_1):page207_i74@mstr_discrete.cap~
(chips)',
 PATH='I74',
 DRAWING='@BASEBOARD_FAB2_LIB.BASEBOARD_FAB2(SCH_1):PAGE207',
 POP='NOPOP',
 TOLERANCE='10%',
 SEC_TYPE='0402LF',
 MATERIAL='X7R',
 PHYS_PAGE='207',
 XY='(-2125,3850)',
 ROT='0',
 VER='1',
 VALUE='1000PF',
 PACK_TYPE='0402LF',
 PART_NUMBER='A36096-046',
 LOCATION='CT22',
 ROOM='VDDQ_KLM_PWR_VR',
 SEC='1',
 CDS_LIB='mstr_discrete',
 CDS_PART_NAME='CAP_0402LF-1000PF,50V,10%,X7R,A',
 VOLTAGE='50V',
 PRIM_FILE='./archive_libs/mstr_discrete/cap/chips/chips.prt';

PART_NAME
 CT23 'CAP_0402LF-1000PF,50V,10%,X7R,A':
 ROOM='VDDQ_KLM_PWR_VR';

SECTION_NUMBER 1
 '@BASEBOARD_FAB2_LIB.BASEBOARD_FAB2(SCH_1):PAGE207_I95@MSTR_DISCRETE.CAP(CHIPS)':
 C_PATH='@baseboard_fab2_lib.baseboard_fab2(sch_1):page207_i95@mstr_discrete.cap~
(chips)',
 P_PATH='@baseboard_fab2_lib.baseboard_fab2(sch_1):page207_i95@mstr_discrete.cap~
(chips)',
 PATH='I95',
 DRAWING='@BASEBOARD_FAB2_LIB.BASEBOARD_FAB2(SCH_1):PAGE207',
 POP='NOPOP',
 TOLERANCE='10%',
 SEC_TYPE='0402LF',
 MATERIAL='X7R',
 PHYS_PAGE='207',
 XY='(-2225,3400)',
 ROT='0',
 VER='1',
 VALUE='1000PF',
 PACK_TYPE='0402LF',
 PART_NUMBER='A36096-046',
 LOCATION='CT23',
 ROOM='VDDQ_KLM_PWR_VR',
 SEC='1',
 CDS_LIB='mstr_discrete',
 CDS_PART_NAME='CAP_0402LF-1000PF,50V,10%,X7R,A',
 VOLTAGE='50V',
 PRIM_FILE='./archive_libs/mstr_discrete/cap/chips/chips.prt';

PART_NAME
 CT24 'CAP_A_0402V-0.1UF,16V,10%,X7R,A':
 ROOM='PVCCIN_CPU0_PWR_VR';

SECTION_NUMBER 1
 '@BASEBOARD_FAB2_LIB.BASEBOARD_FAB2(SCH_1):PAGE207_I71@DEV_DISCRETE.CAP_A(CHIPS)':
 C_PATH='@baseboard_fab2_lib.baseboard_fab2(sch_1):page207_i71@dev_discrete.cap_~
a(chips)',
 P_PATH='@baseboard_fab2_lib.baseboard_fab2(sch_1):page207_i71@dev_discrete.cap_~
a(chips)',
 PATH='I71',
 DRAWING='@BASEBOARD_FAB2_LIB.BASEBOARD_FAB2(SCH_1):PAGE207',
 POP='NOPOP',
 TOLERANCE='10%',
 SEC_TYPE='0402V',
 MATERIAL='X7R',
 PHYS_PAGE='207',
 XY='(-3850,3350)',
 ROT='0',
 VER='1',
 VALUE='0.1UF',
 PACK_TYPE='0402V',
 PART_NUMBER='A36096-030',
 LOCATION='CT24',
 ROOM='PVCCIN_CPU0_PWR_VR',
 SEC='1',
 CDS_LIB='dev_discrete',
 CDS_PART_NAME='CAP_A_0402V-0.1UF,16V,10%,X7R,A',
 VOLTAGE='16V',
 PRIM_FILE='./archive_libs/discrete/cap_a/chips/chips.prt';

PART_NAME
 CT25 'CAP_A_0402V-0.1UF,16V,10%,X7R,A':
 ROOM='PVCCIN_CPU0_PWR_VR';

SECTION_NUMBER 1
 '@BASEBOARD_FAB2_LIB.BASEBOARD_FAB2(SCH_1):PAGE207_I81@DEV_DISCRETE.CAP_A(CHIPS)':
 C_PATH='@baseboard_fab2_lib.baseboard_fab2(sch_1):page207_i81@dev_discrete.cap_~
a(chips)',
 P_PATH='@baseboard_fab2_lib.baseboard_fab2(sch_1):page207_i81@dev_discrete.cap_~
a(chips)',
 PATH='I81',
 DRAWING='@BASEBOARD_FAB2_LIB.BASEBOARD_FAB2(SCH_1):PAGE207',
 POP='NOPOP',
 TOLERANCE='10%',
 SEC_TYPE='0402V',
 MATERIAL='X7R',
 PHYS_PAGE='207',
 XY='(-3825,750)',
 ROT='0',
 VER='1',
 VALUE='0.1UF',
 PACK_TYPE='0402V',
 PART_NUMBER='A36096-030',
 LOCATION='CT25',
 ROOM='PVCCIN_CPU0_PWR_VR',
 SEC='1',
 CDS_LIB='dev_discrete',
 CDS_PART_NAME='CAP_A_0402V-0.1UF,16V,10%,X7R,A',
 VOLTAGE='16V',
 PRIM_FILE='./archive_libs/discrete/cap_a/chips/chips.prt';

PART_NAME
 CT26 'CAP_0402LF-1000PF,50V,10%,X7R,A':
 ROOM='VDDQ_KLM_PWR_VR';

SECTION_NUMBER 1
 '@BASEBOARD_FAB2_LIB.BASEBOARD_FAB2(SCH_1):PAGE207_I82@MSTR_DISCRETE.CAP(CHIPS)':
 C_PATH='@baseboard_fab2_lib.baseboard_fab2(sch_1):page207_i82@mstr_discrete.cap~
(chips)',
 P_PATH='@baseboard_fab2_lib.baseboard_fab2(sch_1):page207_i82@mstr_discrete.cap~
(chips)',
 PATH='I82',
 DRAWING='@BASEBOARD_FAB2_LIB.BASEBOARD_FAB2(SCH_1):PAGE207',
 POP='NOPOP',
 TOLERANCE='10%',
 SEC_TYPE='0402LF',
 MATERIAL='X7R',
 PHYS_PAGE='207',
 XY='(-2075,1250)',
 ROT='0',
 VER='1',
 VALUE='1000PF',
 PACK_TYPE='0402LF',
 PART_NUMBER='A36096-046',
 LOCATION='CT26',
 ROOM='VDDQ_KLM_PWR_VR',
 SEC='1',
 CDS_LIB='mstr_discrete',
 CDS_PART_NAME='CAP_0402LF-1000PF,50V,10%,X7R,A',
 VOLTAGE='50V',
 PRIM_FILE='./archive_libs/mstr_discrete/cap/chips/chips.prt';

PART_NAME
 CT27 'CAP_0402LF-1000PF,50V,10%,X7R,A':
 ROOM='VDDQ_KLM_PWR_VR';

SECTION_NUMBER 1
 '@BASEBOARD_FAB2_LIB.BASEBOARD_FAB2(SCH_1):PAGE207_I96@MSTR_DISCRETE.CAP(CHIPS)':
 C_PATH='@baseboard_fab2_lib.baseboard_fab2(sch_1):page207_i96@mstr_discrete.cap~
(chips)',
 P_PATH='@baseboard_fab2_lib.baseboard_fab2(sch_1):page207_i96@mstr_discrete.cap~
(chips)',
 PATH='I96',
 DRAWING='@BASEBOARD_FAB2_LIB.BASEBOARD_FAB2(SCH_1):PAGE207',
 POP='NOPOP',
 TOLERANCE='10%',
 SEC_TYPE='0402LF',
 MATERIAL='X7R',
 PHYS_PAGE='207',
 XY='(-1925,825)',
 ROT='0',
 VER='1',
 VALUE='1000PF',
 PACK_TYPE='0402LF',
 PART_NUMBER='A36096-046',
 LOCATION='CT27',
 ROOM='VDDQ_KLM_PWR_VR',
 SEC='1',
 CDS_LIB='mstr_discrete',
 CDS_PART_NAME='CAP_0402LF-1000PF,50V,10%,X7R,A',
 VOLTAGE='50V',
 PRIM_FILE='./archive_libs/mstr_discrete/cap/chips/chips.prt';

PART_NAME
 CT28 'CAP_0402LF-1000PF,50V,10%,X7R,A':
 ROOM='VDDQ_KLM_PWR_VR';

SECTION_NUMBER 1
 '@BASEBOARD_FAB2_LIB.BASEBOARD_FAB2(SCH_1):PAGE224_I122@MSTR_DISCRETE.CAP(CHIPS)':
 C_PATH='@baseboard_fab2_lib.baseboard_fab2(sch_1):page224_i122@mstr_discrete.ca~
p(chips)',
 P_PATH='@baseboard_fab2_lib.baseboard_fab2(sch_1):page224_i122@mstr_discrete.ca~
p(chips)',
 PATH='I122',
 DRAWING='@BASEBOARD_FAB2_LIB.BASEBOARD_FAB2(SCH_1):PAGE224',
 POP='NOPOP',
 TOLERANCE='10%',
 SEC_TYPE='0402LF',
 MATERIAL='X7R',
 PHYS_PAGE='224',
 XY='(2950,2225)',
 ROT='0',
 VER='1',
 VALUE='1000PF',
 PACK_TYPE='0402LF',
 PART_NUMBER='A36096-046',
 LOCATION='CT28',
 ROOM='VDDQ_KLM_PWR_VR',
 SEC='1',
 CDS_LIB='mstr_discrete',
 CDS_PART_NAME='CAP_0402LF-1000PF,50V,10%,X7R,A',
 VOLTAGE='50V',
 PRIM_FILE='./archive_libs/mstr_discrete/cap/chips/chips.prt';

PART_NAME
 CT29 'CAP_0402LF-1000PF,50V,10%,X7R,A':
 ROOM='VDDQ_KLM_PWR_VR';

SECTION_NUMBER 1
 '@BASEBOARD_FAB2_LIB.BASEBOARD_FAB2(SCH_1):PAGE224_I140@MSTR_DISCRETE.CAP(CHIPS)':
 C_PATH='@baseboard_fab2_lib.baseboard_fab2(sch_1):page224_i140@mstr_discrete.ca~
p(chips)',
 P_PATH='@baseboard_fab2_lib.baseboard_fab2(sch_1):page224_i140@mstr_discrete.ca~
p(chips)',
 PATH='I140',
 DRAWING='@BASEBOARD_FAB2_LIB.BASEBOARD_FAB2(SCH_1):PAGE224',
 POP='NOPOP',
 TOLERANCE='10%',
 SEC_TYPE='0402LF',
 MATERIAL='X7R',
 PHYS_PAGE='224',
 XY='(2900,1800)',
 ROT='0',
 VER='1',
 VALUE='1000PF',
 PACK_TYPE='0402LF',
 PART_NUMBER='A36096-046',
 LOCATION='CT29',
 ROOM='VDDQ_KLM_PWR_VR',
 SEC='1',
 CDS_LIB='mstr_discrete',
 CDS_PART_NAME='CAP_0402LF-1000PF,50V,10%,X7R,A',
 VOLTAGE='50V',
 PRIM_FILE='./archive_libs/mstr_discrete/cap/chips/chips.prt';

PART_NAME
 CT30 'CAP_A_0402V-0.1UF,16V,10%,X7R,A':
 ROOM='PVCCIN_CPU0_PWR_VR';

SECTION_NUMBER 1
 '@BASEBOARD_FAB2_LIB.BASEBOARD_FAB2(SCH_1):PAGE224_I117@DEV_DISCRETE.CAP_A(CHIPS)':
 C_PATH='@baseboard_fab2_lib.baseboard_fab2(sch_1):page224_i117@dev_discrete.cap~
_a(chips)',
 P_PATH='@baseboard_fab2_lib.baseboard_fab2(sch_1):page224_i117@dev_discrete.cap~
_a(chips)',
 PATH='I117',
 DRAWING='@BASEBOARD_FAB2_LIB.BASEBOARD_FAB2(SCH_1):PAGE224',
 POP='NOPOP',
 TOLERANCE='10%',
 SEC_TYPE='0402V',
 MATERIAL='X7R',
 PHYS_PAGE='224',
 XY='(1050,1725)',
 ROT='0',
 VER='1',
 VALUE='0.1UF',
 PACK_TYPE='0402V',
 PART_NUMBER='A36096-030',
 LOCATION='CT30',
 ROOM='PVCCIN_CPU0_PWR_VR',
 SEC='1',
 CDS_LIB='dev_discrete',
 CDS_PART_NAME='CAP_A_0402V-0.1UF,16V,10%,X7R,A',
 VOLTAGE='16V',
 PRIM_FILE='./archive_libs/discrete/cap_a/chips/chips.prt';

PART_NAME
 CT31 'CAP_A_0402V-0.1UF,16V,10%,X7R,A':
 ROOM='PVCCIN_CPU0_PWR_VR';

SECTION_NUMBER 1
 '@BASEBOARD_FAB2_LIB.BASEBOARD_FAB2(SCH_1):PAGE224_I124@DEV_DISCRETE.CAP_A(CHIPS)':
 C_PATH='@baseboard_fab2_lib.baseboard_fab2(sch_1):page224_i124@dev_discrete.cap~
_a(chips)',
 P_PATH='@baseboard_fab2_lib.baseboard_fab2(sch_1):page224_i124@dev_discrete.cap~
_a(chips)',
 PATH='I124',
 DRAWING='@BASEBOARD_FAB2_LIB.BASEBOARD_FAB2(SCH_1):PAGE224',
 BOM_SS='NOPOP',
 POP='NOPOP',
 TOLERANCE='10%',
 SEC_TYPE='0402V',
 MATERIAL='X7R',
 PHYS_PAGE='224',
 XY='(1150,-625)',
 ROT='0',
 VER='1',
 VALUE='0.1UF',
 PACK_TYPE='0402V',
 PART_NUMBER='A36096-030',
 LOCATION='CT31',
 ROOM='PVCCIN_CPU0_PWR_VR',
 SEC='1',
 CDS_LIB='dev_discrete',
 CDS_PART_NAME='CAP_A_0402V-0.1UF,16V,10%,X7R,A',
 VOLTAGE='16V',
 PRIM_FILE='./archive_libs/discrete/cap_a/chips/chips.prt';

PART_NAME
 CT32 'CAP_0402LF-1000PF,50V,10%,X7R,A':
 ROOM='VDDQ_KLM_PWR_VR';

SECTION_NUMBER 1
 '@BASEBOARD_FAB2_LIB.BASEBOARD_FAB2(SCH_1):PAGE224_I130@MSTR_DISCRETE.CAP(CHIPS)':
 C_PATH='@baseboard_fab2_lib.baseboard_fab2(sch_1):page224_i130@mstr_discrete.ca~
p(chips)',
 P_PATH='@baseboard_fab2_lib.baseboard_fab2(sch_1):page224_i130@mstr_discrete.ca~
p(chips)',
 PATH='I130',
 DRAWING='@BASEBOARD_FAB2_LIB.BASEBOARD_FAB2(SCH_1):PAGE224',
 BOM_SS='NOPOP',
 POP='NOPOP',
 TOLERANCE='10%',
 SEC_TYPE='0402LF',
 MATERIAL='X7R',
 PHYS_PAGE='224',
 XY='(3050,-75)',
 ROT='0',
 VER='1',
 VALUE='1000PF',
 PACK_TYPE='0402LF',
 PART_NUMBER='A36096-046',
 LOCATION='CT32',
 ROOM='VDDQ_KLM_PWR_VR',
 SEC='1',
 CDS_LIB='mstr_discrete',
 CDS_PART_NAME='CAP_0402LF-1000PF,50V,10%,X7R,A',
 VOLTAGE='50V',
 PRIM_FILE='./archive_libs/mstr_discrete/cap/chips/chips.prt';

PART_NAME
 CT33 'CAP_0402LF-1000PF,50V,10%,X7R,A':
 ROOM='VDDQ_KLM_PWR_VR';

SECTION_NUMBER 1
 '@BASEBOARD_FAB2_LIB.BASEBOARD_FAB2(SCH_1):PAGE224_I141@MSTR_DISCRETE.CAP(CHIPS)':
 C_PATH='@baseboard_fab2_lib.baseboard_fab2(sch_1):page224_i141@mstr_discrete.ca~
p(chips)',
 P_PATH='@baseboard_fab2_lib.baseboard_fab2(sch_1):page224_i141@mstr_discrete.ca~
p(chips)',
 PATH='I141',
 DRAWING='@BASEBOARD_FAB2_LIB.BASEBOARD_FAB2(SCH_1):PAGE224',
 BOM_SS='NOPOP',
 POP='NOPOP',
 TOLERANCE='10%',
 SEC_TYPE='0402LF',
 MATERIAL='X7R',
 PHYS_PAGE='224',
 XY='(3250,-625)',
 ROT='0',
 VER='1',
 VALUE='1000PF',
 PACK_TYPE='0402LF',
 PART_NUMBER='A36096-046',
 LOCATION='CT33',
 ROOM='VDDQ_KLM_PWR_VR',
 SEC='1',
 CDS_LIB='mstr_discrete',
 CDS_PART_NAME='CAP_0402LF-1000PF,50V,10%,X7R,A',
 VOLTAGE='50V',
 PRIM_FILE='./archive_libs/mstr_discrete/cap/chips/chips.prt';

PART_NAME
 CT34 'CAP_0402LF-1000PF,50V,10%,X7R,A':
 ROOM='VDDQ_KLM_PWR_VR';

SECTION_NUMBER 1
 '@BASEBOARD_FAB2_LIB.BASEBOARD_FAB2(SCH_1):PAGE204_I88@MSTR_DISCRETE.CAP(CHIPS)':
 C_PATH='@baseboard_fab2_lib.baseboard_fab2(sch_1):page204_i88@mstr_discrete.cap~
(chips)',
 P_PATH='@baseboard_fab2_lib.baseboard_fab2(sch_1):page204_i88@mstr_discrete.cap~
(chips)',
 PATH='I88',
 DRAWING='@BASEBOARD_FAB2_LIB.BASEBOARD_FAB2(SCH_1):PAGE204',
 POP='NOPOP',
 TOLERANCE='10%',
 SEC_TYPE='0402LF',
 MATERIAL='X7R',
 PHYS_PAGE='204',
 XY='(-2075,3950)',
 ROT='0',
 VER='1',
 VALUE='1000PF',
 PACK_TYPE='0402LF',
 PART_NUMBER='A36096-046',
 LOCATION='CT34',
 ROOM='VDDQ_KLM_PWR_VR',
 SEC='1',
 CDS_LIB='mstr_discrete',
 CDS_PART_NAME='CAP_0402LF-1000PF,50V,10%,X7R,A',
 VOLTAGE='50V',
 PRIM_FILE='./archive_libs/mstr_discrete/cap/chips/chips.prt';

PART_NAME
 CT35 'CAP_0402LF-1000PF,50V,10%,X7R,A':
 ROOM='VDDQ_KLM_PWR_VR';

SECTION_NUMBER 1
 '@BASEBOARD_FAB2_LIB.BASEBOARD_FAB2(SCH_1):PAGE204_I97@MSTR_DISCRETE.CAP(CHIPS)':
 C_PATH='@baseboard_fab2_lib.baseboard_fab2(sch_1):page204_i97@mstr_discrete.cap~
(chips)',
 P_PATH='@baseboard_fab2_lib.baseboard_fab2(sch_1):page204_i97@mstr_discrete.cap~
(chips)',
 PATH='I97',
 DRAWING='@BASEBOARD_FAB2_LIB.BASEBOARD_FAB2(SCH_1):PAGE204',
 POP='NOPOP',
 TOLERANCE='10%',
 SEC_TYPE='0402LF',
 MATERIAL='X7R',
 PHYS_PAGE='204',
 XY='(-1975,3475)',
 ROT='0',
 VER='1',
 VALUE='1000PF',
 PACK_TYPE='0402LF',
 PART_NUMBER='A36096-046',
 LOCATION='CT35',
 ROOM='VDDQ_KLM_PWR_VR',
 SEC='1',
 CDS_LIB='mstr_discrete',
 CDS_PART_NAME='CAP_0402LF-1000PF,50V,10%,X7R,A',
 VOLTAGE='50V',
 PRIM_FILE='./archive_libs/mstr_discrete/cap/chips/chips.prt';

PART_NAME
 CT36 'CAP_A_0402V-0.1UF,16V,10%,X7R,A':
 ROOM='PVCCIN_CPU0_PWR_VR';

SECTION_NUMBER 1
 '@BASEBOARD_FAB2_LIB.BASEBOARD_FAB2(SCH_1):PAGE204_I85@DEV_DISCRETE.CAP_A(CHIPS)':
 C_PATH='@baseboard_fab2_lib.baseboard_fab2(sch_1):page204_i85@dev_discrete.cap_~
a(chips)',
 P_PATH='@baseboard_fab2_lib.baseboard_fab2(sch_1):page204_i85@dev_discrete.cap_~
a(chips)',
 PATH='I85',
 DRAWING='@BASEBOARD_FAB2_LIB.BASEBOARD_FAB2(SCH_1):PAGE204',
 POP='NOPOP',
 TOLERANCE='10%',
 SEC_TYPE='0402V',
 MATERIAL='X7R',
 PHYS_PAGE='204',
 XY='(-3850,3425)',
 ROT='0',
 VER='1',
 VALUE='0.1UF',
 PACK_TYPE='0402V',
 PART_NUMBER='A36096-030',
 LOCATION='CT36',
 ROOM='PVCCIN_CPU0_PWR_VR',
 SEC='1',
 CDS_LIB='dev_discrete',
 CDS_PART_NAME='CAP_A_0402V-0.1UF,16V,10%,X7R,A',
 VOLTAGE='16V',
 PRIM_FILE='./archive_libs/discrete/cap_a/chips/chips.prt';

PART_NAME
 CT37 'CAP_0402LF-1000PF,50V,10%,X7R,A':
 ROOM='VDDQ_KLM_PWR_VR';

SECTION_NUMBER 1
 '@BASEBOARD_FAB2_LIB.BASEBOARD_FAB2(SCH_1):PAGE203_I99@MSTR_DISCRETE.CAP(CHIPS)':
 C_PATH='@baseboard_fab2_lib.baseboard_fab2(sch_1):page203_i99@mstr_discrete.cap~
(chips)',
 P_PATH='@baseboard_fab2_lib.baseboard_fab2(sch_1):page203_i99@mstr_discrete.cap~
(chips)',
 PATH='I99',
 DRAWING='@BASEBOARD_FAB2_LIB.BASEBOARD_FAB2(SCH_1):PAGE203',
 POP='NOPOP',
 TOLERANCE='10%',
 SEC_TYPE='0402LF',
 MATERIAL='X7R',
 PHYS_PAGE='203',
 XY='(-1975,3950)',
 ROT='0',
 VER='1',
 VALUE='1000PF',
 PACK_TYPE='0402LF',
 PART_NUMBER='A36096-046',
 LOCATION='CT37',
 ROOM='VDDQ_KLM_PWR_VR',
 SEC='1',
 CDS_LIB='mstr_discrete',
 CDS_PART_NAME='CAP_0402LF-1000PF,50V,10%,X7R,A',
 VOLTAGE='50V',
 PRIM_FILE='./archive_libs/mstr_discrete/cap/chips/chips.prt';

PART_NAME
 CT38 'CAP_0402LF-1000PF,50V,10%,X7R,A':
 ROOM='VDDQ_KLM_PWR_VR';

SECTION_NUMBER 1
 '@BASEBOARD_FAB2_LIB.BASEBOARD_FAB2(SCH_1):PAGE203_I118@MSTR_DISCRETE.CAP(CHIPS)':
 C_PATH='@baseboard_fab2_lib.baseboard_fab2(sch_1):page203_i118@mstr_discrete.ca~
p(chips)',
 P_PATH='@baseboard_fab2_lib.baseboard_fab2(sch_1):page203_i118@mstr_discrete.ca~
p(chips)',
 PATH='I118',
 DRAWING='@BASEBOARD_FAB2_LIB.BASEBOARD_FAB2(SCH_1):PAGE203',
 POP='NOPOP',
 TOLERANCE='10%',
 SEC_TYPE='0402LF',
 MATERIAL='X7R',
 PHYS_PAGE='203',
 XY='(-1950,3500)',
 ROT='0',
 VER='1',
 VALUE='1000PF',
 PACK_TYPE='0402LF',
 PART_NUMBER='A36096-046',
 LOCATION='CT38',
 ROOM='VDDQ_KLM_PWR_VR',
 SEC='1',
 CDS_LIB='mstr_discrete',
 CDS_PART_NAME='CAP_0402LF-1000PF,50V,10%,X7R,A',
 VOLTAGE='50V',
 PRIM_FILE='./archive_libs/mstr_discrete/cap/chips/chips.prt';

PART_NAME
 CT39 'CAP_A_0402V-0.1UF,16V,10%,X7R,A':
 ROOM='PVCCIN_CPU0_PWR_VR';

SECTION_NUMBER 1
 '@BASEBOARD_FAB2_LIB.BASEBOARD_FAB2(SCH_1):PAGE203_I96@DEV_DISCRETE.CAP_A(CHIPS)':
 C_PATH='@baseboard_fab2_lib.baseboard_fab2(sch_1):page203_i96@dev_discrete.cap_~
a(chips)',
 P_PATH='@baseboard_fab2_lib.baseboard_fab2(sch_1):page203_i96@dev_discrete.cap_~
a(chips)',
 PATH='I96',
 DRAWING='@BASEBOARD_FAB2_LIB.BASEBOARD_FAB2(SCH_1):PAGE203',
 POP='NOPOP',
 TOLERANCE='10%',
 SEC_TYPE='0402V',
 MATERIAL='X7R',
 PHYS_PAGE='203',
 XY='(-3900,3400)',
 ROT='0',
 VER='1',
 VALUE='0.1UF',
 PACK_TYPE='0402V',
 PART_NUMBER='A36096-030',
 LOCATION='CT39',
 ROOM='PVCCIN_CPU0_PWR_VR',
 SEC='1',
 CDS_LIB='dev_discrete',
 CDS_PART_NAME='CAP_A_0402V-0.1UF,16V,10%,X7R,A',
 VOLTAGE='16V',
 PRIM_FILE='./archive_libs/discrete/cap_a/chips/chips.prt';

PART_NAME
 CT40 'CAP_A_0402V-0.1UF,16V,10%,X7R,A':
 ROOM='PVCCIN_CPU0_PWR_VR';

SECTION_NUMBER 1
 '@BASEBOARD_FAB2_LIB.BASEBOARD_FAB2(SCH_1):PAGE203_I93@DEV_DISCRETE.CAP_A(CHIPS)':
 C_PATH='@baseboard_fab2_lib.baseboard_fab2(sch_1):page203_i93@dev_discrete.cap_~
a(chips)',
 P_PATH='@baseboard_fab2_lib.baseboard_fab2(sch_1):page203_i93@dev_discrete.cap_~
a(chips)',
 PATH='I93',
 DRAWING='@BASEBOARD_FAB2_LIB.BASEBOARD_FAB2(SCH_1):PAGE203',
 POP='NOPOP',
 TOLERANCE='10%',
 SEC_TYPE='0402V',
 MATERIAL='X7R',
 PHYS_PAGE='203',
 XY='(-3900,700)',
 ROT='0',
 VER='1',
 VALUE='0.1UF',
 PACK_TYPE='0402V',
 PART_NUMBER='A36096-030',
 LOCATION='CT40',
 ROOM='PVCCIN_CPU0_PWR_VR',
 SEC='1',
 CDS_LIB='dev_discrete',
 CDS_PART_NAME='CAP_A_0402V-0.1UF,16V,10%,X7R,A',
 VOLTAGE='16V',
 PRIM_FILE='./archive_libs/discrete/cap_a/chips/chips.prt';

PART_NAME
 CT41 'CAP_0402LF-1000PF,50V,10%,X7R,A':
 ROOM='VDDQ_KLM_PWR_VR';

SECTION_NUMBER 1
 '@BASEBOARD_FAB2_LIB.BASEBOARD_FAB2(SCH_1):PAGE203_I119@MSTR_DISCRETE.CAP(CHIPS)':
 C_PATH='@baseboard_fab2_lib.baseboard_fab2(sch_1):page203_i119@mstr_discrete.ca~
p(chips)',
 P_PATH='@baseboard_fab2_lib.baseboard_fab2(sch_1):page203_i119@mstr_discrete.ca~
p(chips)',
 PATH='I119',
 DRAWING='@BASEBOARD_FAB2_LIB.BASEBOARD_FAB2(SCH_1):PAGE203',
 POP='NOPOP',
 TOLERANCE='10%',
 SEC_TYPE='0402LF',
 MATERIAL='X7R',
 PHYS_PAGE='203',
 XY='(-1975,800)',
 ROT='0',
 VER='1',
 VALUE='1000PF',
 PACK_TYPE='0402LF',
 PART_NUMBER='A36096-046',
 LOCATION='CT41',
 ROOM='VDDQ_KLM_PWR_VR',
 SEC='1',
 CDS_LIB='mstr_discrete',
 CDS_PART_NAME='CAP_0402LF-1000PF,50V,10%,X7R,A',
 VOLTAGE='50V',
 PRIM_FILE='./archive_libs/mstr_discrete/cap/chips/chips.prt';

PART_NAME
 CT42 'CAP_0402LF-1000PF,50V,10%,X7R,A':
 ROOM='VDDQ_KLM_PWR_VR';

SECTION_NUMBER 1
 '@BASEBOARD_FAB2_LIB.BASEBOARD_FAB2(SCH_1):PAGE203_I108@MSTR_DISCRETE.CAP(CHIPS)':
 C_PATH='@baseboard_fab2_lib.baseboard_fab2(sch_1):page203_i108@mstr_discrete.ca~
p(chips)',
 P_PATH='@baseboard_fab2_lib.baseboard_fab2(sch_1):page203_i108@mstr_discrete.ca~
p(chips)',
 PATH='I108',
 DRAWING='@BASEBOARD_FAB2_LIB.BASEBOARD_FAB2(SCH_1):PAGE203',
 POP='NOPOP',
 TOLERANCE='10%',
 SEC_TYPE='0402LF',
 MATERIAL='X7R',
 PHYS_PAGE='203',
 XY='(-1925,1275)',
 ROT='0',
 VER='1',
 VALUE='1000PF',
 PACK_TYPE='0402LF',
 PART_NUMBER='A36096-046',
 LOCATION='CT42',
 ROOM='VDDQ_KLM_PWR_VR',
 SEC='1',
 CDS_LIB='mstr_discrete',
 CDS_PART_NAME='CAP_0402LF-1000PF,50V,10%,X7R,A',
 VOLTAGE='50V',
 PRIM_FILE='./archive_libs/mstr_discrete/cap/chips/chips.prt';

PART_NAME
 CT43 'CAP_0402LF-1000PF,50V,10%,X7R,A':
 ROOM='VDDQ_KLM_PWR_VR';

SECTION_NUMBER 1
 '@BASEBOARD_FAB2_LIB.BASEBOARD_FAB2(SCH_1):PAGE219_I124@MSTR_DISCRETE.CAP(CHIPS)':
 C_PATH='@baseboard_fab2_lib.baseboard_fab2(sch_1):page219_i124@mstr_discrete.ca~
p(chips)',
 P_PATH='@baseboard_fab2_lib.baseboard_fab2(sch_1):page219_i124@mstr_discrete.ca~
p(chips)',
 PATH='I124',
 DRAWING='@BASEBOARD_FAB2_LIB.BASEBOARD_FAB2(SCH_1):PAGE219',
 POP='NOPOP',
 TOLERANCE='10%',
 SEC_TYPE='0402LF',
 MATERIAL='X7R',
 PHYS_PAGE='219',
 XY='(2900,2125)',
 ROT='0',
 VER='1',
 VALUE='1000PF',
 PACK_TYPE='0402LF',
 PART_NUMBER='A36096-046',
 LOCATION='CT43',
 ROOM='VDDQ_KLM_PWR_VR',
 SEC='1',
 CDS_LIB='mstr_discrete',
 CDS_PART_NAME='CAP_0402LF-1000PF,50V,10%,X7R,A',
 VOLTAGE='50V',
 PRIM_FILE='./archive_libs/mstr_discrete/cap/chips/chips.prt';

PART_NAME
 CT44 'CAP_0402LF-1000PF,50V,10%,X7R,A':
 ROOM='VDDQ_KLM_PWR_VR';

SECTION_NUMBER 1
 '@BASEBOARD_FAB2_LIB.BASEBOARD_FAB2(SCH_1):PAGE219_I137@MSTR_DISCRETE.CAP(CHIPS)':
 C_PATH='@baseboard_fab2_lib.baseboard_fab2(sch_1):page219_i137@mstr_discrete.ca~
p(chips)',
 P_PATH='@baseboard_fab2_lib.baseboard_fab2(sch_1):page219_i137@mstr_discrete.ca~
p(chips)',
 PATH='I137',
 DRAWING='@BASEBOARD_FAB2_LIB.BASEBOARD_FAB2(SCH_1):PAGE219',
 POP='NOPOP',
 TOLERANCE='10%',
 SEC_TYPE='0402LF',
 MATERIAL='X7R',
 PHYS_PAGE='219',
 XY='(2850,1625)',
 ROT='0',
 VER='1',
 VALUE='1000PF',
 PACK_TYPE='0402LF',
 PART_NUMBER='A36096-046',
 LOCATION='CT44',
 ROOM='VDDQ_KLM_PWR_VR',
 SEC='1',
 CDS_LIB='mstr_discrete',
 CDS_PART_NAME='CAP_0402LF-1000PF,50V,10%,X7R,A',
 VOLTAGE='50V',
 PRIM_FILE='./archive_libs/mstr_discrete/cap/chips/chips.prt';

PART_NAME
 CT45 'CAP_A_0402V-0.1UF,16V,10%,X7R,A':
 ROOM='PVCCIN_CPU0_PWR_VR';

SECTION_NUMBER 1
 '@BASEBOARD_FAB2_LIB.BASEBOARD_FAB2(SCH_1):PAGE219_I116@DEV_DISCRETE.CAP_A(CHIPS)':
 C_PATH='@baseboard_fab2_lib.baseboard_fab2(sch_1):page219_i116@dev_discrete.cap~
_a(chips)',
 P_PATH='@baseboard_fab2_lib.baseboard_fab2(sch_1):page219_i116@dev_discrete.cap~
_a(chips)',
 PATH='I116',
 DRAWING='@BASEBOARD_FAB2_LIB.BASEBOARD_FAB2(SCH_1):PAGE219',
 POP='NOPOP',
 TOLERANCE='10%',
 SEC_TYPE='0402V',
 MATERIAL='X7R',
 PHYS_PAGE='219',
 XY='(1025,1625)',
 ROT='0',
 VER='1',
 VALUE='0.1UF',
 PACK_TYPE='0402V',
 PART_NUMBER='A36096-030',
 LOCATION='CT45',
 ROOM='PVCCIN_CPU0_PWR_VR',
 SEC='1',
 CDS_LIB='dev_discrete',
 CDS_PART_NAME='CAP_A_0402V-0.1UF,16V,10%,X7R,A',
 VOLTAGE='16V',
 PRIM_FILE='./archive_libs/discrete/cap_a/chips/chips.prt';

PART_NAME
 CT46 'CAP_A_0402V-0.1UF,16V,10%,X7R,A':
 ROOM='PVCCIN_CPU0_PWR_VR';

SECTION_NUMBER 1
 '@BASEBOARD_FAB2_LIB.BASEBOARD_FAB2(SCH_1):PAGE219_I113@DEV_DISCRETE.CAP_A(CHIPS)':
 C_PATH='@baseboard_fab2_lib.baseboard_fab2(sch_1):page219_i113@dev_discrete.cap~
_a(chips)',
 P_PATH='@baseboard_fab2_lib.baseboard_fab2(sch_1):page219_i113@dev_discrete.cap~
_a(chips)',
 PATH='I113',
 DRAWING='@BASEBOARD_FAB2_LIB.BASEBOARD_FAB2(SCH_1):PAGE219',
 BOM_SS='NOPOP',
 POP='NOPOP',
 TOLERANCE='10%',
 SEC_TYPE='0402V',
 MATERIAL='X7R',
 PHYS_PAGE='219',
 XY='(1075,-625)',
 ROT='0',
 VER='1',
 VALUE='0.1UF',
 PACK_TYPE='0402V',
 PART_NUMBER='A36096-030',
 LOCATION='CT46',
 ROOM='PVCCIN_CPU0_PWR_VR',
 SEC='1',
 CDS_LIB='dev_discrete',
 CDS_PART_NAME='CAP_A_0402V-0.1UF,16V,10%,X7R,A',
 VOLTAGE='16V',
 PRIM_FILE='./archive_libs/discrete/cap_a/chips/chips.prt';

PART_NAME
 CT47 'CAP_0402LF-1000PF,50V,10%,X7R,A':
 ROOM='VDDQ_KLM_PWR_VR';

SECTION_NUMBER 1
 '@BASEBOARD_FAB2_LIB.BASEBOARD_FAB2(SCH_1):PAGE219_I138@MSTR_DISCRETE.CAP(CHIPS)':
 C_PATH='@baseboard_fab2_lib.baseboard_fab2(sch_1):page219_i138@mstr_discrete.ca~
p(chips)',
 P_PATH='@baseboard_fab2_lib.baseboard_fab2(sch_1):page219_i138@mstr_discrete.ca~
p(chips)',
 PATH='I138',
 DRAWING='@BASEBOARD_FAB2_LIB.BASEBOARD_FAB2(SCH_1):PAGE219',
 BOM_SS='NOPOP',
 POP='NOPOP',
 TOLERANCE='10%',
 SEC_TYPE='0402LF',
 MATERIAL='X7R',
 PHYS_PAGE='219',
 XY='(2875,-600)',
 ROT='0',
 VER='1',
 VALUE='1000PF',
 PACK_TYPE='0402LF',
 PART_NUMBER='A36096-046',
 LOCATION='CT47',
 ROOM='VDDQ_KLM_PWR_VR',
 SEC='1',
 CDS_LIB='mstr_discrete',
 CDS_PART_NAME='CAP_0402LF-1000PF,50V,10%,X7R,A',
 VOLTAGE='50V',
 PRIM_FILE='./archive_libs/mstr_discrete/cap/chips/chips.prt';

PART_NAME
 CT48 'CAP_0402LF-1000PF,50V,10%,X7R,A':
 ROOM='VDDQ_KLM_PWR_VR';

SECTION_NUMBER 1
 '@BASEBOARD_FAB2_LIB.BASEBOARD_FAB2(SCH_1):PAGE219_I119@MSTR_DISCRETE.CAP(CHIPS)':
 C_PATH='@baseboard_fab2_lib.baseboard_fab2(sch_1):page219_i119@mstr_discrete.ca~
p(chips)',
 P_PATH='@baseboard_fab2_lib.baseboard_fab2(sch_1):page219_i119@mstr_discrete.ca~
p(chips)',
 PATH='I119',
 DRAWING='@BASEBOARD_FAB2_LIB.BASEBOARD_FAB2(SCH_1):PAGE219',
 BOM_SS='NOPOP',
 POP='NOPOP',
 TOLERANCE='10%',
 SEC_TYPE='0402LF',
 MATERIAL='X7R',
 PHYS_PAGE='219',
 XY='(3075,-100)',
 ROT='0',
 VER='1',
 VALUE='1000PF',
 PACK_TYPE='0402LF',
 PART_NUMBER='A36096-046',
 LOCATION='CT48',
 ROOM='VDDQ_KLM_PWR_VR',
 SEC='1',
 CDS_LIB='mstr_discrete',
 CDS_PART_NAME='CAP_0402LF-1000PF,50V,10%,X7R,A',
 VOLTAGE='50V',
 PRIM_FILE='./archive_libs/mstr_discrete/cap/chips/chips.prt';

PART_NAME
 CT49 'CAP_0402LF-1000PF,50V,10%,X7R,A':
 ROOM='VDDQ_KLM_PWR_VR';

SECTION_NUMBER 1
 '@BASEBOARD_FAB2_LIB.BASEBOARD_FAB2(SCH_1):PAGE216_I118@MSTR_DISCRETE.CAP(CHIPS)':
 C_PATH='@baseboard_fab2_lib.baseboard_fab2(sch_1):page216_i118@mstr_discrete.ca~
p(chips)',
 P_PATH='@baseboard_fab2_lib.baseboard_fab2(sch_1):page216_i118@mstr_discrete.ca~
p(chips)',
 PATH='I118',
 DRAWING='@BASEBOARD_FAB2_LIB.BASEBOARD_FAB2(SCH_1):PAGE216',
 POP='NOPOP',
 TOLERANCE='10%',
 SEC_TYPE='0402LF',
 MATERIAL='X7R',
 PHYS_PAGE='216',
 XY='(3000,2375)',
 ROT='0',
 VER='1',
 VALUE='1000PF',
 PACK_TYPE='0402LF',
 PART_NUMBER='A36096-046',
 LOCATION='CT49',
 ROOM='VDDQ_KLM_PWR_VR',
 SEC='1',
 CDS_LIB='mstr_discrete',
 CDS_PART_NAME='CAP_0402LF-1000PF,50V,10%,X7R,A',
 VOLTAGE='50V',
 PRIM_FILE='./archive_libs/mstr_discrete/cap/chips/chips.prt';

PART_NAME
 CT50 'CAP_0402LF-1000PF,50V,10%,X7R,A':
 ROOM='VDDQ_KLM_PWR_VR';

SECTION_NUMBER 1
 '@BASEBOARD_FAB2_LIB.BASEBOARD_FAB2(SCH_1):PAGE216_I135@MSTR_DISCRETE.CAP(CHIPS)':
 C_PATH='@baseboard_fab2_lib.baseboard_fab2(sch_1):page216_i135@mstr_discrete.ca~
p(chips)',
 P_PATH='@baseboard_fab2_lib.baseboard_fab2(sch_1):page216_i135@mstr_discrete.ca~
p(chips)',
 PATH='I135',
 DRAWING='@BASEBOARD_FAB2_LIB.BASEBOARD_FAB2(SCH_1):PAGE216',
 POP='NOPOP',
 TOLERANCE='10%',
 SEC_TYPE='0402LF',
 MATERIAL='X7R',
 PHYS_PAGE='216',
 XY='(2900,1850)',
 ROT='0',
 VER='1',
 VALUE='1000PF',
 PACK_TYPE='0402LF',
 PART_NUMBER='A36096-046',
 LOCATION='CT50',
 ROOM='VDDQ_KLM_PWR_VR',
 SEC='1',
 CDS_LIB='mstr_discrete',
 CDS_PART_NAME='CAP_0402LF-1000PF,50V,10%,X7R,A',
 VOLTAGE='50V',
 PRIM_FILE='./archive_libs/mstr_discrete/cap/chips/chips.prt';

PART_NAME
 CT51 'CAP_A_0402V-0.1UF,16V,10%,X7R,A':
 ROOM='PVCCIN_CPU0_PWR_VR';

SECTION_NUMBER 1
 '@BASEBOARD_FAB2_LIB.BASEBOARD_FAB2(SCH_1):PAGE216_I108@DEV_DISCRETE.CAP_A(CHIPS)':
 C_PATH='@baseboard_fab2_lib.baseboard_fab2(sch_1):page216_i108@dev_discrete.cap~
_a(chips)',
 P_PATH='@baseboard_fab2_lib.baseboard_fab2(sch_1):page216_i108@dev_discrete.cap~
_a(chips)',
 PATH='I108',
 DRAWING='@BASEBOARD_FAB2_LIB.BASEBOARD_FAB2(SCH_1):PAGE216',
 POP='NOPOP',
 TOLERANCE='10%',
 SEC_TYPE='0402V',
 MATERIAL='X7R',
 PHYS_PAGE='216',
 XY='(1025,1800)',
 ROT='0',
 VER='1',
 VALUE='0.1UF',
 PACK_TYPE='0402V',
 PART_NUMBER='A36096-030',
 LOCATION='CT51',
 ROOM='PVCCIN_CPU0_PWR_VR',
 SEC='1',
 CDS_LIB='dev_discrete',
 CDS_PART_NAME='CAP_A_0402V-0.1UF,16V,10%,X7R,A',
 VOLTAGE='16V',
 PRIM_FILE='./archive_libs/discrete/cap_a/chips/chips.prt';

PART_NAME
 CT52 'CAP_A_0402V-0.1UF,16V,10%,X7R,A':
 ROOM='PVCCIN_CPU0_PWR_VR';

SECTION_NUMBER 1
 '@BASEBOARD_FAB2_LIB.BASEBOARD_FAB2(SCH_1):PAGE216_I111@DEV_DISCRETE.CAP_A(CHIPS)':
 C_PATH='@baseboard_fab2_lib.baseboard_fab2(sch_1):page216_i111@dev_discrete.cap~
_a(chips)',
 P_PATH='@baseboard_fab2_lib.baseboard_fab2(sch_1):page216_i111@dev_discrete.cap~
_a(chips)',
 PATH='I111',
 DRAWING='@BASEBOARD_FAB2_LIB.BASEBOARD_FAB2(SCH_1):PAGE216',
 BOM_SS='NOPOP',
 POP='NOPOP',
 TOLERANCE='10%',
 SEC_TYPE='0402V',
 MATERIAL='X7R',
 PHYS_PAGE='216',
 XY='(1125,-950)',
 ROT='0',
 VER='1',
 VALUE='0.1UF',
 PACK_TYPE='0402V',
 PART_NUMBER='A36096-030',
 LOCATION='CT52',
 ROOM='PVCCIN_CPU0_PWR_VR',
 SEC='1',
 CDS_LIB='dev_discrete',
 CDS_PART_NAME='CAP_A_0402V-0.1UF,16V,10%,X7R,A',
 VOLTAGE='16V',
 PRIM_FILE='./archive_libs/discrete/cap_a/chips/chips.prt';

PART_NAME
 CT53 'CAP_0402LF-1000PF,50V,10%,X7R,A':
 ROOM='VDDQ_KLM_PWR_VR';

SECTION_NUMBER 1
 '@BASEBOARD_FAB2_LIB.BASEBOARD_FAB2(SCH_1):PAGE216_I136@MSTR_DISCRETE.CAP(CHIPS)':
 C_PATH='@baseboard_fab2_lib.baseboard_fab2(sch_1):page216_i136@mstr_discrete.ca~
p(chips)',
 P_PATH='@baseboard_fab2_lib.baseboard_fab2(sch_1):page216_i136@mstr_discrete.ca~
p(chips)',
 PATH='I136',
 DRAWING='@BASEBOARD_FAB2_LIB.BASEBOARD_FAB2(SCH_1):PAGE216',
 BOM_SS='NOPOP',
 POP='NOPOP',
 TOLERANCE='10%',
 SEC_TYPE='0402LF',
 MATERIAL='X7R',
 PHYS_PAGE='216',
 XY='(2900,-525)',
 ROT='0',
 VER='1',
 VALUE='1000PF',
 PACK_TYPE='0402LF',
 PART_NUMBER='A36096-046',
 LOCATION='CT53',
 ROOM='VDDQ_KLM_PWR_VR',
 SEC='1',
 CDS_LIB='mstr_discrete',
 CDS_PART_NAME='CAP_0402LF-1000PF,50V,10%,X7R,A',
 VOLTAGE='50V',
 PRIM_FILE='./archive_libs/mstr_discrete/cap/chips/chips.prt';

PART_NAME
 CT54 'CAP_0402LF-1000PF,50V,10%,X7R,A':
 ROOM='VDDQ_KLM_PWR_VR';

SECTION_NUMBER 1
 '@BASEBOARD_FAB2_LIB.BASEBOARD_FAB2(SCH_1):PAGE216_I121@MSTR_DISCRETE.CAP(CHIPS)':
 C_PATH='@baseboard_fab2_lib.baseboard_fab2(sch_1):page216_i121@mstr_discrete.ca~
p(chips)',
 P_PATH='@baseboard_fab2_lib.baseboard_fab2(sch_1):page216_i121@mstr_discrete.ca~
p(chips)',
 PATH='I121',
 DRAWING='@BASEBOARD_FAB2_LIB.BASEBOARD_FAB2(SCH_1):PAGE216',
 BOM_SS='NOPOP',
 POP='NOPOP',
 TOLERANCE='10%',
 SEC_TYPE='0402LF',
 MATERIAL='X7R',
 PHYS_PAGE='216',
 XY='(2900,-75)',
 ROT='0',
 VER='1',
 VALUE='1000PF',
 PACK_TYPE='0402LF',
 PART_NUMBER='A36096-046',
 LOCATION='CT54',
 ROOM='VDDQ_KLM_PWR_VR',
 SEC='1',
 CDS_LIB='mstr_discrete',
 CDS_PART_NAME='CAP_0402LF-1000PF,50V,10%,X7R,A',
 VOLTAGE='50V',
 PRIM_FILE='./archive_libs/mstr_discrete/cap/chips/chips.prt';

PART_NAME
 CT55 'CAP_0402LF-1000PF,50V,10%,X7R,A':
 ROOM='VDDQ_KLM_PWR_VR';

SECTION_NUMBER 1
 '@BASEBOARD_FAB2_LIB.BASEBOARD_FAB2(SCH_1):PAGE210_I60@MSTR_DISCRETE.CAP(CHIPS)':
 C_PATH='@baseboard_fab2_lib.baseboard_fab2(sch_1):page210_i60@mstr_discrete.cap~
(chips)',
 P_PATH='@baseboard_fab2_lib.baseboard_fab2(sch_1):page210_i60@mstr_discrete.cap~
(chips)',
 PATH='I60',
 DRAWING='@BASEBOARD_FAB2_LIB.BASEBOARD_FAB2(SCH_1):PAGE210',
 POP='NOPOP',
 TOLERANCE='10%',
 SEC_TYPE='0402LF',
 MATERIAL='X7R',
 PHYS_PAGE='210',
 XY='(-2650,3625)',
 ROT='0',
 VER='1',
 VALUE='1000PF',
 PACK_TYPE='0402LF',
 PART_NUMBER='A36096-046',
 LOCATION='CT55',
 ROOM='VDDQ_KLM_PWR_VR',
 SEC='1',
 CDS_LIB='mstr_discrete',
 CDS_PART_NAME='CAP_0402LF-1000PF,50V,10%,X7R,A',
 VOLTAGE='50V',
 PRIM_FILE='./archive_libs/mstr_discrete/cap/chips/chips.prt';

PART_NAME
 CT56 'CAP_0402LF-1000PF,50V,10%,X7R,A':
 ROOM='VDDQ_KLM_PWR_VR';

SECTION_NUMBER 1
 '@BASEBOARD_FAB2_LIB.BASEBOARD_FAB2(SCH_1):PAGE210_I66@MSTR_DISCRETE.CAP(CHIPS)':
 C_PATH='@baseboard_fab2_lib.baseboard_fab2(sch_1):page210_i66@mstr_discrete.cap~
(chips)',
 P_PATH='@baseboard_fab2_lib.baseboard_fab2(sch_1):page210_i66@mstr_discrete.cap~
(chips)',
 PATH='I66',
 DRAWING='@BASEBOARD_FAB2_LIB.BASEBOARD_FAB2(SCH_1):PAGE210',
 POP='NOPOP',
 TOLERANCE='10%',
 SEC_TYPE='0402LF',
 MATERIAL='X7R',
 PHYS_PAGE='210',
 XY='(-2500,3150)',
 ROT='0',
 VER='1',
 VALUE='1000PF',
 PACK_TYPE='0402LF',
 PART_NUMBER='A36096-046',
 LOCATION='CT56',
 ROOM='VDDQ_KLM_PWR_VR',
 SEC='1',
 CDS_LIB='mstr_discrete',
 CDS_PART_NAME='CAP_0402LF-1000PF,50V,10%,X7R,A',
 VOLTAGE='50V',
 PRIM_FILE='./archive_libs/mstr_discrete/cap/chips/chips.prt';

PART_NAME
 CT57 'CAP_A_0402V-0.1UF,16V,10%,X7R,A':
 ROOM='PVCCIN_CPU0_PWR_VR';

SECTION_NUMBER 1
 '@BASEBOARD_FAB2_LIB.BASEBOARD_FAB2(SCH_1):PAGE210_I55@DEV_DISCRETE.CAP_A(CHIPS)':
 C_PATH='@baseboard_fab2_lib.baseboard_fab2(sch_1):page210_i55@dev_discrete.cap_~
a(chips)',
 P_PATH='@baseboard_fab2_lib.baseboard_fab2(sch_1):page210_i55@dev_discrete.cap_~
a(chips)',
 PATH='I55',
 DRAWING='@BASEBOARD_FAB2_LIB.BASEBOARD_FAB2(SCH_1):PAGE210',
 POP='NOPOP',
 TOLERANCE='10%',
 SEC_TYPE='0402V',
 MATERIAL='X7R',
 PHYS_PAGE='210',
 XY='(-4450,3100)',
 ROT='0',
 VER='1',
 VALUE='0.1UF',
 PACK_TYPE='0402V',
 PART_NUMBER='A36096-030',
 LOCATION='CT57',
 ROOM='PVCCIN_CPU0_PWR_VR',
 SEC='1',
 CDS_LIB='dev_discrete',
 CDS_PART_NAME='CAP_A_0402V-0.1UF,16V,10%,X7R,A',
 VOLTAGE='16V',
 PRIM_FILE='./archive_libs/discrete/cap_a/chips/chips.prt';

PART_NAME
 CT58 'CAP_0402LF-1000PF,50V,10%,X7R,A':
 ROOM='VDDQ_KLM_PWR_VR';

SECTION_NUMBER 1
 '@BASEBOARD_FAB2_LIB.BASEBOARD_FAB2(SCH_1):PAGE205_I65@MSTR_DISCRETE.CAP(CHIPS)':
 C_PATH='@baseboard_fab2_lib.baseboard_fab2(sch_1):page205_i65@mstr_discrete.cap~
(chips)',
 P_PATH='@baseboard_fab2_lib.baseboard_fab2(sch_1):page205_i65@mstr_discrete.cap~
(chips)',
 PATH='I65',
 DRAWING='@BASEBOARD_FAB2_LIB.BASEBOARD_FAB2(SCH_1):PAGE205',
 POP='NOPOP',
 TOLERANCE='10%',
 SEC_TYPE='0402LF',
 MATERIAL='X7R',
 PHYS_PAGE='205',
 XY='(-2025,3950)',
 ROT='0',
 VER='1',
 VALUE='1000PF',
 PACK_TYPE='0402LF',
 PART_NUMBER='A36096-046',
 LOCATION='CT58',
 ROOM='VDDQ_KLM_PWR_VR',
 SEC='1',
 CDS_LIB='mstr_discrete',
 CDS_PART_NAME='CAP_0402LF-1000PF,50V,10%,X7R,A',
 VOLTAGE='50V',
 PRIM_FILE='./archive_libs/mstr_discrete/cap/chips/chips.prt';

PART_NAME
 CT59 'CAP_0402LF-1000PF,50V,10%,X7R,A':
 ROOM='VDDQ_KLM_PWR_VR';

SECTION_NUMBER 1
 '@BASEBOARD_FAB2_LIB.BASEBOARD_FAB2(SCH_1):PAGE205_I76@MSTR_DISCRETE.CAP(CHIPS)':
 C_PATH='@baseboard_fab2_lib.baseboard_fab2(sch_1):page205_i76@mstr_discrete.cap~
(chips)',
 P_PATH='@baseboard_fab2_lib.baseboard_fab2(sch_1):page205_i76@mstr_discrete.cap~
(chips)',
 PATH='I76',
 DRAWING='@BASEBOARD_FAB2_LIB.BASEBOARD_FAB2(SCH_1):PAGE205',
 POP='NOPOP',
 TOLERANCE='10%',
 SEC_TYPE='0402LF',
 MATERIAL='X7R',
 PHYS_PAGE='205',
 XY='(-2050,3475)',
 ROT='0',
 VER='1',
 VALUE='1000PF',
 PACK_TYPE='0402LF',
 PART_NUMBER='A36096-046',
 LOCATION='CT59',
 ROOM='VDDQ_KLM_PWR_VR',
 SEC='1',
 CDS_LIB='mstr_discrete',
 CDS_PART_NAME='CAP_0402LF-1000PF,50V,10%,X7R,A',
 VOLTAGE='50V',
 PRIM_FILE='./archive_libs/mstr_discrete/cap/chips/chips.prt';

PART_NAME
 CT60 'CAP_A_0402V-0.1UF,16V,10%,X7R,A':
 ROOM='PVCCIN_CPU0_PWR_VR';

SECTION_NUMBER 1
 '@BASEBOARD_FAB2_LIB.BASEBOARD_FAB2(SCH_1):PAGE205_I69@DEV_DISCRETE.CAP_A(CHIPS)':
 C_PATH='@baseboard_fab2_lib.baseboard_fab2(sch_1):page205_i69@dev_discrete.cap_~
a(chips)',
 P_PATH='@baseboard_fab2_lib.baseboard_fab2(sch_1):page205_i69@dev_discrete.cap_~
a(chips)',
 PATH='I69',
 DRAWING='@BASEBOARD_FAB2_LIB.BASEBOARD_FAB2(SCH_1):PAGE205',
 POP='NOPOP',
 TOLERANCE='10%',
 SEC_TYPE='0402V',
 MATERIAL='X7R',
 PHYS_PAGE='205',
 XY='(-3850,3425)',
 ROT='0',
 VER='1',
 VALUE='0.1UF',
 PACK_TYPE='0402V',
 PART_NUMBER='A36096-030',
 LOCATION='CT60',
 ROOM='PVCCIN_CPU0_PWR_VR',
 SEC='1',
 CDS_LIB='dev_discrete',
 CDS_PART_NAME='CAP_A_0402V-0.1UF,16V,10%,X7R,A',
 VOLTAGE='16V',
 PRIM_FILE='./archive_libs/discrete/cap_a/chips/chips.prt';

PART_NAME
 CT61 'CAP_0402LF-1000PF,50V,10%,X7R,A':
 ROOM='VDDQ_KLM_PWR_VR';

SECTION_NUMBER 1
 '@BASEBOARD_FAB2_LIB.BASEBOARD_FAB2(SCH_1):PAGE214_I134@MSTR_DISCRETE.CAP(CHIPS)':
 C_PATH='@baseboard_fab2_lib.baseboard_fab2(sch_1):page214_i134@mstr_discrete.ca~
p(chips)',
 P_PATH='@baseboard_fab2_lib.baseboard_fab2(sch_1):page214_i134@mstr_discrete.ca~
p(chips)',
 PATH='I134',
 DRAWING='@BASEBOARD_FAB2_LIB.BASEBOARD_FAB2(SCH_1):PAGE214',
 POP='NOPOP',
 TOLERANCE='10%',
 SEC_TYPE='0402LF',
 MATERIAL='X7R',
 PHYS_PAGE='214',
 XY='(2275,3950)',
 ROT='0',
 VER='1',
 VALUE='1000PF',
 PACK_TYPE='0402LF',
 PART_NUMBER='A36096-046',
 LOCATION='CT61',
 ROOM='VDDQ_KLM_PWR_VR',
 SEC='1',
 CDS_LIB='mstr_discrete',
 CDS_PART_NAME='CAP_0402LF-1000PF,50V,10%,X7R,A',
 VOLTAGE='50V',
 PRIM_FILE='./archive_libs/mstr_discrete/cap/chips/chips.prt';

PART_NAME
 CT62 'CAP_0402LF-1000PF,50V,10%,X7R,A':
 ROOM='VDDQ_KLM_PWR_VR';

SECTION_NUMBER 1
 '@BASEBOARD_FAB2_LIB.BASEBOARD_FAB2(SCH_1):PAGE214_I143@MSTR_DISCRETE.CAP(CHIPS)':
 C_PATH='@baseboard_fab2_lib.baseboard_fab2(sch_1):page214_i143@mstr_discrete.ca~
p(chips)',
 P_PATH='@baseboard_fab2_lib.baseboard_fab2(sch_1):page214_i143@mstr_discrete.ca~
p(chips)',
 PATH='I143',
 DRAWING='@BASEBOARD_FAB2_LIB.BASEBOARD_FAB2(SCH_1):PAGE214',
 POP='NOPOP',
 TOLERANCE='10%',
 SEC_TYPE='0402LF',
 MATERIAL='X7R',
 PHYS_PAGE='214',
 XY='(2200,3450)',
 ROT='0',
 VER='1',
 VALUE='1000PF',
 PACK_TYPE='0402LF',
 PART_NUMBER='A36096-046',
 LOCATION='CT62',
 ROOM='VDDQ_KLM_PWR_VR',
 SEC='1',
 CDS_LIB='mstr_discrete',
 CDS_PART_NAME='CAP_0402LF-1000PF,50V,10%,X7R,A',
 VOLTAGE='50V',
 PRIM_FILE='./archive_libs/mstr_discrete/cap/chips/chips.prt';

PART_NAME
 CT63 'CAP_A_0402V-0.1UF,16V,10%,X7R,A':
 ROOM='PVCCIN_CPU0_PWR_VR';

SECTION_NUMBER 1
 '@BASEBOARD_FAB2_LIB.BASEBOARD_FAB2(SCH_1):PAGE214_I137@DEV_DISCRETE.CAP_A(CHIPS)':
 C_PATH='@baseboard_fab2_lib.baseboard_fab2(sch_1):page214_i137@dev_discrete.cap~
_a(chips)',
 P_PATH='@baseboard_fab2_lib.baseboard_fab2(sch_1):page214_i137@dev_discrete.cap~
_a(chips)',
 PATH='I137',
 DRAWING='@BASEBOARD_FAB2_LIB.BASEBOARD_FAB2(SCH_1):PAGE214',
 POP='NOPOP',
 TOLERANCE='10%',
 SEC_TYPE='0402V',
 MATERIAL='X7R',
 PHYS_PAGE='214',
 XY='(275,3425)',
 ROT='0',
 VER='1',
 VALUE='0.1UF',
 PACK_TYPE='0402V',
 PART_NUMBER='A36096-030',
 LOCATION='CT63',
 ROOM='PVCCIN_CPU0_PWR_VR',
 SEC='1',
 CDS_LIB='dev_discrete',
 CDS_PART_NAME='CAP_A_0402V-0.1UF,16V,10%,X7R,A',
 VOLTAGE='16V',
 PRIM_FILE='./archive_libs/discrete/cap_a/chips/chips.prt';

PART_NAME
 CT64 'CAP_0402LF-1000PF,50V,10%,X7R,A':
 ROOM='VDDQ_KLM_PWR_VR';

SECTION_NUMBER 1
 '@BASEBOARD_FAB2_LIB.BASEBOARD_FAB2(SCH_1):PAGE236_I136@MSTR_DISCRETE.CAP(CHIPS)':
 C_PATH='@baseboard_fab2_lib.baseboard_fab2(sch_1):page236_i136@mstr_discrete.ca~
p(chips)',
 P_PATH='@baseboard_fab2_lib.baseboard_fab2(sch_1):page236_i136@mstr_discrete.ca~
p(chips)',
 PATH='I136',
 DRAWING='@BASEBOARD_FAB2_LIB.BASEBOARD_FAB2(SCH_1):PAGE236',
 POP='NOPOP',
 TOLERANCE='10%',
 SEC_TYPE='0402LF',
 MATERIAL='X7R',
 PHYS_PAGE='236',
 XY='(10925,4300)',
 ROT='0',
 VER='1',
 VALUE='1000PF',
 PACK_TYPE='0402LF',
 PART_NUMBER='A36096-046',
 LOCATION='CT64',
 ROOM='VDDQ_KLM_PWR_VR',
 SEC='1',
 CDS_LIB='mstr_discrete',
 CDS_PART_NAME='CAP_0402LF-1000PF,50V,10%,X7R,A',
 VOLTAGE='50V',
 PRIM_FILE='./archive_libs/mstr_discrete/cap/chips/chips.prt';

PART_NAME
 CT65 'CAP_0402LF-1000PF,50V,10%,X7R,A':
 ROOM='VDDQ_KLM_PWR_VR';

SECTION_NUMBER 1
 '@BASEBOARD_FAB2_LIB.BASEBOARD_FAB2(SCH_1):PAGE236_I149@MSTR_DISCRETE.CAP(CHIPS)':
 C_PATH='@baseboard_fab2_lib.baseboard_fab2(sch_1):page236_i149@mstr_discrete.ca~
p(chips)',
 P_PATH='@baseboard_fab2_lib.baseboard_fab2(sch_1):page236_i149@mstr_discrete.ca~
p(chips)',
 PATH='I149',
 DRAWING='@BASEBOARD_FAB2_LIB.BASEBOARD_FAB2(SCH_1):PAGE236',
 POP='NOPOP',
 TOLERANCE='10%',
 SEC_TYPE='0402LF',
 MATERIAL='X7R',
 PHYS_PAGE='236',
 XY='(10550,3850)',
 ROT='0',
 VER='1',
 VALUE='1000PF',
 PACK_TYPE='0402LF',
 PART_NUMBER='A36096-046',
 LOCATION='CT65',
 ROOM='VDDQ_KLM_PWR_VR',
 SEC='1',
 CDS_LIB='mstr_discrete',
 CDS_PART_NAME='CAP_0402LF-1000PF,50V,10%,X7R,A',
 VOLTAGE='50V',
 PRIM_FILE='./archive_libs/mstr_discrete/cap/chips/chips.prt';

PART_NAME
 CT66 'CAP_A_0402V-0.1UF,16V,10%,X7R,A':
 ROOM='PVCCIN_CPU0_PWR_VR';

SECTION_NUMBER 1
 '@BASEBOARD_FAB2_LIB.BASEBOARD_FAB2(SCH_1):PAGE236_I127@DEV_DISCRETE.CAP_A(CHIPS)':
 C_PATH='@baseboard_fab2_lib.baseboard_fab2(sch_1):page236_i127@dev_discrete.cap~
_a(chips)',
 P_PATH='@baseboard_fab2_lib.baseboard_fab2(sch_1):page236_i127@dev_discrete.cap~
_a(chips)',
 PATH='I127',
 DRAWING='@BASEBOARD_FAB2_LIB.BASEBOARD_FAB2(SCH_1):PAGE236',
 POP='NOPOP',
 TOLERANCE='10%',
 SEC_TYPE='0402V',
 MATERIAL='X7R',
 PHYS_PAGE='236',
 XY='(9125,3775)',
 ROT='0',
 VER='1',
 VALUE='0.1UF',
 PACK_TYPE='0402V',
 PART_NUMBER='A36096-030',
 LOCATION='CT66',
 ROOM='PVCCIN_CPU0_PWR_VR',
 SEC='1',
 CDS_LIB='dev_discrete',
 CDS_PART_NAME='CAP_A_0402V-0.1UF,16V,10%,X7R,A',
 VOLTAGE='16V',
 PRIM_FILE='./archive_libs/discrete/cap_a/chips/chips.prt';

PART_NAME
 CT67 'CAP_A_0402V-0.1UF,16V,10%,X7R,A':
 ROOM='PVCCIN_CPU0_PWR_VR';

SECTION_NUMBER 1
 '@BASEBOARD_FAB2_LIB.BASEBOARD_FAB2(SCH_1):PAGE236_I124@DEV_DISCRETE.CAP_A(CHIPS)':
 C_PATH='@baseboard_fab2_lib.baseboard_fab2(sch_1):page236_i124@dev_discrete.cap~
_a(chips)',
 P_PATH='@baseboard_fab2_lib.baseboard_fab2(sch_1):page236_i124@dev_discrete.cap~
_a(chips)',
 PATH='I124',
 DRAWING='@BASEBOARD_FAB2_LIB.BASEBOARD_FAB2(SCH_1):PAGE236',
 POP='NOPOP',
 TOLERANCE='10%',
 MATERIAL='X7R',
 PHYS_PAGE='236',
 XY='(9125,2025)',
 ROT='0',
 VER='1',
 VALUE='0.1UF',
 PACK_TYPE='0402V',
 PART_NUMBER='A36096-030',
 LOCATION='CT67',
 ROOM='PVCCIN_CPU0_PWR_VR',
 CDS_LIB='dev_discrete',
 CDS_PART_NAME='CAP_A_0402V-0.1UF,16V,10%,X7R,A',
 VOLTAGE='16V',
 PRIM_FILE='./archive_libs/discrete/cap_a/chips/chips.prt';

PART_NAME
 CT68 'CAP_0402LF-1000PF,50V,10%,X7R,A':
 ROOM='VDDQ_KLM_PWR_VR';

SECTION_NUMBER 1
 '@BASEBOARD_FAB2_LIB.BASEBOARD_FAB2(SCH_1):PAGE236_I150@MSTR_DISCRETE.CAP(CHIPS)':
 C_PATH='@baseboard_fab2_lib.baseboard_fab2(sch_1):page236_i150@mstr_discrete.ca~
p(chips)',
 P_PATH='@baseboard_fab2_lib.baseboard_fab2(sch_1):page236_i150@mstr_discrete.ca~
p(chips)',
 PATH='I150',
 DRAWING='@BASEBOARD_FAB2_LIB.BASEBOARD_FAB2(SCH_1):PAGE236',
 POP='NOPOP',
 TOLERANCE='10%',
 SEC_TYPE='0402LF',
 MATERIAL='X7R',
 PHYS_PAGE='236',
 XY='(11050,2150)',
 ROT='0',
 VER='1',
 VALUE='1000PF',
 PACK_TYPE='0402LF',
 PART_NUMBER='A36096-046',
 LOCATION='CT68',
 ROOM='VDDQ_KLM_PWR_VR',
 SEC='1',
 CDS_LIB='mstr_discrete',
 CDS_PART_NAME='CAP_0402LF-1000PF,50V,10%,X7R,A',
 VOLTAGE='50V',
 PRIM_FILE='./archive_libs/mstr_discrete/cap/chips/chips.prt';

PART_NAME
 CT69 'CAP_0402LF-1000PF,50V,10%,X7R,A':
 ROOM='VDDQ_KLM_PWR_VR';

SECTION_NUMBER 1
 '@BASEBOARD_FAB2_LIB.BASEBOARD_FAB2(SCH_1):PAGE236_I134@MSTR_DISCRETE.CAP(CHIPS)':
 C_PATH='@baseboard_fab2_lib.baseboard_fab2(sch_1):page236_i134@mstr_discrete.ca~
p(chips)',
 P_PATH='@baseboard_fab2_lib.baseboard_fab2(sch_1):page236_i134@mstr_discrete.ca~
p(chips)',
 PATH='I134',
 DRAWING='@BASEBOARD_FAB2_LIB.BASEBOARD_FAB2(SCH_1):PAGE236',
 POP='NOPOP',
 TOLERANCE='10%',
 SEC_TYPE='0402LF',
 MATERIAL='X7R',
 PHYS_PAGE='236',
 XY='(10900,2600)',
 ROT='0',
 VER='1',
 VALUE='1000PF',
 PACK_TYPE='0402LF',
 PART_NUMBER='A36096-046',
 LOCATION='CT69',
 ROOM='VDDQ_KLM_PWR_VR',
 SEC='1',
 CDS_LIB='mstr_discrete',
 CDS_PART_NAME='CAP_0402LF-1000PF,50V,10%,X7R,A',
 VOLTAGE='50V',
 PRIM_FILE='./archive_libs/mstr_discrete/cap/chips/chips.prt';

PART_NAME
 CT70 'CAP_A_0402V-0.1UF,16V,10%,X7R,A':
 ROOM='PVCCIN_CPU0_PWR_VR';

SECTION_NUMBER 1
 '@BASEBOARD_FAB2_LIB.BASEBOARD_FAB2(SCH_1):PAGE212_I106@DEV_DISCRETE.CAP_A(CHIPS)':
 C_PATH='@baseboard_fab2_lib.baseboard_fab2(sch_1):page212_i106@dev_discrete.cap~
_a(chips)',
 P_PATH='@baseboard_fab2_lib.baseboard_fab2(sch_1):page212_i106@dev_discrete.cap~
_a(chips)',
 PATH='I106',
 DRAWING='@BASEBOARD_FAB2_LIB.BASEBOARD_FAB2(SCH_1):PAGE212',
 POP='NOPOP',
 TOLERANCE='10%',
 MATERIAL='X7R',
 PHYS_PAGE='212',
 XY='(450,3450)',
 ROT='0',
 VER='1',
 VALUE='0.1UF',
 PACK_TYPE='0402V',
 PART_NUMBER='A36096-030',
 LOCATION='CT70',
 ROOM='PVCCIN_CPU0_PWR_VR',
 CDS_LIB='dev_discrete',
 CDS_PART_NAME='CAP_A_0402V-0.1UF,16V,10%,X7R,A',
 VOLTAGE='16V',
 PRIM_FILE='./archive_libs/discrete/cap_a/chips/chips.prt';

PART_NAME
 CT71 'CAP_0402LF-1000PF,50V,10%,X7R,A':
 ROOM='VDDQ_KLM_PWR_VR';

SECTION_NUMBER 1
 '@BASEBOARD_FAB2_LIB.BASEBOARD_FAB2(SCH_1):PAGE212_I109@MSTR_DISCRETE.CAP(CHIPS)':
 C_PATH='@baseboard_fab2_lib.baseboard_fab2(sch_1):page212_i109@mstr_discrete.ca~
p(chips)',
 P_PATH='@baseboard_fab2_lib.baseboard_fab2(sch_1):page212_i109@mstr_discrete.ca~
p(chips)',
 PATH='I109',
 DRAWING='@BASEBOARD_FAB2_LIB.BASEBOARD_FAB2(SCH_1):PAGE212',
 POP='NOPOP',
 TOLERANCE='10%',
 MATERIAL='X7R',
 PHYS_PAGE='212',
 XY='(2375,3975)',
 ROT='0',
 VER='1',
 VALUE='1000PF',
 PACK_TYPE='0402LF',
 PART_NUMBER='A36096-046',
 LOCATION='CT71',
 ROOM='VDDQ_KLM_PWR_VR',
 CDS_LIB='mstr_discrete',
 CDS_PART_NAME='CAP_0402LF-1000PF,50V,10%,X7R,A',
 VOLTAGE='50V',
 PRIM_FILE='./archive_libs/mstr_discrete/cap/chips/chips.prt';

PART_NAME
 CT72 'CAP_0402LF-1000PF,50V,10%,X7R,A':
 ROOM='VDDQ_KLM_PWR_VR';

SECTION_NUMBER 1
 '@BASEBOARD_FAB2_LIB.BASEBOARD_FAB2(SCH_1):PAGE212_I118@MSTR_DISCRETE.CAP(CHIPS)':
 C_PATH='@baseboard_fab2_lib.baseboard_fab2(sch_1):page212_i118@mstr_discrete.ca~
p(chips)',
 P_PATH='@baseboard_fab2_lib.baseboard_fab2(sch_1):page212_i118@mstr_discrete.ca~
p(chips)',
 PATH='I118',
 DRAWING='@BASEBOARD_FAB2_LIB.BASEBOARD_FAB2(SCH_1):PAGE212',
 POP='NOPOP',
 TOLERANCE='10%',
 SEC_TYPE='0402LF',
 MATERIAL='X7R',
 PHYS_PAGE='212',
 XY='(2625,3450)',
 ROT='0',
 VER='1',
 VALUE='1000PF',
 PACK_TYPE='0402LF',
 PART_NUMBER='A36096-046',
 LOCATION='CT72',
 ROOM='VDDQ_KLM_PWR_VR',
 SEC='1',
 CDS_LIB='mstr_discrete',
 CDS_PART_NAME='CAP_0402LF-1000PF,50V,10%,X7R,A',
 VOLTAGE='50V',
 PRIM_FILE='./archive_libs/mstr_discrete/cap/chips/chips.prt';

PART_NAME
 CTI7 'CAP_0402LF-1000PF,50V,10%,X7R,A':
 ROOM='VDDQ_KLM_PWR_VR';

SECTION_NUMBER 1
 '@BASEBOARD_FAB2_LIB.BASEBOARD_FAB2(SCH_1):PAGE208_I82@MSTR_DISCRETE.CAP(CHIPS)':
 C_PATH='@baseboard_fab2_lib.baseboard_fab2(sch_1):page208_i82@mstr_discrete.cap~
(chips)',
 P_PATH='@baseboard_fab2_lib.baseboard_fab2(sch_1):page208_i82@mstr_discrete.cap~
(chips)',
 PATH='I82',
 DRAWING='@BASEBOARD_FAB2_LIB.BASEBOARD_FAB2(SCH_1):PAGE208',
 POP='NOPOP',
 TOLERANCE='10%',
 SEC_TYPE='0402LF',
 MATERIAL='X7R',
 PHYS_PAGE='208',
 XY='(-2050,3900)',
 ROT='0',
 VER='1',
 VALUE='1000PF',
 PACK_TYPE='0402LF',
 PART_NUMBER='A36096-046',
 LOCATION='CTI7',
 ROOM='VDDQ_KLM_PWR_VR',
 SEC='1',
 CDS_LIB='mstr_discrete',
 CDS_PART_NAME='CAP_0402LF-1000PF,50V,10%,X7R,A',
 VOLTAGE='50V',
 PRIM_FILE='./archive_libs/mstr_discrete/cap/chips/chips.prt';

PART_NAME
 D25W8 'RB551V30-GP_DISCRET-G-RB551V30A':
 GROUP='AST2500';

SECTION_NUMBER 1
 '@BASEBOARD_FAB2_LIB.BASEBOARD_FAB2(SCH_1):PAGE255_I128@W_HDL.RB551V30-GP(CHIPS)':
 C_PATH='@baseboard_fab2_lib.baseboard_fab2(sch_1):page255_i128@w_hdl.\rb551v30-~
gp\(chips)',
 P_PATH='@baseboard_fab2_lib.baseboard_fab2(sch_1):page252_i128@w_hdl.\rb551v30-~
gp\(chips)',
 PATH='I128',
 DRAWING='@BASEBOARD_FAB2_LIB.BASEBOARD_FAB2(SCH_1):PAGE255',
 SEC_TYPE='DISCRET-G',
 PHYS_PAGE='252',
 XY='(-4775,2750)',
 ROT='0',
 VER='1',
 VALUE='RB551V30-GP',
 PACK_TYPE='DISCRET-G',
 PART_NUMBER='83.R5003.H8H',
 LOCATION='D25W8',
 GROUP='AST2500',
 SEC='1',
 CDS_LIB='w_hdl',
 CDS_PART_NAME='RB551V30-GP_DISCRET-G-RB551V30A',
 PRIM_FILE='C:/<user>/w_hdl/rb551v30#2dgp/chips/chips.prt';

PART_NAME
 DS9A1 'LED_1NC-BLUE,IC,C96565-012':
 ROOM='MIO_CHASSIS';

SECTION_NUMBER 1
 '@BASEBOARD_FAB2_LIB.BASEBOARD_FAB2(SCH_1):PAGE175_I50@MSTR_DISCRETE.LED(CHIPS)':
 C_PATH='@baseboard_fab2_lib.baseboard_fab2(sch_1):page175_i50@mstr_discrete.led~
(chips)',
 P_PATH='@baseboard_fab2_lib.baseboard_fab2(sch_1):page175_i50@mstr_discrete.led~
(chips)',
 PATH='I50',
 DRAWING='@BASEBOARD_FAB2_LIB.BASEBOARD_FAB2(SCH_1):PAGE175',
 COLOR='BLUE',
 MATERIAL='IC',
 BOM_COST='MIO_CHASSIS',
 PHYS_PAGE='175',
 XY='(-1700,1025)',
 ROT='0',
 VER='3',
 PACK_TYPE='1NC',
 PART_NUMBER='C96565-012',
 LOCATION='DS9A1',
 ROOM='MIO_CHASSIS',
 CDS_LIB='mstr_discrete',
 CDS_PART_NAME='LED_1NC-BLUE,IC,C96565-012',
 PRIM_FILE='./archive_libs/mstr_discrete/led/chips/chips.prt';

PART_NAME
 DS9A2 'LED_1NCLF-GREEN,IC,C96565-011':
 ROOM='MIO_CHASSIS';

SECTION_NUMBER 1
 '@BASEBOARD_FAB2_LIB.BASEBOARD_FAB2(SCH_1):PAGE177_I42@MSTR_DISCRETE.LED(CHIPS)':
 C_PATH='@baseboard_fab2_lib.baseboard_fab2(sch_1):page177_i42@mstr_discrete.led~
(chips)',
 P_PATH='@baseboard_fab2_lib.baseboard_fab2(sch_1):page177_i42@mstr_discrete.led~
(chips)',
 PATH='I42',
 DRAWING='@BASEBOARD_FAB2_LIB.BASEBOARD_FAB2(SCH_1):PAGE177',
 NEW_PN='83.00320.A70',
 COLOR='GREEN',
 SEC_TYPE='1NCLF',
 MATERIAL='IC',
 PHYS_PAGE='177',
 XY='(-5550,6275)',
 ROT='0',
 VER='3',
 PACK_TYPE='1NCLF',
 PART_NUMBER='C96565-011',
 LOCATION='DS9A2',
 ROOM='MIO_CHASSIS',
 SEC='1',
 CDS_LIB='mstr_discrete',
 CDS_PART_NAME='LED_1NCLF-GREEN,IC,C96565-011',
 PRIM_FILE='./archive_libs/mstr_discrete/led/chips/chips.prt';

PART_NAME
 DS9A3 'LED_1NCLF-YELLOW,IC,C96565-003':
 ROOM='MIO_CHASSIS';

SECTION_NUMBER 1
 '@BASEBOARD_FAB2_LIB.BASEBOARD_FAB2(SCH_1):PAGE175_I67@MSTR_DISCRETE.LED(CHIPS)':
 C_PATH='@baseboard_fab2_lib.baseboard_fab2(sch_1):page175_i67@mstr_discrete.led~
(chips)',
 P_PATH='@baseboard_fab2_lib.baseboard_fab2(sch_1):page175_i67@mstr_discrete.led~
(chips)',
 PATH='I67',
 DRAWING='@BASEBOARD_FAB2_LIB.BASEBOARD_FAB2(SCH_1):PAGE175',
 COLOR='YELLOW',
 SEC_TYPE='1NCLF',
 MATERIAL='IC',
 BOM_COST='MIO_CHASSIS',
 PHYS_PAGE='175',
 XY='(-4600,1550)',
 ROT='0',
 VER='3',
 PACK_TYPE='1NCLF',
 PART_NUMBER='C96565-003',
 LOCATION='DS9A3',
 ROOM='MIO_CHASSIS',
 SEC='1',
 CDS_LIB='mstr_discrete',
 CDS_PART_NAME='LED_1NCLF-YELLOW,IC,C96565-003',
 PRIM_FILE='./archive_libs/mstr_discrete/led/chips/chips.prt';

PART_NAME
 DS9A4 'LED_A1LF-GREEN,IC,D14725-022':
 ROOM='UART_MUX';

SECTION_NUMBER 1
 '@BASEBOARD_FAB2_LIB.BASEBOARD_FAB2(SCH_1):PAGE158_I130@MSTR_DISCRETE.LED(CHIPS)':
 C_PATH='@baseboard_fab2_lib.baseboard_fab2(sch_1):page158_i130@mstr_discrete.le~
d(chips)',
 P_PATH='@baseboard_fab2_lib.baseboard_fab2(sch_1):page158_i130@mstr_discrete.le~
d(chips)',
 PATH='I130',
 DRAWING='@BASEBOARD_FAB2_LIB.BASEBOARD_FAB2(SCH_1):PAGE158',
 COLOR='GREEN',
 SEC_TYPE='A1LF',
 MATERIAL='IC',
 BOM_COST='DEBUG',
 PHYS_PAGE='158',
 XY='(-5725,3200)',
 ROT='0',
 VER='3',
 PACK_TYPE='A1LF',
 PART_NUMBER='D14725-022',
 LOCATION='DS9A4',
 ROOM='UART_MUX',
 SEC='1',
 CDS_LIB='mstr_discrete',
 CDS_PART_NAME='LED_A1LF-GREEN,IC,D14725-022',
 PRIM_FILE='./archive_libs/mstr_discrete/led/chips/chips.prt';

PART_NAME
 DS9A5 'LED_A1LF-GREEN,IC,C97278-010':
 ROOM='SB';

SECTION_NUMBER 1
 '@BASEBOARD_FAB2_LIB.BASEBOARD_FAB2(SCH_1):PAGE119_I179@MSTR_DISCRETE.LED(CHIPS)':
 C_PATH='@baseboard_fab2_lib.baseboard_fab2(sch_1):page119_i179@mstr_discrete.le~
d(chips)',
 P_PATH='@baseboard_fab2_lib.baseboard_fab2(sch_1):page119_i179@mstr_discrete.le~
d(chips)',
 PATH='I179',
 DRAWING='@BASEBOARD_FAB2_LIB.BASEBOARD_FAB2(SCH_1):PAGE119',
 COLOR='GREEN',
 SEC_TYPE='A1LF',
 MATERIAL='IC',
 BOM_COST='SB',
 PHYS_PAGE='119',
 XY='(-3550,1525)',
 ROT='0',
 VER='3',
 PACK_TYPE='A1LF',
 PART_NUMBER='C97278-010',
 LOCATION='DS9A5',
 ROOM='SB',
 SEC='1',
 CDS_LIB='mstr_discrete',
 CDS_PART_NAME='LED_A1LF-GREEN,IC,C97278-010',
 PRIM_FILE='./archive_libs/mstr_discrete/led/chips/chips.prt';

PART_NAME
 DS9A6 'LED_A1LF-GREEN,IC,C97278-010':
 ROOM='MIO_CHASSIS';

SECTION_NUMBER 1
 '@BASEBOARD_FAB2_LIB.BASEBOARD_FAB2(SCH_1):PAGE177_I31@MSTR_DISCRETE.LED(CHIPS)':
 C_PATH='@baseboard_fab2_lib.baseboard_fab2(sch_1):page177_i31@mstr_discrete.led~
(chips)',
 P_PATH='@baseboard_fab2_lib.baseboard_fab2(sch_1):page177_i31@mstr_discrete.led~
(chips)',
 PATH='I31',
 DRAWING='@BASEBOARD_FAB2_LIB.BASEBOARD_FAB2(SCH_1):PAGE177',
 COLOR='GREEN',
 SEC_TYPE='A1LF',
 MATERIAL='IC',
 PHYS_PAGE='177',
 XY='(-3825,8475)',
 ROT='0',
 VER='2',
 PACK_TYPE='A1LF',
 PART_NUMBER='C97278-010',
 LOCATION='DS9A6',
 ROOM='MIO_CHASSIS',
 SEC='1',
 CDS_LIB='mstr_discrete',
 CDS_PART_NAME='LED_A1LF-GREEN,IC,C97278-010',
 PRIM_FILE='./archive_libs/mstr_discrete/led/chips/chips.prt';

PART_NAME
 DS9A7 'LED_A1LF-GREEN,IC,D14725-022':
 ROOM='UART_MUX';

SECTION_NUMBER 1
 '@BASEBOARD_FAB2_LIB.BASEBOARD_FAB2(SCH_1):PAGE158_I134@MSTR_DISCRETE.LED(CHIPS)':
 C_PATH='@baseboard_fab2_lib.baseboard_fab2(sch_1):page158_i134@mstr_discrete.le~
d(chips)',
 P_PATH='@baseboard_fab2_lib.baseboard_fab2(sch_1):page158_i134@mstr_discrete.le~
d(chips)',
 PATH='I134',
 DRAWING='@BASEBOARD_FAB2_LIB.BASEBOARD_FAB2(SCH_1):PAGE158',
 COLOR='GREEN',
 SEC_TYPE='A1LF',
 MATERIAL='IC',
 BOM_COST='DEBUG',
 PHYS_PAGE='158',
 XY='(-5725,3600)',
 ROT='0',
 VER='3',
 PACK_TYPE='A1LF',
 PART_NUMBER='D14725-022',
 LOCATION='DS9A7',
 ROOM='UART_MUX',
 SEC='1',
 CDS_LIB='mstr_discrete',
 CDS_PART_NAME='LED_A1LF-GREEN,IC,D14725-022',
 PRIM_FILE='./archive_libs/mstr_discrete/led/chips/chips.prt';

PART_NAME
 DS9E1 'LED_A1LF-GREEN,IC,C97278-010':
 ROOM='BMC';

SECTION_NUMBER 1
 '@BASEBOARD_FAB2_LIB.BASEBOARD_FAB2(SCH_1):PAGE151_I144@MSTR_DISCRETE.LED(CHIPS)':
 C_PATH='@baseboard_fab2_lib.baseboard_fab2(sch_1):page151_i144@mstr_discrete.le~
d(chips)',
 P_PATH='@baseboard_fab2_lib.baseboard_fab2(sch_1):page151_i144@mstr_discrete.le~
d(chips)',
 PATH='I144',
 DRAWING='@BASEBOARD_FAB2_LIB.BASEBOARD_FAB2(SCH_1):PAGE151',
 COLOR='GREEN',
 SEC_TYPE='A1LF',
 MATERIAL='IC',
 BOM_COST='SM_CONTROLLER',
 PHYS_PAGE='151',
 XY='(-900,0)',
 ROT='0',
 VER='3',
 PACK_TYPE='A1LF',
 PART_NUMBER='C97278-010',
 LOCATION='DS9E1',
 ROOM='BMC',
 SEC='1',
 CDS_LIB='mstr_discrete',
 CDS_PART_NAME='LED_A1LF-GREEN,IC,C97278-010',
 PRIM_FILE='./archive_libs/mstr_discrete/led/chips/chips.prt';

PART_NAME
 DS9F1 'LED_A1-RED,IC,D14725-005':
 ROOM='BMC';

SECTION_NUMBER 1
 '@BASEBOARD_FAB2_LIB.BASEBOARD_FAB2(SCH_1):PAGE177_I71@MSTR_DISCRETE.LED(CHIPS)':
 C_PATH='@baseboard_fab2_lib.baseboard_fab2(sch_1):page177_i71@mstr_discrete.led~
(chips)',
 P_PATH='@baseboard_fab2_lib.baseboard_fab2(sch_1):page177_i71@mstr_discrete.led~
(chips)',
 PATH='I71',
 DRAWING='@BASEBOARD_FAB2_LIB.BASEBOARD_FAB2(SCH_1):PAGE177',
 COLOR='RED',
 SEC_TYPE='A1',
 MATERIAL='IC',
 BOM_COST='SM_CONTROLLER',
 PHYS_PAGE='177',
 XY='(-7200,8475)',
 ROT='0',
 VER='2',
 PACK_TYPE='A1',
 PART_NUMBER='D14725-005',
 LOCATION='DS9F1',
 ROOM='BMC',
 SEC='1',
 CDS_LIB='mstr_discrete',
 CDS_PART_NAME='LED_A1-RED,IC,D14725-005',
 PRIM_FILE='./archive_libs/mstr_discrete/led/chips/chips.prt';

PART_NAME
 EU1A1 'IR354XX_SM-IR35411,IC,H73688-0A':
 NO_XNET_CONNECTION='1';

SECTION_NUMBER 1
 '@BASEBOARD_FAB2_LIB.BASEBOARD_FAB2(SCH_1):PAGE227_I102@MSTR_DISCRETE.IR354XX(CHIPS)':
 C_PATH='@baseboard_fab2_lib.baseboard_fab2(sch_1):page227_i102@mstr_discrete.ir~
354xx(chips)',
 P_PATH='@baseboard_fab2_lib.baseboard_fab2(sch_1):page227_i102@mstr_discrete.ir~
354xx(chips)',
 PATH='I102',
 DRAWING='@BASEBOARD_FAB2_LIB.BASEBOARD_FAB2(SCH_1):PAGE227',
 BOM_SS='NOPOP',
 SEC_TYPE='SM',
 MATERIAL='IC',
 NO_XNET_CONNECTION='1',
 PHYS_PAGE='227',
 XY='(1825,-25)',
 ROT='0',
 VER='1',
 VALUE='IR35411',
 PACK_TYPE='SM',
 PART_NUMBER='H73688-001',
 LOCATION='EU1A1',
 SEC='1',
 CDS_LIB='mstr_discrete',
 CDS_PART_NAME='IR354XX_SM-IR35411,IC,H73688-0A',
 PRIM_FILE='./archive_libs/mstr_discrete/ir354xx/chips/chips.prt';

PART_NAME
 EU1A2 'IR354XX_SM-IR35411,IC,H73688-0A':
 NO_XNET_CONNECTION='1';

SECTION_NUMBER 1
 '@BASEBOARD_FAB2_LIB.BASEBOARD_FAB2(SCH_1):PAGE227_I101@MSTR_DISCRETE.IR354XX(CHIPS)':
 C_PATH='@baseboard_fab2_lib.baseboard_fab2(sch_1):page227_i101@mstr_discrete.ir~
354xx(chips)',
 P_PATH='@baseboard_fab2_lib.baseboard_fab2(sch_1):page227_i101@mstr_discrete.ir~
354xx(chips)',
 PATH='I101',
 DRAWING='@BASEBOARD_FAB2_LIB.BASEBOARD_FAB2(SCH_1):PAGE227',
 SEC_TYPE='SM',
 MATERIAL='IC',
 NO_XNET_CONNECTION='1',
 PHYS_PAGE='227',
 XY='(1825,2225)',
 ROT='0',
 VER='1',
 VALUE='IR35411',
 PACK_TYPE='SM',
 PART_NUMBER='H73688-001',
 LOCATION='EU1A2',
 SEC='1',
 CDS_LIB='mstr_discrete',
 CDS_PART_NAME='IR354XX_SM-IR35411,IC,H73688-0A',
 PRIM_FILE='./archive_libs/mstr_discrete/ir354xx/chips/chips.prt';

PART_NAME
 EU1B1 'PXM1310B_QFN-IC,H89186-001':;

SECTION_NUMBER 1
 '@BASEBOARD_FAB2_LIB.BASEBOARD_FAB2(SCH_1):PAGE226_I69@MSTR_CONTROLLER.PXM1310B(CHIPS)':
 C_PATH='@baseboard_fab2_lib.baseboard_fab2(sch_1):page226_i69@mstr_controller.p~
xm1310b(chips)',
 P_PATH='@baseboard_fab2_lib.baseboard_fab2(sch_1):page226_i69@mstr_controller.p~
xm1310b(chips)',
 PATH='I69',
 DRAWING='@BASEBOARD_FAB2_LIB.BASEBOARD_FAB2(SCH_1):PAGE226',
 SEC_TYPE='QFN',
 MATERIAL='IC',
 PHYS_PAGE='226',
 XY='(1175,1075)',
 ROT='0',
 VER='2',
 PACK_TYPE='QFN',
 PART_NUMBER='H89186-001',
 LOCATION='EU1B1',
 SEC='1',
 CDS_LIB='mstr_controller',
 CDS_PART_NAME='PXM1310B_QFN-IC,H89186-001',
 PRIM_FILE='./archive_libs/mstr_controller/pxm1310b/chips/chips.prt';

PART_NAME
 EU1C1 'IR354XX_SM-IR35412,IC,H73684-0A':;

SECTION_NUMBER 1
 '@BASEBOARD_FAB2_LIB.BASEBOARD_FAB2(SCH_1):PAGE210_I51@MSTR_DISCRETE.IR354XX(CHIPS)':
 C_PATH='@baseboard_fab2_lib.baseboard_fab2(sch_1):page210_i51@mstr_discrete.ir3~
54xx(chips)',
 P_PATH='@baseboard_fab2_lib.baseboard_fab2(sch_1):page210_i51@mstr_discrete.ir3~
54xx(chips)',
 PATH='I51',
 DRAWING='@BASEBOARD_FAB2_LIB.BASEBOARD_FAB2(SCH_1):PAGE210',
 SEC_TYPE='SM',
 MATERIAL='IC',
 PHYS_PAGE='210',
 XY='(-3725,3600)',
 ROT='0',
 VER='1',
 VALUE='IR35412',
 PACK_TYPE='SM',
 PART_NUMBER='H73684-001',
 LOCATION='EU1C1',
 SEC='1',
 CDS_LIB='mstr_discrete',
 CDS_PART_NAME='IR354XX_SM-IR35412,IC,H73684-0A',
 PRIM_FILE='./archive_libs/mstr_discrete/ir354xx/chips/chips.prt';

PART_NAME
 EU1C2 'PXE1610B_QFN-IC,H79206-001':;

SECTION_NUMBER 1
 '@BASEBOARD_FAB2_LIB.BASEBOARD_FAB2(SCH_1):PAGE206_I130@MSTR_CONTROLLER.PXE1610B(CHIPS)':
 C_PATH='@baseboard_fab2_lib.baseboard_fab2(sch_1):page206_i130@mstr_controller.~
pxe1610b(chips)',
 P_PATH='@baseboard_fab2_lib.baseboard_fab2(sch_1):page206_i130@mstr_controller.~
pxe1610b(chips)',
 PATH='I130',
 DRAWING='@BASEBOARD_FAB2_LIB.BASEBOARD_FAB2(SCH_1):PAGE206',
 SEC_TYPE='QFN',
 MATERIAL='IC',
 PHYS_PAGE='206',
 XY='(-3825,2625)',
 ROT='0',
 VER='1',
 PACK_TYPE='QFN',
 PART_NUMBER='H79206-001',
 LOCATION='EU1C2',
 SEC='1',
 CDS_LIB='mstr_controller',
 CDS_PART_NAME='PXE1610B_QFN-IC,H79206-001',
 PRIM_FILE='./archive_libs/mstr_controller/pxe1610b/chips/chips.prt';

PART_NAME
 EU1C3 'IR354XX_SM-IR35411,IC,H73688-0A':
 ROOM='PVCCIN_CPU1_PWR_VR';

SECTION_NUMBER 1
 '@BASEBOARD_FAB2_LIB.BASEBOARD_FAB2(SCH_1):PAGE209_I56@MSTR_DISCRETE.IR354XX(CHIPS)':
 C_PATH='@baseboard_fab2_lib.baseboard_fab2(sch_1):page209_i56@mstr_discrete.ir3~
54xx(chips)',
 P_PATH='@baseboard_fab2_lib.baseboard_fab2(sch_1):page209_i56@mstr_discrete.ir3~
54xx(chips)',
 PATH='I56',
 DRAWING='@BASEBOARD_FAB2_LIB.BASEBOARD_FAB2(SCH_1):PAGE209',
 SEC_TYPE='SM',
 MATERIAL='IC',
 PHYS_PAGE='209',
 XY='(-3250,3775)',
 ROT='0',
 VER='1',
 VALUE='IR35411',
 PACK_TYPE='SM',
 PART_NUMBER='H73688-001',
 LOCATION='EU1C3',
 ROOM='PVCCIN_CPU1_PWR_VR',
 SEC='1',
 CDS_LIB='mstr_discrete',
 CDS_PART_NAME='IR354XX_SM-IR35411,IC,H73688-0A',
 PRIM_FILE='./archive_libs/mstr_discrete/ir354xx/chips/chips.prt';

PART_NAME
 EU1D1 'IR354XX_SM-IR35411,IC,H73688-0A':
 ROOM='PVCCIN_CPU1_PWR_VR';

SECTION_NUMBER 1
 '@BASEBOARD_FAB2_LIB.BASEBOARD_FAB2(SCH_1):PAGE208_I71@MSTR_DISCRETE.IR354XX(CHIPS)':
 C_PATH='@baseboard_fab2_lib.baseboard_fab2(sch_1):page208_i71@mstr_discrete.ir3~
54xx(chips)',
 P_PATH='@baseboard_fab2_lib.baseboard_fab2(sch_1):page208_i71@mstr_discrete.ir3~
54xx(chips)',
 PATH='I71',
 DRAWING='@BASEBOARD_FAB2_LIB.BASEBOARD_FAB2(SCH_1):PAGE208',
 SEC_TYPE='SM',
 MATERIAL='IC',
 PHYS_PAGE='208',
 XY='(-3250,1275)',
 ROT='0',
 VER='1',
 VALUE='IR35411',
 PACK_TYPE='SM',
 PART_NUMBER='H73688-001',
 LOCATION='EU1D1',
 ROOM='PVCCIN_CPU1_PWR_VR',
 SEC='1',
 CDS_LIB='mstr_discrete',
 CDS_PART_NAME='IR354XX_SM-IR35411,IC,H73688-0A',
 PRIM_FILE='./archive_libs/mstr_discrete/ir354xx/chips/chips.prt';

PART_NAME
 EU1D2 'ADM1278_SM-IC,G99251-001':
 ROOM='HOT_SWAP';

SECTION_NUMBER 1
 '@BASEBOARD_FAB2_LIB.BASEBOARD_FAB2(SCH_1):PAGE199_I10@MSTR_CONTROLLER.ADM1278(CHIPS)':
 C_PATH='@baseboard_fab2_lib.baseboard_fab2(sch_1):page199_i10@mstr_controller.a~
dm1278(chips)',
 P_PATH='@baseboard_fab2_lib.baseboard_fab2(sch_1):page199_i10@mstr_controller.a~
dm1278(chips)',
 PATH='I10',
 DRAWING='@BASEBOARD_FAB2_LIB.BASEBOARD_FAB2(SCH_1):PAGE199',
 SEC_TYPE='SM',
 MATERIAL='IC',
 PHYS_PAGE='199',
 XY='(-3250,2575)',
 ROT='0',
 VER='1',
 PACK_TYPE='SM',
 PART_NUMBER='G99251-001',
 LOCATION='EU1D2',
 ROOM='HOT_SWAP',
 SEC='1',
 CDS_LIB='mstr_controller',
 CDS_PART_NAME='ADM1278_SM-IC,G99251-001',
 PRIM_FILE='./archive_libs/mstr_controller/adm1278/chips/chips.prt';

PART_NAME
 EU1D3 'IR354XX_SM-IR35411,IC,H73688-0A':
 ROOM='PVCCIN_CPU1_PWR_VR';

SECTION_NUMBER 1
 '@BASEBOARD_FAB2_LIB.BASEBOARD_FAB2(SCH_1):PAGE208_I27@MSTR_DISCRETE.IR354XX(CHIPS)':
 C_PATH='@baseboard_fab2_lib.baseboard_fab2(sch_1):page208_i27@mstr_discrete.ir3~
54xx(chips)',
 P_PATH='@baseboard_fab2_lib.baseboard_fab2(sch_1):page208_i27@mstr_discrete.ir3~
54xx(chips)',
 PATH='I27',
 DRAWING='@BASEBOARD_FAB2_LIB.BASEBOARD_FAB2(SCH_1):PAGE208',
 SEC_TYPE='SM',
 MATERIAL='IC',
 PHYS_PAGE='208',
 XY='(-3300,3875)',
 ROT='0',
 VER='1',
 VALUE='IR35411',
 PACK_TYPE='SM',
 PART_NUMBER='H73688-001',
 LOCATION='EU1D3',
 ROOM='PVCCIN_CPU1_PWR_VR',
 SEC='1',
 CDS_LIB='mstr_discrete',
 CDS_PART_NAME='IR354XX_SM-IR35411,IC,H73688-0A',
 PRIM_FILE='./archive_libs/mstr_discrete/ir354xx/chips/chips.prt';

PART_NAME
 EU1D4 'IR354XX_SM-IR35411,IC,H73688-0A':
 ROOM='PVCCIN_CPU1_PWR_VR';

SECTION_NUMBER 1
 '@BASEBOARD_FAB2_LIB.BASEBOARD_FAB2(SCH_1):PAGE207_I113@MSTR_DISCRETE.IR354XX(CHIPS)':
 C_PATH='@baseboard_fab2_lib.baseboard_fab2(sch_1):page207_i113@mstr_discrete.ir~
354xx(chips)',
 P_PATH='@baseboard_fab2_lib.baseboard_fab2(sch_1):page207_i113@mstr_discrete.ir~
354xx(chips)',
 PATH='I113',
 DRAWING='@BASEBOARD_FAB2_LIB.BASEBOARD_FAB2(SCH_1):PAGE207',
 SEC_TYPE='SM',
 MATERIAL='IC',
 PHYS_PAGE='207',
 XY='(-3150,1250)',
 ROT='0',
 VER='1',
 VALUE='IR35411',
 PACK_TYPE='SM',
 PART_NUMBER='H73688-001',
 LOCATION='EU1D4',
 ROOM='PVCCIN_CPU1_PWR_VR',
 SEC='1',
 CDS_LIB='mstr_discrete',
 CDS_PART_NAME='IR354XX_SM-IR35411,IC,H73688-0A',
 PRIM_FILE='./archive_libs/mstr_discrete/ir354xx/chips/chips.prt';

PART_NAME
 EU1E1 'MOSFETN_1D3S_SOT5-IC,G68777-001':
 ROOM='HOT_SWAP';

SECTION_NUMBER 1
 '@BASEBOARD_FAB2_LIB.BASEBOARD_FAB2(SCH_1):PAGE200_I59@MSTR_DISCRETE.MOSFETN_1D3S(CHIPS)':
 C_PATH='@baseboard_fab2_lib.baseboard_fab2(sch_1):page200_i59@mstr_discrete.mos~
fetn_1d3s(chips)',
 P_PATH='@baseboard_fab2_lib.baseboard_fab2(sch_1):page200_i59@mstr_discrete.mos~
fetn_1d3s(chips)',
 PATH='I59',
 DRAWING='@BASEBOARD_FAB2_LIB.BASEBOARD_FAB2(SCH_1):PAGE200',
 SEC_TYPE='SOT5',
 MATERIAL='IC',
 PHYS_PAGE='200',
 XY='(2275,2100)',
 ROT='1',
 VER='1',
 PACK_TYPE='SOT5',
 PART_NUMBER='G68777-001',
 LOCATION='EU1E1',
 ROOM='HOT_SWAP',
 SEC='1',
 CDS_LIB='mstr_discrete',
 CDS_PART_NAME='MOSFETN_1D3S_SOT5-IC,G68777-001',
 PRIM_FILE='./archive_libs/mstr_discrete/mosfetn_1d3s/chips/chips.prt';

PART_NAME
 EU1E2 'IR354XX_SM-IR35411,IC,H73688-0A':
 ROOM='PVCCIN_CPU1_PWR_VR';

SECTION_NUMBER 1
 '@BASEBOARD_FAB2_LIB.BASEBOARD_FAB2(SCH_1):PAGE207_I20@MSTR_DISCRETE.IR354XX(CHIPS)':
 C_PATH='@baseboard_fab2_lib.baseboard_fab2(sch_1):page207_i20@mstr_discrete.ir3~
54xx(chips)',
 P_PATH='@baseboard_fab2_lib.baseboard_fab2(sch_1):page207_i20@mstr_discrete.ir3~
54xx(chips)',
 PATH='I20',
 DRAWING='@BASEBOARD_FAB2_LIB.BASEBOARD_FAB2(SCH_1):PAGE207',
 SEC_TYPE='SM',
 MATERIAL='IC',
 PHYS_PAGE='207',
 XY='(-3125,3850)',
 ROT='0',
 VER='1',
 VALUE='IR35411',
 PACK_TYPE='SM',
 PART_NUMBER='H73688-001',
 LOCATION='EU1E2',
 ROOM='PVCCIN_CPU1_PWR_VR',
 SEC='1',
 CDS_LIB='mstr_discrete',
 CDS_PART_NAME='IR354XX_SM-IR35411,IC,H73688-0A',
 PRIM_FILE='./archive_libs/mstr_discrete/ir354xx/chips/chips.prt';

PART_NAME
 EU1E3 'MOSFETN_1D3S_SOT5-IC,G68777-001':
 ROOM='HOT_SWAP';

SECTION_NUMBER 1
 '@BASEBOARD_FAB2_LIB.BASEBOARD_FAB2(SCH_1):PAGE200_I54@MSTR_DISCRETE.MOSFETN_1D3S(CHIPS)':
 C_PATH='@baseboard_fab2_lib.baseboard_fab2(sch_1):page200_i54@mstr_discrete.mos~
fetn_1d3s(chips)',
 P_PATH='@baseboard_fab2_lib.baseboard_fab2(sch_1):page200_i54@mstr_discrete.mos~
fetn_1d3s(chips)',
 PATH='I54',
 DRAWING='@BASEBOARD_FAB2_LIB.BASEBOARD_FAB2(SCH_1):PAGE200',
 SEC_TYPE='SOT5',
 MATERIAL='IC',
 PHYS_PAGE='200',
 XY='(2275,3375)',
 ROT='1',
 VER='1',
 PACK_TYPE='SOT5',
 PART_NUMBER='G68777-001',
 LOCATION='EU1E3',
 ROOM='HOT_SWAP',
 SEC='1',
 CDS_LIB='mstr_discrete',
 CDS_PART_NAME='MOSFETN_1D3S_SOT5-IC,G68777-001',
 PRIM_FILE='./archive_libs/mstr_discrete/mosfetn_1d3s/chips/chips.prt';

PART_NAME
 EU1F1 'IR354XX_SM-IR35411,IC,H73688-0A':;

SECTION_NUMBER 1
 '@BASEBOARD_FAB2_LIB.BASEBOARD_FAB2(SCH_1):PAGE224_I111@MSTR_DISCRETE.IR354XX(CHIPS)':
 C_PATH='@baseboard_fab2_lib.baseboard_fab2(sch_1):page224_i111@mstr_discrete.ir~
354xx(chips)',
 P_PATH='@baseboard_fab2_lib.baseboard_fab2(sch_1):page224_i111@mstr_discrete.ir~
354xx(chips)',
 PATH='I111',
 DRAWING='@BASEBOARD_FAB2_LIB.BASEBOARD_FAB2(SCH_1):PAGE224',
 BOM_SS='NOPOP',
 SEC_TYPE='SM',
 MATERIAL='IC',
 PHYS_PAGE='224',
 XY='(1850,-125)',
 ROT='0',
 VER='1',
 VALUE='IR35411',
 PACK_TYPE='SM',
 PART_NUMBER='H73688-001',
 LOCATION='EU1F1',
 SEC='1',
 CDS_LIB='mstr_discrete',
 CDS_PART_NAME='IR354XX_SM-IR35411,IC,H73688-0A',
 PRIM_FILE='./archive_libs/mstr_discrete/ir354xx/chips/chips.prt';

PART_NAME
 EU1G1 'IR354XX_SM-IR35411,IC,H73688-0A':
 NO_XNET_CONNECTION='1';

SECTION_NUMBER 1
 '@BASEBOARD_FAB2_LIB.BASEBOARD_FAB2(SCH_1):PAGE224_I110@MSTR_DISCRETE.IR354XX(CHIPS)':
 C_PATH='@baseboard_fab2_lib.baseboard_fab2(sch_1):page224_i110@mstr_discrete.ir~
354xx(chips)',
 P_PATH='@baseboard_fab2_lib.baseboard_fab2(sch_1):page224_i110@mstr_discrete.ir~
354xx(chips)',
 PATH='I110',
 DRAWING='@BASEBOARD_FAB2_LIB.BASEBOARD_FAB2(SCH_1):PAGE224',
 SEC_TYPE='SM',
 MATERIAL='IC',
 NO_XNET_CONNECTION='1',
 PHYS_PAGE='224',
 XY='(1825,2250)',
 ROT='0',
 VER='1',
 VALUE='IR35411',
 PACK_TYPE='SM',
 PART_NUMBER='H73688-001',
 LOCATION='EU1G1',
 SEC='1',
 CDS_LIB='mstr_discrete',
 CDS_PART_NAME='IR354XX_SM-IR35411,IC,H73688-0A',
 PRIM_FILE='./archive_libs/mstr_discrete/ir354xx/chips/chips.prt';

PART_NAME
 EU1G2 'PXM1310B_QFN-IC,H89186-001':;

SECTION_NUMBER 1
 '@BASEBOARD_FAB2_LIB.BASEBOARD_FAB2(SCH_1):PAGE223_I69@MSTR_CONTROLLER.PXM1310B(CHIPS)':
 C_PATH='@baseboard_fab2_lib.baseboard_fab2(sch_1):page223_i69@mstr_controller.p~
xm1310b(chips)',
 P_PATH='@baseboard_fab2_lib.baseboard_fab2(sch_1):page223_i69@mstr_controller.p~
xm1310b(chips)',
 PATH='I69',
 DRAWING='@BASEBOARD_FAB2_LIB.BASEBOARD_FAB2(SCH_1):PAGE223',
 SEC_TYPE='QFN',
 MATERIAL='IC',
 PHYS_PAGE='223',
 XY='(1500,1450)',
 ROT='0',
 VER='2',
 PACK_TYPE='QFN',
 PART_NUMBER='H89186-001',
 LOCATION='EU1G2',
 SEC='1',
 CDS_LIB='mstr_controller',
 CDS_PART_NAME='PXM1310B_QFN-IC,H89186-001',
 PRIM_FILE='./archive_libs/mstr_controller/pxm1310b/chips/chips.prt';

PART_NAME
 EU2T1 'SLG55021_SM-IC,G56246-001':
 ROOM='P3V3_PWR_SWITCH';

SECTION_NUMBER 1
 '@BASEBOARD_FAB2_LIB.BASEBOARD_FAB2(SCH_1):PAGE198_I1@MSTR_VREG.SLG55021(CHIPS)':
 C_PATH='@baseboard_fab2_lib.baseboard_fab2(sch_1):page198_i1@mstr_vreg.slg55021~
(chips)',
 P_PATH='@baseboard_fab2_lib.baseboard_fab2(sch_1):page198_i1@mstr_vreg.slg55021~
(chips)',
 PATH='I1',
 DRAWING='@BASEBOARD_FAB2_LIB.BASEBOARD_FAB2(SCH_1):PAGE198',
 MATERIAL='IC',
 PHYS_PAGE='198',
 XY='(-7000,3825)',
 ROT='0',
 VER='1',
 PACK_TYPE='SM',
 PART_NUMBER='G56246-001',
 LOCATION='EU2T1',
 ROOM='P3V3_PWR_SWITCH',
 CDS_LIB='mstr_vreg',
 CDS_PART_NAME='SLG55021_SM-IC,G56246-001',
 PRIM_FILE='./archive_libs/mstr_vreg/slg55021/chips/chips.prt';

PART_NAME
 EU3P1 'PXE1110B_QFN-IC,H89187-001':;

SECTION_NUMBER 1
 '@BASEBOARD_FAB2_LIB.BASEBOARD_FAB2(SCH_1):PAGE211_I93@MSTR_CONTROLLER.PXE1110B(CHIPS)':
 C_PATH='@baseboard_fab2_lib.baseboard_fab2(sch_1):page211_i93@mstr_controller.p~
xe1110b(chips)',
 P_PATH='@baseboard_fab2_lib.baseboard_fab2(sch_1):page211_i93@mstr_controller.p~
xe1110b(chips)',
 PATH='I93',
 DRAWING='@BASEBOARD_FAB2_LIB.BASEBOARD_FAB2(SCH_1):PAGE211',
 SEC_TYPE='QFN',
 MATERIAL='IC',
 PHYS_PAGE='211',
 XY='(100,2850)',
 ROT='0',
 VER='1',
 PACK_TYPE='QFN',
 PART_NUMBER='H89187-001',
 LOCATION='EU3P1',
 SEC='1',
 CDS_LIB='mstr_controller',
 CDS_PART_NAME='PXE1110B_QFN-IC,H89187-001',
 PRIM_FILE='./archive_libs/mstr_controller/pxe1110b/chips/chips.prt';

PART_NAME
 EU4A1 'MIC5166_DFN-IC,H55101-001':
 ROOM='VTT_DEF_PWR_VR';

SECTION_NUMBER 1
 '@BASEBOARD_FAB2_LIB.BASEBOARD_FAB2(SCH_1):PAGE222_I13@MSTR_VREG.MIC5166(CHIPS)':
 C_PATH='@baseboard_fab2_lib.baseboard_fab2(sch_1):page222_i13@mstr_vreg.mic5166~
(chips)',
 P_PATH='@baseboard_fab2_lib.baseboard_fab2(sch_1):page222_i13@mstr_vreg.mic5166~
(chips)',
 PATH='I13',
 DRAWING='@BASEBOARD_FAB2_LIB.BASEBOARD_FAB2(SCH_1):PAGE222',
 SEC_TYPE='DFN',
 MATERIAL='IC',
 BOM_COST='MEM_VRD_VTT_DEF',
 PHYS_PAGE='222',
 XY='(775,600)',
 ROT='0',
 VER='1',
 PACK_TYPE='DFN',
 PART_NUMBER='H55101-001',
 LOCATION='EU4A1',
 ROOM='VTT_DEF_PWR_VR',
 SEC='1',
 CDS_LIB='mstr_vreg',
 CDS_PART_NAME='MIC5166_DFN-IC,H55101-001',
 PRIM_FILE='./archive_libs/mstr_vreg/mic5166/chips/chips.prt';

PART_NAME
 EU4A2 'MIC5166_DFN-IC,H55101-001':
 ROOM='VTT_KLM_PWR_VR';

SECTION_NUMBER 1
 '@BASEBOARD_FAB2_LIB.BASEBOARD_FAB2(SCH_1):PAGE230_I37@MSTR_VREG.MIC5166(CHIPS)':
 C_PATH='@baseboard_fab2_lib.baseboard_fab2(sch_1):page230_i37@mstr_vreg.mic5166~
(chips)',
 P_PATH='@baseboard_fab2_lib.baseboard_fab2(sch_1):page230_i37@mstr_vreg.mic5166~
(chips)',
 PATH='I37',
 DRAWING='@BASEBOARD_FAB2_LIB.BASEBOARD_FAB2(SCH_1):PAGE230',
 SEC_TYPE='DFN',
 MATERIAL='IC',
 BOM_COST='MEM_VRD_VTT_KLM',
 PHYS_PAGE='230',
 XY='(-100,325)',
 ROT='0',
 VER='1',
 PACK_TYPE='DFN',
 PART_NUMBER='H55101-001',
 LOCATION='EU4A2',
 ROOM='VTT_KLM_PWR_VR',
 SEC='1',
 CDS_LIB='mstr_vreg',
 CDS_PART_NAME='MIC5166_DFN-IC,H55101-001',
 PRIM_FILE='./archive_libs/mstr_vreg/mic5166/chips/chips.prt';

PART_NAME
 EU4A3 'NCP3232L_SM-IC,H86355-001':;

SECTION_NUMBER 1
 '@BASEBOARD_FAB2_LIB.BASEBOARD_FAB2(SCH_1):PAGE234_I184@MSTR_VREG.NCP3232L(CHIPS)':
 C_PATH='@baseboard_fab2_lib.baseboard_fab2(sch_1):page234_i184@mstr_vreg.ncp323~
2l(chips)',
 P_PATH='@baseboard_fab2_lib.baseboard_fab2(sch_1):page234_i184@mstr_vreg.ncp323~
2l(chips)',
 PATH='I184',
 DRAWING='@BASEBOARD_FAB2_LIB.BASEBOARD_FAB2(SCH_1):PAGE234',
 SEC_TYPE='SM',
 MATERIAL='IC',
 PHYS_PAGE='234',
 XY='(-3800,2875)',
 ROT='0',
 VER='1',
 PACK_TYPE='SM',
 PART_NUMBER='H86355-001',
 LOCATION='EU4A3',
 SEC='1',
 CDS_LIB='mstr_vreg',
 CDS_PART_NAME='NCP3232L_SM-IC,H86355-001',
 PRIM_FILE='./archive_libs/mstr_vreg/ncp3232l/chips/chips.prt';

PART_NAME
 EU4C1 'IR354XX_SM-IR35412,IC,H73684-0A':;

SECTION_NUMBER 1
 '@BASEBOARD_FAB2_LIB.BASEBOARD_FAB2(SCH_1):PAGE205_I46@MSTR_DISCRETE.IR354XX(CHIPS)':
 C_PATH='@baseboard_fab2_lib.baseboard_fab2(sch_1):page205_i46@mstr_discrete.ir3~
54xx(chips)',
 P_PATH='@baseboard_fab2_lib.baseboard_fab2(sch_1):page205_i46@mstr_discrete.ir3~
54xx(chips)',
 PATH='I46',
 DRAWING='@BASEBOARD_FAB2_LIB.BASEBOARD_FAB2(SCH_1):PAGE205',
 MATERIAL='IC',
 PHYS_PAGE='205',
 XY='(-3150,3925)',
 ROT='0',
 VER='1',
 VALUE='IR35412',
 PACK_TYPE='SM',
 PART_NUMBER='H73684-001',
 LOCATION='EU4C1',
 CDS_LIB='mstr_discrete',
 CDS_PART_NAME='IR354XX_SM-IR35412,IC,H73684-0A',
 PRIM_FILE='./archive_libs/mstr_discrete/ir354xx/chips/chips.prt';

PART_NAME
 EU4C2 'IR354XX_SM-IR35411,IC,H73688-0A':;

SECTION_NUMBER 1
 '@BASEBOARD_FAB2_LIB.BASEBOARD_FAB2(SCH_1):PAGE204_I71@MSTR_DISCRETE.IR354XX(CHIPS)':
 C_PATH='@baseboard_fab2_lib.baseboard_fab2(sch_1):page204_i71@mstr_discrete.ir3~
54xx(chips)',
 P_PATH='@baseboard_fab2_lib.baseboard_fab2(sch_1):page204_i71@mstr_discrete.ir3~
54xx(chips)',
 PATH='I71',
 DRAWING='@BASEBOARD_FAB2_LIB.BASEBOARD_FAB2(SCH_1):PAGE204',
 MATERIAL='IC',
 PHYS_PAGE='204',
 XY='(-3125,3925)',
 ROT='0',
 VER='1',
 VALUE='IR35411',
 PACK_TYPE='SM',
 PART_NUMBER='H73688-001',
 LOCATION='EU4C2',
 CDS_LIB='mstr_discrete',
 CDS_PART_NAME='IR354XX_SM-IR35411,IC,H73688-0A',
 PRIM_FILE='./archive_libs/mstr_discrete/ir354xx/chips/chips.prt';

PART_NAME
 EU4D1 'IR354XX_SM-IR35411,IC,H73688-0A':;

SECTION_NUMBER 1
 '@BASEBOARD_FAB2_LIB.BASEBOARD_FAB2(SCH_1):PAGE203_I71@MSTR_DISCRETE.IR354XX(CHIPS)':
 C_PATH='@baseboard_fab2_lib.baseboard_fab2(sch_1):page203_i71@mstr_discrete.ir3~
54xx(chips)',
 P_PATH='@baseboard_fab2_lib.baseboard_fab2(sch_1):page203_i71@mstr_discrete.ir3~
54xx(chips)',
 PATH='I71',
 DRAWING='@BASEBOARD_FAB2_LIB.BASEBOARD_FAB2(SCH_1):PAGE203',
 MATERIAL='IC',
 PHYS_PAGE='203',
 XY='(-3125,1200)',
 ROT='0',
 VER='1',
 VALUE='IR35411',
 PACK_TYPE='SM',
 PART_NUMBER='H73688-001',
 LOCATION='EU4D1',
 CDS_LIB='mstr_discrete',
 CDS_PART_NAME='IR354XX_SM-IR35411,IC,H73688-0A',
 PRIM_FILE='./archive_libs/mstr_discrete/ir354xx/chips/chips.prt';

PART_NAME
 EU4D2 'NB3W1200L_LCC-IC,H13585-001':
 ROOM='DB1200ZL';

SECTION_NUMBER 1
 '@BASEBOARD_FAB2_LIB.BASEBOARD_FAB2(SCH_1):PAGE102_I1@MSTR_CLOCK.NB3W1200L(CHIPS)':
 C_PATH='@baseboard_fab2_lib.baseboard_fab2(sch_1):page102_i1@mstr_clock.nb3w120~
0l(chips)',
 P_PATH='@baseboard_fab2_lib.baseboard_fab2(sch_1):page102_i1@mstr_clock.nb3w120~
0l(chips)',
 PATH='I1',
 DRAWING='@BASEBOARD_FAB2_LIB.BASEBOARD_FAB2(SCH_1):PAGE102',
 SEC_TYPE='LCC',
 MATERIAL='IC',
 BOM_COST='SYS_CLOCK',
 PHYS_PAGE='102',
 XY='(350,2900)',
 ROT='0',
 VER='1',
 PACK_TYPE='LCC',
 PART_NUMBER='H13585-001',
 LOCATION='EU4D2',
 ROOM='DB1200ZL',
 SEC='1',
 CDS_LIB='mstr_clock',
 CDS_PART_NAME='NB3W1200L_LCC-IC,H13585-001',
 PRIM_FILE='./archive_libs/mstr_clock/nb3w1200l/chips/chips.prt';

PART_NAME
 EU4D3 'IR354XX_SM-IR35411,IC,H73688-0A':;

SECTION_NUMBER 1
 '@BASEBOARD_FAB2_LIB.BASEBOARD_FAB2(SCH_1):PAGE203_I70@MSTR_DISCRETE.IR354XX(CHIPS)':
 C_PATH='@baseboard_fab2_lib.baseboard_fab2(sch_1):page203_i70@mstr_discrete.ir3~
54xx(chips)',
 P_PATH='@baseboard_fab2_lib.baseboard_fab2(sch_1):page203_i70@mstr_discrete.ir3~
54xx(chips)',
 PATH='I70',
 DRAWING='@BASEBOARD_FAB2_LIB.BASEBOARD_FAB2(SCH_1):PAGE203',
 SEC_TYPE='SM',
 MATERIAL='IC',
 PHYS_PAGE='203',
 XY='(-3100,3925)',
 ROT='0',
 VER='1',
 VALUE='IR35411',
 PACK_TYPE='SM',
 PART_NUMBER='H73688-001',
 LOCATION='EU4D3',
 SEC='1',
 CDS_LIB='mstr_discrete',
 CDS_PART_NAME='IR354XX_SM-IR35411,IC,H73688-0A',
 PRIM_FILE='./archive_libs/mstr_discrete/ir354xx/chips/chips.prt';

PART_NAME
 EU4D4 'PXE1610B_QFN-IC,H79206-001':;

SECTION_NUMBER 1
 '@BASEBOARD_FAB2_LIB.BASEBOARD_FAB2(SCH_1):PAGE201_I155@MSTR_CONTROLLER.PXE1610B(CHIPS)':
 C_PATH='@baseboard_fab2_lib.baseboard_fab2(sch_1):page201_i155@mstr_controller.~
pxe1610b(chips)',
 P_PATH='@baseboard_fab2_lib.baseboard_fab2(sch_1):page201_i155@mstr_controller.~
pxe1610b(chips)',
 PATH='I155',
 DRAWING='@BASEBOARD_FAB2_LIB.BASEBOARD_FAB2(SCH_1):PAGE201',
 MATERIAL='IC',
 PHYS_PAGE='201',
 XY='(-3800,2575)',
 ROT='0',
 VER='1',
 PACK_TYPE='QFN',
 PART_NUMBER='H79206-001',
 LOCATION='EU4D4',
 CDS_LIB='mstr_controller',
 CDS_PART_NAME='PXE1610B_QFN-IC,H79206-001',
 PRIM_FILE='./archive_libs/mstr_controller/pxe1610b/chips/chips.prt';

PART_NAME
 EU4D5 'PXE1110B_QFN-IC,H89187-001':;

SECTION_NUMBER 1
 '@BASEBOARD_FAB2_LIB.BASEBOARD_FAB2(SCH_1):PAGE213_I96@MSTR_CONTROLLER.PXE1110B(CHIPS)':
 C_PATH='@baseboard_fab2_lib.baseboard_fab2(sch_1):page213_i96@mstr_controller.p~
xe1110b(chips)',
 P_PATH='@baseboard_fab2_lib.baseboard_fab2(sch_1):page213_i96@mstr_controller.p~
xe1110b(chips)',
 PATH='I96',
 DRAWING='@BASEBOARD_FAB2_LIB.BASEBOARD_FAB2(SCH_1):PAGE213',
 SEC_TYPE='QFN',
 MATERIAL='IC',
 PHYS_PAGE='213',
 XY='(175,2825)',
 ROT='0',
 VER='1',
 PACK_TYPE='QFN',
 PART_NUMBER='H89187-001',
 LOCATION='EU4D5',
 SEC='1',
 CDS_LIB='mstr_controller',
 CDS_PART_NAME='PXE1110B_QFN-IC,H89187-001',
 PRIM_FILE='./archive_libs/mstr_controller/pxe1110b/chips/chips.prt';

PART_NAME
 EU4D6 'IR354XX_SM-IR35411,IC,H73688-0A':;

SECTION_NUMBER 1
 '@BASEBOARD_FAB2_LIB.BASEBOARD_FAB2(SCH_1):PAGE202_I64@MSTR_DISCRETE.IR354XX(CHIPS)':
 C_PATH='@baseboard_fab2_lib.baseboard_fab2(sch_1):page202_i64@mstr_discrete.ir3~
54xx(chips)',
 P_PATH='@baseboard_fab2_lib.baseboard_fab2(sch_1):page202_i64@mstr_discrete.ir3~
54xx(chips)',
 PATH='I64',
 DRAWING='@BASEBOARD_FAB2_LIB.BASEBOARD_FAB2(SCH_1):PAGE202',
 MATERIAL='IC',
 PHYS_PAGE='202',
 XY='(-3475,1175)',
 ROT='0',
 VER='1',
 VALUE='IR35411',
 PACK_TYPE='SM',
 PART_NUMBER='H73688-001',
 LOCATION='EU4D6',
 CDS_LIB='mstr_discrete',
 CDS_PART_NAME='IR354XX_SM-IR35411,IC,H73688-0A',
 PRIM_FILE='./archive_libs/mstr_discrete/ir354xx/chips/chips.prt';

PART_NAME
 EU4E1 'IR354XX_SM-IR35411,IC,H73688-0A':;

SECTION_NUMBER 1
 '@BASEBOARD_FAB2_LIB.BASEBOARD_FAB2(SCH_1):PAGE202_I63@MSTR_DISCRETE.IR354XX(CHIPS)':
 C_PATH='@baseboard_fab2_lib.baseboard_fab2(sch_1):page202_i63@mstr_discrete.ir3~
54xx(chips)',
 P_PATH='@baseboard_fab2_lib.baseboard_fab2(sch_1):page202_i63@mstr_discrete.ir3~
54xx(chips)',
 PATH='I63',
 DRAWING='@BASEBOARD_FAB2_LIB.BASEBOARD_FAB2(SCH_1):PAGE202',
 MATERIAL='IC',
 PHYS_PAGE='202',
 XY='(-3425,3800)',
 ROT='0',
 VER='1',
 VALUE='IR35411',
 PACK_TYPE='SM',
 PART_NUMBER='H73688-001',
 LOCATION='EU4E1',
 CDS_LIB='mstr_discrete',
 CDS_PART_NAME='IR354XX_SM-IR35411,IC,H73688-0A',
 PRIM_FILE='./archive_libs/mstr_discrete/ir354xx/chips/chips.prt';

PART_NAME
 EU4E2 'IR354XX_SM-IR35412,IC,H73684-0A':
 NO_XNET_CONNECTION='1';

SECTION_NUMBER 1
 '@BASEBOARD_FAB2_LIB.BASEBOARD_FAB2(SCH_1):PAGE214_I126@MSTR_DISCRETE.IR354XX(CHIPS)':
 C_PATH='@baseboard_fab2_lib.baseboard_fab2(sch_1):page214_i126@mstr_discrete.ir~
354xx(chips)',
 P_PATH='@baseboard_fab2_lib.baseboard_fab2(sch_1):page214_i126@mstr_discrete.ir~
354xx(chips)',
 PATH='I126',
 DRAWING='@BASEBOARD_FAB2_LIB.BASEBOARD_FAB2(SCH_1):PAGE214',
 SEC_TYPE='SM',
 MATERIAL='IC',
 NO_XNET_CONNECTION='1',
 PHYS_PAGE='214',
 XY='(1075,3925)',
 ROT='0',
 VER='1',
 VALUE='IR35412',
 PACK_TYPE='SM',
 PART_NUMBER='H73684-001',
 LOCATION='EU4E2',
 SEC='1',
 CDS_LIB='mstr_discrete',
 CDS_PART_NAME='IR354XX_SM-IR35412,IC,H73684-0A',
 PRIM_FILE='./archive_libs/mstr_discrete/ir354xx/chips/chips.prt';

PART_NAME
 EU4G1 'NCP3232L_SM-IC,H86355-001':;

SECTION_NUMBER 1
 '@BASEBOARD_FAB2_LIB.BASEBOARD_FAB2(SCH_1):PAGE233_I225@MSTR_VREG.NCP3232L(CHIPS)':
 C_PATH='@baseboard_fab2_lib.baseboard_fab2(sch_1):page233_i225@mstr_vreg.ncp323~
2l(chips)',
 P_PATH='@baseboard_fab2_lib.baseboard_fab2(sch_1):page233_i225@mstr_vreg.ncp323~
2l(chips)',
 PATH='I225',
 DRAWING='@BASEBOARD_FAB2_LIB.BASEBOARD_FAB2(SCH_1):PAGE233',
 SEC_TYPE='SM',
 MATERIAL='IC',
 PHYS_PAGE='233',
 XY='(-3725,2725)',
 ROT='0',
 VER='1',
 PACK_TYPE='SM',
 PART_NUMBER='H86355-001',
 LOCATION='EU4G1',
 SEC='1',
 CDS_LIB='mstr_vreg',
 CDS_PART_NAME='NCP3232L_SM-IC,H86355-001',
 PRIM_FILE='./archive_libs/mstr_vreg/ncp3232l/chips/chips.prt';

PART_NAME
 EU4G2 'MIC5166_DFN-IC,H55101-001':
 ROOM='VTT_GHJ_PWR_VR';

SECTION_NUMBER 1
 '@BASEBOARD_FAB2_LIB.BASEBOARD_FAB2(SCH_1):PAGE229_I37@MSTR_VREG.MIC5166(CHIPS)':
 C_PATH='@baseboard_fab2_lib.baseboard_fab2(sch_1):page229_i37@mstr_vreg.mic5166~
(chips)',
 P_PATH='@baseboard_fab2_lib.baseboard_fab2(sch_1):page229_i37@mstr_vreg.mic5166~
(chips)',
 PATH='I37',
 DRAWING='@BASEBOARD_FAB2_LIB.BASEBOARD_FAB2(SCH_1):PAGE229',
 SEC_TYPE='DFN',
 MATERIAL='IC',
 BOM_COST='MEM_VRD_VTT_GHJ',
 PHYS_PAGE='229',
 XY='(1425,900)',
 ROT='0',
 VER='1',
 PACK_TYPE='DFN',
 PART_NUMBER='H55101-001',
 LOCATION='EU4G2',
 ROOM='VTT_GHJ_PWR_VR',
 SEC='1',
 CDS_LIB='mstr_vreg',
 CDS_PART_NAME='MIC5166_DFN-IC,H55101-001',
 PRIM_FILE='./archive_libs/mstr_vreg/mic5166/chips/chips.prt';

PART_NAME
 EU4G3 'MIC5166_DFN-IC,H55101-001':
 ROOM='VTT_ABC_PWR_VR';

SECTION_NUMBER 1
 '@BASEBOARD_FAB2_LIB.BASEBOARD_FAB2(SCH_1):PAGE221_I15@MSTR_VREG.MIC5166(CHIPS)':
 C_PATH='@baseboard_fab2_lib.baseboard_fab2(sch_1):page221_i15@mstr_vreg.mic5166~
(chips)',
 P_PATH='@baseboard_fab2_lib.baseboard_fab2(sch_1):page221_i15@mstr_vreg.mic5166~
(chips)',
 PATH='I15',
 DRAWING='@BASEBOARD_FAB2_LIB.BASEBOARD_FAB2(SCH_1):PAGE221',
 SEC_TYPE='DFN',
 MATERIAL='IC',
 BOM_COST='MEM_VRD_VTT_ABC',
 PHYS_PAGE='221',
 XY='(1275,975)',
 ROT='0',
 VER='1',
 PACK_TYPE='DFN',
 PART_NUMBER='H55101-001',
 LOCATION='EU4G3',
 ROOM='VTT_ABC_PWR_VR',
 SEC='1',
 CDS_LIB='mstr_vreg',
 CDS_PART_NAME='MIC5166_DFN-IC,H55101-001',
 PRIM_FILE='./archive_libs/mstr_vreg/mic5166/chips/chips.prt';

PART_NAME
 EU7A1 'IR354XX_SM-IR35411,IC,H73688-0A':
 NO_XNET_CONNECTION='1';

SECTION_NUMBER 1
 '@BASEBOARD_FAB2_LIB.BASEBOARD_FAB2(SCH_1):PAGE219_I106@MSTR_DISCRETE.IR354XX(CHIPS)':
 C_PATH='@baseboard_fab2_lib.baseboard_fab2(sch_1):page219_i106@mstr_discrete.ir~
354xx(chips)',
 P_PATH='@baseboard_fab2_lib.baseboard_fab2(sch_1):page219_i106@mstr_discrete.ir~
354xx(chips)',
 PATH='I106',
 DRAWING='@BASEBOARD_FAB2_LIB.BASEBOARD_FAB2(SCH_1):PAGE219',
 SEC_TYPE='SM',
 MATERIAL='IC',
 NO_XNET_CONNECTION='1',
 PHYS_PAGE='219',
 XY='(1750,2125)',
 ROT='0',
 VER='1',
 VALUE='IR35411',
 PACK_TYPE='SM',
 PART_NUMBER='H73688-001',
 LOCATION='EU7A1',
 SEC='1',
 CDS_LIB='mstr_discrete',
 CDS_PART_NAME='IR354XX_SM-IR35411,IC,H73688-0A',
 PRIM_FILE='./archive_libs/mstr_discrete/ir354xx/chips/chips.prt';

PART_NAME
 EU7A2 'IR354XX_SM-IR35412,IC,H73684-0A':
 NO_XNET_CONNECTION='1';

SECTION_NUMBER 1
 '@BASEBOARD_FAB2_LIB.BASEBOARD_FAB2(SCH_1):PAGE236_I117@MSTR_DISCRETE.IR354XX(CHIPS)':
 C_PATH='@baseboard_fab2_lib.baseboard_fab2(sch_1):page236_i117@mstr_discrete.ir~
354xx(chips)',
 P_PATH='@baseboard_fab2_lib.baseboard_fab2(sch_1):page236_i117@mstr_discrete.ir~
354xx(chips)',
 PATH='I117',
 DRAWING='@BASEBOARD_FAB2_LIB.BASEBOARD_FAB2(SCH_1):PAGE236',
 SEC_TYPE='SM',
 MATERIAL='IC',
 NO_XNET_CONNECTION='1',
 PHYS_PAGE='236',
 XY='(9875,2525)',
 ROT='0',
 VER='1',
 VALUE='IR35412',
 PACK_TYPE='SM',
 PART_NUMBER='H73684-001',
 LOCATION='EU7A2',
 SEC='1',
 CDS_LIB='mstr_discrete',
 CDS_PART_NAME='IR354XX_SM-IR35412,IC,H73684-0A',
 PRIM_FILE='./archive_libs/mstr_discrete/ir354xx/chips/chips.prt';

PART_NAME
 EU7A3 'IR354XX_SM-IR35412,IC,H73684-0A':
 NO_XNET_CONNECTION='1';

SECTION_NUMBER 1
 '@BASEBOARD_FAB2_LIB.BASEBOARD_FAB2(SCH_1):PAGE236_I116@MSTR_DISCRETE.IR354XX(CHIPS)':
 C_PATH='@baseboard_fab2_lib.baseboard_fab2(sch_1):page236_i116@mstr_discrete.ir~
354xx(chips)',
 P_PATH='@baseboard_fab2_lib.baseboard_fab2(sch_1):page236_i116@mstr_discrete.ir~
354xx(chips)',
 PATH='I116',
 DRAWING='@BASEBOARD_FAB2_LIB.BASEBOARD_FAB2(SCH_1):PAGE236',
 SEC_TYPE='SM',
 MATERIAL='IC',
 NO_XNET_CONNECTION='1',
 PHYS_PAGE='236',
 XY='(9850,4275)',
 ROT='0',
 VER='1',
 VALUE='IR35412',
 PACK_TYPE='SM',
 PART_NUMBER='H73684-001',
 LOCATION='EU7A3',
 SEC='1',
 CDS_LIB='mstr_discrete',
 CDS_PART_NAME='IR354XX_SM-IR35412,IC,H73684-0A',
 PRIM_FILE='./archive_libs/mstr_discrete/ir354xx/chips/chips.prt';

PART_NAME
 EU7A4 'IR354XX_SM-IR35411,IC,H73688-0A':
 NO_XNET_CONNECTION='1';

SECTION_NUMBER 1
 '@BASEBOARD_FAB2_LIB.BASEBOARD_FAB2(SCH_1):PAGE219_I107@MSTR_DISCRETE.IR354XX(CHIPS)':
 C_PATH='@baseboard_fab2_lib.baseboard_fab2(sch_1):page219_i107@mstr_discrete.ir~
354xx(chips)',
 P_PATH='@baseboard_fab2_lib.baseboard_fab2(sch_1):page219_i107@mstr_discrete.ir~
354xx(chips)',
 PATH='I107',
 DRAWING='@BASEBOARD_FAB2_LIB.BASEBOARD_FAB2(SCH_1):PAGE219',
 BOM_SS='NOPOP',
 SEC_TYPE='SM',
 MATERIAL='IC',
 NO_XNET_CONNECTION='1',
 PHYS_PAGE='219',
 XY='(1775,-125)',
 ROT='0',
 VER='1',
 VALUE='IR35411',
 PACK_TYPE='SM',
 PART_NUMBER='H73688-001',
 LOCATION='EU7A4',
 SEC='1',
 CDS_LIB='mstr_discrete',
 CDS_PART_NAME='IR354XX_SM-IR35411,IC,H73688-0A',
 PRIM_FILE='./archive_libs/mstr_discrete/ir354xx/chips/chips.prt';

PART_NAME
 EU7A5 'PXM1310B_QFN-IC,H89186-001':;

SECTION_NUMBER 1
 '@BASEBOARD_FAB2_LIB.BASEBOARD_FAB2(SCH_1):PAGE218_I69@MSTR_CONTROLLER.PXM1310B(CHIPS)':
 C_PATH='@baseboard_fab2_lib.baseboard_fab2(sch_1):page218_i69@mstr_controller.p~
xm1310b(chips)',
 P_PATH='@baseboard_fab2_lib.baseboard_fab2(sch_1):page218_i69@mstr_controller.p~
xm1310b(chips)',
 PATH='I69',
 DRAWING='@BASEBOARD_FAB2_LIB.BASEBOARD_FAB2(SCH_1):PAGE218',
 SEC_TYPE='QFN',
 MATERIAL='IC',
 PHYS_PAGE='218',
 XY='(150,1500)',
 ROT='0',
 VER='2',
 PACK_TYPE='QFN',
 PART_NUMBER='H89186-001',
 LOCATION='EU7A5',
 SEC='1',
 CDS_LIB='mstr_controller',
 CDS_PART_NAME='PXM1310B_QFN-IC,H89186-001',
 PRIM_FILE='./archive_libs/mstr_controller/pxm1310b/chips/chips.prt';

PART_NAME
 EU7B1 'NCP3232L_SM-IC,H86355-001':;

SECTION_NUMBER 1
 '@BASEBOARD_FAB2_LIB.BASEBOARD_FAB2(SCH_1):PAGE232_I214@MSTR_VREG.NCP3232L(CHIPS)':
 C_PATH='@baseboard_fab2_lib.baseboard_fab2(sch_1):page232_i214@mstr_vreg.ncp323~
2l(chips)',
 P_PATH='@baseboard_fab2_lib.baseboard_fab2(sch_1):page232_i214@mstr_vreg.ncp323~
2l(chips)',
 PATH='I214',
 DRAWING='@BASEBOARD_FAB2_LIB.BASEBOARD_FAB2(SCH_1):PAGE232',
 SEC_TYPE='SM',
 MATERIAL='IC',
 PHYS_PAGE='232',
 XY='(-4150,2875)',
 ROT='0',
 VER='1',
 PACK_TYPE='SM',
 PART_NUMBER='H86355-001',
 LOCATION='EU7B1',
 SEC='1',
 CDS_LIB='mstr_vreg',
 CDS_PART_NAME='NCP3232L_SM-IC,H86355-001',
 PRIM_FILE='./archive_libs/mstr_vreg/ncp3232l/chips/chips.prt';

PART_NAME
 EU7C1 'IR354XX_SM-IR35412,IC,H73684-0A':;

SECTION_NUMBER 1
 '@BASEBOARD_FAB2_LIB.BASEBOARD_FAB2(SCH_1):PAGE212_I101@MSTR_DISCRETE.IR354XX(CHIPS)':
 C_PATH='@baseboard_fab2_lib.baseboard_fab2(sch_1):page212_i101@mstr_discrete.ir~
354xx(chips)',
 P_PATH='@baseboard_fab2_lib.baseboard_fab2(sch_1):page212_i101@mstr_discrete.ir~
354xx(chips)',
 PATH='I101',
 DRAWING='@BASEBOARD_FAB2_LIB.BASEBOARD_FAB2(SCH_1):PAGE212',
 MATERIAL='IC',
 PHYS_PAGE='212',
 XY='(1250,3950)',
 ROT='0',
 VER='1',
 VALUE='IR35412',
 PACK_TYPE='SM',
 PART_NUMBER='H73684-001',
 LOCATION='EU7C1',
 CDS_LIB='mstr_discrete',
 CDS_PART_NAME='IR354XX_SM-IR35412,IC,H73684-0A',
 PRIM_FILE='./archive_libs/mstr_discrete/ir354xx/chips/chips.prt';

PART_NAME
 EU7E1 'SLG55021_SM-IC,G56246-001':
 ROOM='P12V_PWR_SWITCH';

SECTION_NUMBER 1
 '@BASEBOARD_FAB2_LIB.BASEBOARD_FAB2(SCH_1):PAGE198_I19@MSTR_VREG.SLG55021(CHIPS)':
 C_PATH='@baseboard_fab2_lib.baseboard_fab2(sch_1):page198_i19@mstr_vreg.slg5502~
1(chips)',
 P_PATH='@baseboard_fab2_lib.baseboard_fab2(sch_1):page198_i19@mstr_vreg.slg5502~
1(chips)',
 PATH='I19',
 DRAWING='@BASEBOARD_FAB2_LIB.BASEBOARD_FAB2(SCH_1):PAGE198',
 SEC_TYPE='SM',
 MATERIAL='IC',
 PHYS_PAGE='198',
 XY='(-6725,1850)',
 ROT='0',
 VER='1',
 PACK_TYPE='SM',
 PART_NUMBER='G56246-001',
 LOCATION='EU7E1',
 ROOM='P12V_PWR_SWITCH',
 SEC='1',
 CDS_LIB='mstr_vreg',
 CDS_PART_NAME='SLG55021_SM-IC,G56246-001',
 PRIM_FILE='./archive_libs/mstr_vreg/slg55021/chips/chips.prt';

PART_NAME
 EU7E2 'TPS54821_LCC-IC,H63269-001':
 ROOM='P5V_STBY_VR';

SECTION_NUMBER 1
 '@BASEBOARD_FAB2_LIB.BASEBOARD_FAB2(SCH_1):PAGE241_I83@MSTR_VREG.TPS54821(CHIPS)':
 C_PATH='@baseboard_fab2_lib.baseboard_fab2(sch_1):page241_i83@mstr_vreg.tps5482~
1(chips)',
 P_PATH='@baseboard_fab2_lib.baseboard_fab2(sch_1):page241_i83@mstr_vreg.tps5482~
1(chips)',
 PATH='I83',
 DRAWING='@BASEBOARD_FAB2_LIB.BASEBOARD_FAB2(SCH_1):PAGE241',
 SEC_TYPE='LCC',
 MATERIAL='IC',
 BOM_COST='P5V_STBY_VR',
 PHYS_PAGE='241',
 XY='(125,3575)',
 ROT='0',
 VER='1',
 PACK_TYPE='LCC',
 PART_NUMBER='H63269-001',
 LOCATION='EU7E2',
 ROOM='P5V_STBY_VR',
 SEC='1',
 CDS_LIB='mstr_vreg',
 CDS_PART_NAME='TPS54821_LCC-IC,H63269-001',
 PRIM_FILE='./archive_libs/mstr_vreg/tps54821/chips/chips.prt';

PART_NAME
 EU7F1 'NCP3232L_SM-IC,H86355-001':;

SECTION_NUMBER 1
 '@BASEBOARD_FAB2_LIB.BASEBOARD_FAB2(SCH_1):PAGE231_I193@MSTR_VREG.NCP3232L(CHIPS)':
 C_PATH='@baseboard_fab2_lib.baseboard_fab2(sch_1):page231_i193@mstr_vreg.ncp323~
2l(chips)',
 P_PATH='@baseboard_fab2_lib.baseboard_fab2(sch_1):page231_i193@mstr_vreg.ncp323~
2l(chips)',
 PATH='I193',
 DRAWING='@BASEBOARD_FAB2_LIB.BASEBOARD_FAB2(SCH_1):PAGE231',
 SEC_TYPE='SM',
 MATERIAL='IC',
 PHYS_PAGE='231',
 XY='(-3450,3125)',
 ROT='0',
 VER='1',
 PACK_TYPE='SM',
 PART_NUMBER='H86355-001',
 LOCATION='EU7F1',
 SEC='1',
 CDS_LIB='mstr_vreg',
 CDS_PART_NAME='NCP3232L_SM-IC,H86355-001',
 PRIM_FILE='./archive_libs/mstr_vreg/ncp3232l/chips/chips.prt';

PART_NAME
 EU7G1 'PXM1310B_QFN-IC,H89186-001':;

SECTION_NUMBER 1
 '@BASEBOARD_FAB2_LIB.BASEBOARD_FAB2(SCH_1):PAGE215_I69@MSTR_CONTROLLER.PXM1310B(CHIPS)':
 C_PATH='@baseboard_fab2_lib.baseboard_fab2(sch_1):page215_i69@mstr_controller.p~
xm1310b(chips)',
 P_PATH='@baseboard_fab2_lib.baseboard_fab2(sch_1):page215_i69@mstr_controller.p~
xm1310b(chips)',
 PATH='I69',
 DRAWING='@BASEBOARD_FAB2_LIB.BASEBOARD_FAB2(SCH_1):PAGE215',
 MATERIAL='IC',
 PHYS_PAGE='215',
 XY='(2275,1600)',
 ROT='0',
 VER='2',
 PACK_TYPE='QFN',
 PART_NUMBER='H89186-001',
 LOCATION='EU7G1',
 CDS_LIB='mstr_controller',
 CDS_PART_NAME='PXM1310B_QFN-IC,H89186-001',
 PRIM_FILE='./archive_libs/mstr_controller/pxm1310b/chips/chips.prt';

PART_NAME
 EU7G2 'IR354XX_SM-IR35411,IC,H73688-0A':
 NO_XNET_CONNECTION='1';

SECTION_NUMBER 1
 '@BASEBOARD_FAB2_LIB.BASEBOARD_FAB2(SCH_1):PAGE216_I102@MSTR_DISCRETE.IR354XX(CHIPS)':
 C_PATH='@baseboard_fab2_lib.baseboard_fab2(sch_1):page216_i102@mstr_discrete.ir~
354xx(chips)',
 P_PATH='@baseboard_fab2_lib.baseboard_fab2(sch_1):page216_i102@mstr_discrete.ir~
354xx(chips)',
 PATH='I102',
 DRAWING='@BASEBOARD_FAB2_LIB.BASEBOARD_FAB2(SCH_1):PAGE216',
 SEC_TYPE='SM',
 MATERIAL='IC',
 NO_XNET_CONNECTION='1',
 PHYS_PAGE='216',
 XY='(1775,2300)',
 ROT='0',
 VER='1',
 VALUE='IR35411',
 PACK_TYPE='SM',
 PART_NUMBER='H73688-001',
 LOCATION='EU7G2',
 SEC='1',
 CDS_LIB='mstr_discrete',
 CDS_PART_NAME='IR354XX_SM-IR35411,IC,H73688-0A',
 PRIM_FILE='./archive_libs/mstr_discrete/ir354xx/chips/chips.prt';

PART_NAME
 EU7G3 'IR354XX_SM-IR35411,IC,H73688-0A':
 NO_XNET_CONNECTION='1';

SECTION_NUMBER 1
 '@BASEBOARD_FAB2_LIB.BASEBOARD_FAB2(SCH_1):PAGE216_I103@MSTR_DISCRETE.IR354XX(CHIPS)':
 C_PATH='@baseboard_fab2_lib.baseboard_fab2(sch_1):page216_i103@mstr_discrete.ir~
354xx(chips)',
 P_PATH='@baseboard_fab2_lib.baseboard_fab2(sch_1):page216_i103@mstr_discrete.ir~
354xx(chips)',
 PATH='I103',
 DRAWING='@BASEBOARD_FAB2_LIB.BASEBOARD_FAB2(SCH_1):PAGE216',
 BOM_SS='NOPOP',
 SEC_TYPE='SM',
 MATERIAL='IC',
 NO_XNET_CONNECTION='1',
 PHYS_PAGE='216',
 XY='(1775,-75)',
 ROT='0',
 VER='1',
 VALUE='IR35411',
 PACK_TYPE='SM',
 PART_NUMBER='H73688-001',
 LOCATION='EU7G3',
 SEC='1',
 CDS_LIB='mstr_discrete',
 CDS_PART_NAME='IR354XX_SM-IR35411,IC,H73688-0A',
 PRIM_FILE='./archive_libs/mstr_discrete/ir354xx/chips/chips.prt';

PART_NAME
 EU8A1 'PXE1110B_QFN-IC,H89187-001':;

SECTION_NUMBER 1
 '@BASEBOARD_FAB2_LIB.BASEBOARD_FAB2(SCH_1):PAGE235_I229@MSTR_CONTROLLER.PXE1110B(CHIPS)':
 C_PATH='@baseboard_fab2_lib.baseboard_fab2(sch_1):page235_i229@mstr_controller.~
pxe1110b(chips)',
 P_PATH='@baseboard_fab2_lib.baseboard_fab2(sch_1):page235_i229@mstr_controller.~
pxe1110b(chips)',
 PATH='I229',
 DRAWING='@BASEBOARD_FAB2_LIB.BASEBOARD_FAB2(SCH_1):PAGE235',
 SEC_TYPE='QFN',
 MATERIAL='IC',
 PHYS_PAGE='235',
 XY='(-9725,3750)',
 ROT='0',
 VER='1',
 PACK_TYPE='QFN',
 PART_NUMBER='H89187-001',
 LOCATION='EU8A1',
 SEC='1',
 CDS_LIB='mstr_controller',
 CDS_PART_NAME='PXE1110B_QFN-IC,H89187-001',
 PRIM_FILE='./archive_libs/mstr_controller/pxe1110b/chips/chips.prt';

PART_NAME
 EU8A2 'RT9059_DFN-IC,H65765-001':
 ROOM='P1V8_PCH_STBY_VR';

SECTION_NUMBER 1
 '@BASEBOARD_FAB2_LIB.BASEBOARD_FAB2(SCH_1):PAGE237_I86@MSTR_VREG.RT9059(CHIPS)':
 C_PATH='@baseboard_fab2_lib.baseboard_fab2(sch_1):page237_i86@mstr_vreg.rt9059(~
chips)',
 P_PATH='@baseboard_fab2_lib.baseboard_fab2(sch_1):page237_i86@mstr_vreg.rt9059(~
chips)',
 PATH='I86',
 DRAWING='@BASEBOARD_FAB2_LIB.BASEBOARD_FAB2(SCH_1):PAGE237',
 SEC_TYPE='DFN',
 MATERIAL='IC',
 PHYS_PAGE='237',
 XY='(-50,2725)',
 ROT='0',
 VER='1',
 PACK_TYPE='DFN',
 PART_NUMBER='H65765-001',
 LOCATION='EU8A2',
 ROOM='P1V8_PCH_STBY_VR',
 SEC='1',
 CDS_LIB='mstr_vreg',
 CDS_PART_NAME='RT9059_DFN-IC,H65765-001',
 PRIM_FILE='./archive_libs/mstr_vreg/rt9059/chips/chips.prt';

PART_NAME
 EU8B1 'SLG55021_SM-IC,G56246-001':
 ROOM='P5V_PWR_SWITCH';

SECTION_NUMBER 1
 '@BASEBOARD_FAB2_LIB.BASEBOARD_FAB2(SCH_1):PAGE198_I13@MSTR_VREG.SLG55021(CHIPS)':
 C_PATH='@baseboard_fab2_lib.baseboard_fab2(sch_1):page198_i13@mstr_vreg.slg5502~
1(chips)',
 P_PATH='@baseboard_fab2_lib.baseboard_fab2(sch_1):page198_i13@mstr_vreg.slg5502~
1(chips)',
 PATH='I13',
 DRAWING='@BASEBOARD_FAB2_LIB.BASEBOARD_FAB2(SCH_1):PAGE198',
 SEC_TYPE='SM',
 MATERIAL='IC',
 PHYS_PAGE='198',
 XY='(-3300,3800)',
 ROT='0',
 VER='1',
 PACK_TYPE='SM',
 PART_NUMBER='G56246-001',
 LOCATION='EU8B1',
 ROOM='P5V_PWR_SWITCH',
 SEC='1',
 CDS_LIB='mstr_vreg',
 CDS_PART_NAME='SLG55021_SM-IC,G56246-001',
 PRIM_FILE='./archive_libs/mstr_vreg/slg55021/chips/chips.prt';

PART_NAME
 EU8E1 'CSD87384M_SM-IC,H66258-001':
 ROOM='P3V3_STBY_VR';

SECTION_NUMBER 1
 '@BASEBOARD_FAB2_LIB.BASEBOARD_FAB2(SCH_1):PAGE240_I170@MSTR_DISCRETE.CSD87384M(CHIPS)':
 C_PATH='@baseboard_fab2_lib.baseboard_fab2(sch_1):page240_i170@mstr_discrete.cs~
d87384m(chips)',
 P_PATH='@baseboard_fab2_lib.baseboard_fab2(sch_1):page240_i170@mstr_discrete.cs~
d87384m(chips)',
 PATH='I170',
 DRAWING='@BASEBOARD_FAB2_LIB.BASEBOARD_FAB2(SCH_1):PAGE240',
 SEC_TYPE='SM',
 MATERIAL='IC',
 PHYS_PAGE='240',
 XY='(9250,3400)',
 ROT='0',
 VER='1',
 PACK_TYPE='SM',
 PART_NUMBER='H66258-001',
 LOCATION='EU8E1',
 ROOM='P3V3_STBY_VR',
 SEC='1',
 CDS_LIB='mstr_discrete',
 CDS_PART_NAME='CSD87384M_SM-IC,H66258-001',
 PRIM_FILE='./archive_libs/mstr_discrete/csd87384m/chips/chips.prt';

PART_NAME
 EU8F1 'RT8240_QFN-IC,H66262-001':
 ROOM='P3V3_STBY_VR';

SECTION_NUMBER 1
 '@BASEBOARD_FAB2_LIB.BASEBOARD_FAB2(SCH_1):PAGE240_I125@MSTR_VREG.RT8240(CHIPS)':
 C_PATH='@baseboard_fab2_lib.baseboard_fab2(sch_1):page240_i125@mstr_vreg.rt8240~
(chips)',
 P_PATH='@baseboard_fab2_lib.baseboard_fab2(sch_1):page240_i125@mstr_vreg.rt8240~
(chips)',
 PATH='I125',
 DRAWING='@BASEBOARD_FAB2_LIB.BASEBOARD_FAB2(SCH_1):PAGE240',
 SEC_TYPE='QFN',
 MATERIAL='IC',
 PHYS_PAGE='240',
 XY='(7550,2625)',
 ROT='0',
 VER='1',
 PACK_TYPE='QFN',
 PART_NUMBER='H66262-001',
 LOCATION='EU8F1',
 ROOM='P3V3_STBY_VR',
 SEC='1',
 CDS_LIB='mstr_vreg',
 CDS_PART_NAME='RT8240_QFN-IC,H66262-001',
 PRIM_FILE='./archive_libs/mstr_vreg/rt8240/chips/chips.prt';

PART_NAME
 EU8F2 'ICS9FGP204_MLFP-IC,E95226-001':
 ROOM='SYS_CLOCK';

SECTION_NUMBER 1
 '@BASEBOARD_FAB2_LIB.BASEBOARD_FAB2(SCH_1):PAGE101_I34@MSTR_CLOCK.ICS9FGP204(CHIPS)':
 C_PATH='@baseboard_fab2_lib.baseboard_fab2(sch_1):page101_i34@mstr_clock.ics9fg~
p204(chips)',
 P_PATH='@baseboard_fab2_lib.baseboard_fab2(sch_1):page101_i34@mstr_clock.ics9fg~
p204(chips)',
 PATH='I34',
 DRAWING='@BASEBOARD_FAB2_LIB.BASEBOARD_FAB2(SCH_1):PAGE101',
 SEC_TYPE='MLFP',
 MATERIAL='IC',
 BOM_COST='SM_CONTROLLER',
 PHYS_PAGE='101',
 XY='(-5500,1850)',
 ROT='0',
 VER='1',
 PACK_TYPE='MLFP',
 PART_NUMBER='E95226-001',
 LOCATION='EU8F2',
 ROOM='SYS_CLOCK',
 SEC='1',
 CDS_LIB='mstr_clock',
 CDS_PART_NAME='ICS9FGP204_MLFP-IC,E95226-001',
 PRIM_FILE='./archive_libs/mstr_clock/ics9fgp204/chips/chips.prt';

PART_NAME
 EU9E1 'SPRINGVILLE_SM1-IC,G47144-004':
 GROUP='NI_I210&RJ45',
 ROOM='NIC_SPRV';

SECTION_NUMBER 1
 '@BASEBOARD_FAB2_LIB.BASEBOARD_FAB2(SCH_1):PAGE139_I72@MSTR_INTEL.SPRINGVILLE(CHIPS)':
 C_PATH='@baseboard_fab2_lib.baseboard_fab2(sch_1):page139_i72@mstr_intel.spring~
ville(chips)',
 P_PATH='@baseboard_fab2_lib.baseboard_fab2(sch_1):page139_i72@mstr_intel.spring~
ville(chips)',
 PATH='I72',
 DRAWING='@BASEBOARD_FAB2_LIB.BASEBOARD_FAB2(SCH_1):PAGE139',
 SEC_TYPE='SM1',
 MATERIAL='IC',
 BOM_COST='NT_GBE_BASE',
 PHYS_PAGE='139',
 XY='(-4200,3125)',
 ROT='0',
 VER='2',
 PACK_TYPE='SM1',
 PART_NUMBER='G47144-004',
 LOCATION='EU9E1',
 ROOM='NIC_SPRV',
 GROUP='NI_I210&RJ45',
 SEC='1',
 CDS_LIB='mstr_intel',
 CDS_PART_NAME='SPRINGVILLE_SM1-IC,G47144-004',
 PRIM_FILE='./archive_libs/mstr_intel/springville/chips/chips.prt';

PART_NAME
 EU9F1 'RT9059_DFN-IC,H65765-001':
 ROOM='P1V26_BMC_STBY_VR';

SECTION_NUMBER 1
 '@BASEBOARD_FAB2_LIB.BASEBOARD_FAB2(SCH_1):PAGE238_I40@MSTR_VREG.RT9059(CHIPS)':
 C_PATH='@baseboard_fab2_lib.baseboard_fab2(sch_1):page238_i40@mstr_vreg.rt9059(~
chips)',
 P_PATH='@baseboard_fab2_lib.baseboard_fab2(sch_1):page238_i40@mstr_vreg.rt9059(~
chips)',
 PATH='I40',
 DRAWING='@BASEBOARD_FAB2_LIB.BASEBOARD_FAB2(SCH_1):PAGE238',
 SEC_TYPE='DFN',
 MATERIAL='IC',
 PHYS_PAGE='238',
 XY='(-175,2700)',
 ROT='0',
 VER='1',
 PACK_TYPE='DFN',
 PART_NUMBER='H65765-001',
 LOCATION='EU9F1',
 ROOM='P1V26_BMC_STBY_VR',
 SEC='1',
 CDS_LIB='mstr_vreg',
 CDS_PART_NAME='RT9059_DFN-IC,H65765-001',
 PRIM_FILE='./archive_libs/mstr_vreg/rt9059/chips/chips.prt';

PART_NAME
 EU9F2 'RT9059_DFN-IC,H65765-001':;

SECTION_NUMBER 1
 '@BASEBOARD_FAB2_LIB.BASEBOARD_FAB2(SCH_1):PAGE239_I70@MSTR_VREG.RT9059(CHIPS)':
 C_PATH='@baseboard_fab2_lib.baseboard_fab2(sch_1):page239_i70@mstr_vreg.rt9059(~
chips)',
 P_PATH='@baseboard_fab2_lib.baseboard_fab2(sch_1):page239_i70@mstr_vreg.rt9059(~
chips)',
 PATH='I70',
 DRAWING='@BASEBOARD_FAB2_LIB.BASEBOARD_FAB2(SCH_1):PAGE239',
 SEC_TYPE='DFN',
 MATERIAL='IC',
 PHYS_PAGE='239',
 XY='(8850,3775)',
 ROT='0',
 VER='1',
 PACK_TYPE='DFN',
 PART_NUMBER='H65765-001',
 LOCATION='EU9F2',
 SEC='1',
 CDS_LIB='mstr_vreg',
 CDS_PART_NAME='RT9059_DFN-IC,H65765-001',
 PRIM_FILE='./archive_libs/mstr_vreg/rt9059/chips/chips.prt';

PART_NAME
 EU9M1 'SLG55021_SM-IC,G56246-001':
 ROOM='P12V_FAN_PWR_SWITCH';

SECTION_NUMBER 1
 '@BASEBOARD_FAB2_LIB.BASEBOARD_FAB2(SCH_1):PAGE198_I69@MSTR_VREG.SLG55021(CHIPS)':
 C_PATH='@baseboard_fab2_lib.baseboard_fab2(sch_1):page198_i69@mstr_vreg.slg5502~
1(chips)',
 P_PATH='@baseboard_fab2_lib.baseboard_fab2(sch_1):page198_i69@mstr_vreg.slg5502~
1(chips)',
 PATH='I69',
 DRAWING='@BASEBOARD_FAB2_LIB.BASEBOARD_FAB2(SCH_1):PAGE198',
 SEC_TYPE='SM',
 MATERIAL='IC',
 PHYS_PAGE='198',
 XY='(-2775,1825)',
 ROT='0',
 VER='1',
 PACK_TYPE='SM',
 PART_NUMBER='G56246-001',
 LOCATION='EU9M1',
 ROOM='P12V_FAN_PWR_SWITCH',
 SEC='1',
 CDS_LIB='mstr_vreg',
 CDS_PART_NAME='SLG55021_SM-IC,G56246-001',
 PRIM_FILE='./archive_libs/mstr_vreg/slg55021/chips/chips.prt';

PART_NAME
 EU9R1 'MOSFETN_1D3S_SOT5-IC,G68777-001':
 ROOM='HOT_SWAP';

SECTION_NUMBER 1
 '@BASEBOARD_FAB2_LIB.BASEBOARD_FAB2(SCH_1):PAGE200_I57@MSTR_DISCRETE.MOSFETN_1D3S(CHIPS)':
 C_PATH='@baseboard_fab2_lib.baseboard_fab2(sch_1):page200_i57@mstr_discrete.mos~
fetn_1d3s(chips)',
 P_PATH='@baseboard_fab2_lib.baseboard_fab2(sch_1):page200_i57@mstr_discrete.mos~
fetn_1d3s(chips)',
 PATH='I57',
 DRAWING='@BASEBOARD_FAB2_LIB.BASEBOARD_FAB2(SCH_1):PAGE200',
 SEC_TYPE='SOT5',
 MATERIAL='IC',
 PHYS_PAGE='200',
 XY='(2300,2825)',
 ROT='1',
 VER='1',
 PACK_TYPE='SOT5',
 PART_NUMBER='G68777-001',
 LOCATION='EU9R1',
 ROOM='HOT_SWAP',
 SEC='1',
 CDS_LIB='mstr_discrete',
 CDS_PART_NAME='MOSFETN_1D3S_SOT5-IC,G68777-001',
 PRIM_FILE='./archive_libs/mstr_discrete/mosfetn_1d3s/chips/chips.prt';

PART_NAME
 EU25F2 'RT9059_DFN-IC,H65765-001':;

SECTION_NUMBER 1
 '@BASEBOARD_FAB2_LIB.BASEBOARD_FAB2(SCH_1):PAGE239_I73@MSTR_VREG.RT9059(CHIPS)':
 C_PATH='@baseboard_fab2_lib.baseboard_fab2(sch_1):page239_i73@mstr_vreg.rt9059(~
chips)',
 P_PATH='@baseboard_fab2_lib.baseboard_fab2(sch_1):page239_i73@mstr_vreg.rt9059(~
chips)',
 PATH='I73',
 DRAWING='@BASEBOARD_FAB2_LIB.BASEBOARD_FAB2(SCH_1):PAGE239',
 MATERIAL='IC',
 PHYS_PAGE='239',
 XY='(8425,1700)',
 ROT='0',
 VER='1',
 PACK_TYPE='DFN',
 PART_NUMBER='H65765-001',
 LOCATION='EU25F2',
 CDS_LIB='mstr_vreg',
 CDS_PART_NAME='RT9059_DFN-IC,H65765-001',
 PRIM_FILE='./archive_libs/mstr_vreg/rt9059/chips/chips.prt';

PART_NAME
 F1L1 'FUSE_SMT-IC,H45581-001':
 ROOM='BMC_DEBUG_HEADER';

SECTION_NUMBER 1
 '@BASEBOARD_FAB2_LIB.BASEBOARD_FAB2(SCH_1):PAGE155_I129@MSTR_DISCRETE.FUSE(CHIPS)':
 C_PATH='@baseboard_fab2_lib.baseboard_fab2(sch_1):page155_i129@mstr_discrete.fu~
se(chips)',
 P_PATH='@baseboard_fab2_lib.baseboard_fab2(sch_1):page155_i129@mstr_discrete.fu~
se(chips)',
 PATH='I129',
 DRAWING='@BASEBOARD_FAB2_LIB.BASEBOARD_FAB2(SCH_1):PAGE155',
 SIZE='1',
 CONFIG='069.50018.0001',
 SEC_TYPE='SMT',
 MATERIAL='IC',
 BOM_COST='DEBUG',
 PHYS_PAGE='155',
 XY='(-4275,2625)',
 ROT='0',
 VER='1',
 PACK_TYPE='SMT',
 PART_NUMBER='H45581-001',
 LOCATION='F1L1',
 ROOM='BMC_DEBUG_HEADER',
 SEC='1',
 CDS_LIB='mstr_discrete',
 CDS_PART_NAME='FUSE_SMT-IC,H45581-001',
 PRIM_FILE='./archive_libs/mstr_discrete/fuse/chips/chips.prt';

PART_NAME
 F8B1 'FUSE-3A75V-GP_DISCRET-G5-FUSE-A':;

SECTION_NUMBER 1
 '@BASEBOARD_FAB2_LIB.BASEBOARD_FAB2(SCH_1):PAGE172_I71@W_HDL.FUSE-3A75V-GP(CHIPS)':
 C_PATH='@baseboard_fab2_lib.baseboard_fab2(sch_1):page172_i71@w_hdl.\fuse-3a75v~
-gp\(chips)',
 P_PATH='@baseboard_fab2_lib.baseboard_fab2(sch_1):page172_i71@w_hdl.\fuse-3a75v~
-gp\(chips)',
 PATH='I71',
 DRAWING='@BASEBOARD_FAB2_LIB.BASEBOARD_FAB2(SCH_1):PAGE172',
 SEC_TYPE='DISCRET-G5',
 PHYS_PAGE='172',
 XY='(175,650)',
 ROT='0',
 VER='1',
 VALUE='FUSE-3A75V-GP',
 PACK_TYPE='DISCRET-G5',
 PART_NUMBER='69.43001.511',
 LOCATION='F8B1',
 SEC='1',
 CDS_LIB='w_hdl',
 CDS_PART_NAME='FUSE-3A75V-GP_DISCRET-G5-FUSE-A',
 PRIM_FILE='C:/<user>/w_hdl/fuse#2d3a75v#2dgp/chips/chips.prt';

PART_NAME
 F9B1 'FUSE_SM-IC,C94311-016':
 ROOM='ST_SATA';

SECTION_NUMBER 1
 '@BASEBOARD_FAB2_LIB.BASEBOARD_FAB2(SCH_1):PAGE172_I66@MSTR_DISCRETE.FUSE(CHIPS)':
 C_PATH='@baseboard_fab2_lib.baseboard_fab2(sch_1):page172_i66@mstr_discrete.fus~
e(chips)',
 P_PATH='@baseboard_fab2_lib.baseboard_fab2(sch_1):page172_i66@mstr_discrete.fus~
e(chips)',
 PATH='I66',
 DRAWING='@BASEBOARD_FAB2_LIB.BASEBOARD_FAB2(SCH_1):PAGE172',
 SIZE='1',
 SEC_TYPE='SM',
 MATERIAL='IC',
 PHYS_PAGE='172',
 XY='(975,450)',
 ROT='4',
 VER='1',
 PACK_TYPE='SM',
 PART_NUMBER='C94311-016',
 LOCATION='F9B1',
 ROOM='ST_SATA',
 SEC='1',
 CDS_LIB='mstr_discrete',
 CDS_PART_NAME='FUSE_SM-IC,C94311-016',
 PRIM_FILE='./archive_libs/mstr_discrete/fuse/chips/chips.prt';

PART_NAME
 F25W1 'POLYSW-D5A6V-2-GP-U_DISCRET-GAA':
 GROUP='AST2500';

SECTION_NUMBER 1
 '@BASEBOARD_FAB2_LIB.BASEBOARD_FAB2(SCH_1):PAGE255_I89@W_HDL.POLYSW-D5A6V-2-GP-U(CHIPS)':
 C_PATH='@baseboard_fab2_lib.baseboard_fab2(sch_1):page255_i89@w_hdl.\polysw-d5a~
6v-2-gp-u\(chips)',
 P_PATH='@baseboard_fab2_lib.baseboard_fab2(sch_1):page252_i89@w_hdl.\polysw-d5a~
6v-2-gp-u\(chips)',
 PATH='I89',
 DRAWING='@BASEBOARD_FAB2_LIB.BASEBOARD_FAB2(SCH_1):PAGE255',
 CONFIG='069.50007.0071',
 SEC_TYPE='DISCRET-GA1',
 PHYS_PAGE='252',
 XY='(-2775,2850)',
 ROT='0',
 VER='1',
 VALUE='POLYSW-D5A6V-2-GP-U',
 PACK_TYPE='DISCRET-GA1',
 PART_NUMBER='69.50011.051',
 LOCATION='F25W1',
 GROUP='AST2500',
 SEC='1',
 CDS_LIB='w_hdl',
 CDS_PART_NAME='POLYSW-D5A6V-2-GP-U_DISCRET-GAA',
 PRIM_FILE='C:/<user>/w_hdl/polysw#2dd5a6v#2d2#2dgp#2du/chips/chips.prt';

PART_NAME
 F30W1 'POLYSW-1D1A6V-2-GP-U_DISCRET-GA':
 GROUP='NO_KR';

SECTION_NUMBER 1
 '@BASEBOARD_FAB2_LIB.BASEBOARD_FAB2(SCH_1):PAGE253_I44@W_HDL.POLYSW-1D1A6V-2-GP-U(CHIPS)':
 C_PATH='@baseboard_fab2_lib.baseboard_fab2(sch_1):page253_i44@w_hdl.\polysw-1d1~
a6v-2-gp-u\(chips)',
 P_PATH='@baseboard_fab2_lib.baseboard_fab2(sch_1):page253_i44@w_hdl.\polysw-1d1~
a6v-2-gp-u\(chips)',
 PATH='I44',
 DRAWING='@BASEBOARD_FAB2_LIB.BASEBOARD_FAB2(SCH_1):PAGE253',
 SEC_TYPE='DISCRET-G7',
 PHYS_PAGE='253',
 XY='(-5225,4675)',
 ROT='0',
 VER='1',
 VALUE='POLYSW-1D1A6V-2-GP-U',
 PACK_TYPE='DISCRET-G7',
 PART_NUMBER='69.50007.D81',
 LOCATION='F30W1',
 GROUP='NO_KR',
 SEC='1',
 CDS_LIB='w_hdl',
 CDS_PART_NAME='POLYSW-1D1A6V-2-GP-U_DISCRET-GA',
 PRIM_FILE='C:/<user>/w_hdl/polysw#2d1d1a6v#2d2#2dgp#2du/chips/chips.prt';

PART_NAME
 FB1U3 'FERRITE_SMLF-30,FB,693286-021':
 ROOM='BMC_VOLT_MONITOR';

SECTION_NUMBER 1
 '@BASEBOARD_FAB2_LIB.BASEBOARD_FAB2(SCH_1):PAGE169_I57@MSTR_DISCRETE.FERRITE(CHIPS)':
 C_PATH='@baseboard_fab2_lib.baseboard_fab2(sch_1):page169_i57@mstr_discrete.fer~
rite(chips)',
 P_PATH='@baseboard_fab2_lib.baseboard_fab2(sch_1):page169_i57@mstr_discrete.fer~
rite(chips)',
 PATH='I57',
 DRAWING='@BASEBOARD_FAB2_LIB.BASEBOARD_FAB2(SCH_1):PAGE169',
 SEC_TYPE='SMLF',
 MATERIAL='FB',
 BOM_COST='SM_HM',
 PHYS_PAGE='169',
 XY='(-4825,3600)',
 ROT='0',
 VER='4',
 VALUE='30',
 PACK_TYPE='SMLF',
 PART_NUMBER='693286-021',
 LOCATION='FB1U3',
 ROOM='BMC_VOLT_MONITOR',
 SEC='1',
 CDS_LIB='mstr_discrete',
 CDS_PART_NAME='FERRITE_SMLF-30,FB,693286-021',
 PRIM_FILE='./archive_libs/mstr_discrete/ferrite/chips/chips.prt';

PART_NAME
 FB1U4 'FERRITE_SMLF-30,FB,693286-021':
 ROOM='BMC_VOLT_MONITOR';

SECTION_NUMBER 1
 '@BASEBOARD_FAB2_LIB.BASEBOARD_FAB2(SCH_1):PAGE169_I155@MSTR_DISCRETE.FERRITE(CHIPS)':
 C_PATH='@baseboard_fab2_lib.baseboard_fab2(sch_1):page169_i155@mstr_discrete.fe~
rrite(chips)',
 P_PATH='@baseboard_fab2_lib.baseboard_fab2(sch_1):page169_i155@mstr_discrete.fe~
rrite(chips)',
 PATH='I155',
 DRAWING='@BASEBOARD_FAB2_LIB.BASEBOARD_FAB2(SCH_1):PAGE169',
 SEC_TYPE='SMLF',
 MATERIAL='FB',
 BOM_COST='SM_HM',
 PHYS_PAGE='169',
 XY='(800,1850)',
 ROT='0',
 VER='4',
 VALUE='30',
 PACK_TYPE='SMLF',
 PART_NUMBER='693286-021',
 LOCATION='FB1U4',
 ROOM='BMC_VOLT_MONITOR',
 SEC='1',
 CDS_LIB='mstr_discrete',
 CDS_PART_NAME='FERRITE_SMLF-30,FB,693286-021',
 PRIM_FILE='./archive_libs/mstr_discrete/ferrite/chips/chips.prt';

PART_NAME
 FB2M1 'FERRITE_SM-120,FB,693286-027':
 ROOM='SB_FILTER_VM20';

SECTION_NUMBER 1
 '@BASEBOARD_FAB2_LIB.BASEBOARD_FAB2(SCH_1):PAGE127_I46@MSTR_DISCRETE.FERRITE(CHIPS)':
 C_PATH='@baseboard_fab2_lib.baseboard_fab2(sch_1):page127_i46@mstr_discrete.fer~
rite(chips)',
 P_PATH='@baseboard_fab2_lib.baseboard_fab2(sch_1):page127_i46@mstr_discrete.fer~
rite(chips)',
 PATH='I46',
 DRAWING='@BASEBOARD_FAB2_LIB.BASEBOARD_FAB2(SCH_1):PAGE127',
 SEC_TYPE='SM',
 MATERIAL='FB',
 BOM_COST='SB',
 PHYS_PAGE='127',
 XY='(1150,-1175)',
 ROT='0',
 VER='1',
 VALUE='120',
 PACK_TYPE='SM',
 PART_NUMBER='693286-027',
 LOCATION='FB2M1',
 ROOM='SB_FILTER_VM20',
 SEC='1',
 CDS_LIB='mstr_discrete',
 CDS_PART_NAME='FERRITE_SM-120,FB,693286-027',
 PRIM_FILE='./archive_libs/mstr_discrete/ferrite/chips/chips.prt';

PART_NAME
 FB2M2 'FERRITE_SM-120,FB,693286-027':
 ROOM='SB_FILTER_VM26';

SECTION_NUMBER 1
 '@BASEBOARD_FAB2_LIB.BASEBOARD_FAB2(SCH_1):PAGE127_I69@MSTR_DISCRETE.FERRITE(CHIPS)':
 C_PATH='@baseboard_fab2_lib.baseboard_fab2(sch_1):page127_i69@mstr_discrete.fer~
rite(chips)',
 P_PATH='@baseboard_fab2_lib.baseboard_fab2(sch_1):page127_i69@mstr_discrete.fer~
rite(chips)',
 PATH='I69',
 DRAWING='@BASEBOARD_FAB2_LIB.BASEBOARD_FAB2(SCH_1):PAGE127',
 SEC_TYPE='SM',
 MATERIAL='FB',
 BOM_COST='SB',
 PHYS_PAGE='127',
 XY='(-1225,-1200)',
 ROT='0',
 VER='1',
 VALUE='120',
 PACK_TYPE='SM',
 PART_NUMBER='693286-027',
 LOCATION='FB2M2',
 ROOM='SB_FILTER_VM26',
 SEC='1',
 CDS_LIB='mstr_discrete',
 CDS_PART_NAME='FERRITE_SM-120,FB,693286-027',
 PRIM_FILE='./archive_libs/mstr_discrete/ferrite/chips/chips.prt';

PART_NAME
 FB2T1 'HCB1608KF-800T30-GP_DISCRET-G9A':;

SECTION_NUMBER 1
 '@BASEBOARD_FAB2_LIB.BASEBOARD_FAB2(SCH_1):PAGE149_I22@W_HDL.HCB1608KF-800T30-GP(CHIPS)':
 C_PATH='@baseboard_fab2_lib.baseboard_fab2(sch_1):page149_i22@w_hdl.\hcb1608kf-~
800t30-gp\(chips)',
 P_PATH='@baseboard_fab2_lib.baseboard_fab2(sch_1):page149_i22@w_hdl.\hcb1608kf-~
800t30-gp\(chips)',
 PATH='I22',
 DRAWING='@BASEBOARD_FAB2_LIB.BASEBOARD_FAB2(SCH_1):PAGE149',
 PACK_SIZE='DCR=4MOHM',
 RATED='3A',
 ATTRIBUTE='80OHM@100MHZ',
 PHYS_PAGE='149',
 XY='(1500,5500)',
 ROT='1',
 VER='1',
 VALUE='HCB1608KF-800T30-GP',
 PACK_TYPE='DISCRET-G9',
 PART_NUMBER='68.00230.231',
 LOCATION='FB2T1',
 CDS_LIB='w_hdl',
 CDS_PART_NAME='HCB1608KF-800T30-GP_DISCRET-G9A',
 PRIM_FILE='C:/<user>/w_hdl/hcb1608kf#2d800t30#2dgp/chips/chips.prt';

PART_NAME
 FB2T2 'FERRITE_SMLF-600,FB,656554-043':
 ROOM='SYS_CLOCK';

SECTION_NUMBER 1
 '@BASEBOARD_FAB2_LIB.BASEBOARD_FAB2(SCH_1):PAGE101_I114@MSTR_DISCRETE.FERRITE(CHIPS)':
 C_PATH='@baseboard_fab2_lib.baseboard_fab2(sch_1):page101_i114@mstr_discrete.fe~
rrite(chips)',
 P_PATH='@baseboard_fab2_lib.baseboard_fab2(sch_1):page101_i114@mstr_discrete.fe~
rrite(chips)',
 PATH='I114',
 DRAWING='@BASEBOARD_FAB2_LIB.BASEBOARD_FAB2(SCH_1):PAGE101',
 MATERIAL='FB',
 BOM_COST='SM_CONTROLLER',
 PHYS_PAGE='101',
 XY='(-8125,4125)',
 ROT='0',
 VER='1',
 VALUE='600',
 PACK_TYPE='SMLF',
 PART_NUMBER='656554-043',
 LOCATION='FB2T2',
 ROOM='SYS_CLOCK',
 CDS_LIB='mstr_discrete',
 CDS_PART_NAME='FERRITE_SMLF-600,FB,656554-043',
 PRIM_FILE='./archive_libs/mstr_discrete/ferrite/chips/chips.prt';

PART_NAME
 FB2T3 'HCB1608KF-800T30-GP_DISCRET-G9A':;

SECTION_NUMBER 1
 '@BASEBOARD_FAB2_LIB.BASEBOARD_FAB2(SCH_1):PAGE149_I85@W_HDL.HCB1608KF-800T30-GP(CHIPS)':
 C_PATH='@baseboard_fab2_lib.baseboard_fab2(sch_1):page149_i85@w_hdl.\hcb1608kf-~
800t30-gp\(chips)',
 P_PATH='@baseboard_fab2_lib.baseboard_fab2(sch_1):page149_i85@w_hdl.\hcb1608kf-~
800t30-gp\(chips)',
 PATH='I85',
 DRAWING='@BASEBOARD_FAB2_LIB.BASEBOARD_FAB2(SCH_1):PAGE149',
 PACK_SIZE='DCR=4MOHM',
 RATED='3A',
 ATTRIBUTE='80OHM@100MHZ',
 PHYS_PAGE='149',
 XY='(-2075,4400)',
 ROT='1',
 VER='1',
 VALUE='HCB1608KF-800T30-GP',
 PACK_TYPE='DISCRET-G9',
 PART_NUMBER='68.00230.231',
 LOCATION='FB2T3',
 CDS_LIB='w_hdl',
 CDS_PART_NAME='HCB1608KF-800T30-GP_DISCRET-G9A',
 PRIM_FILE='C:/<user>/w_hdl/hcb1608kf#2d800t30#2dgp/chips/chips.prt';

PART_NAME
 FB2T4 'HCB1608KF-800T30-GP_DISCRET-G9A':;

SECTION_NUMBER 1
 '@BASEBOARD_FAB2_LIB.BASEBOARD_FAB2(SCH_1):PAGE149_I86@W_HDL.HCB1608KF-800T30-GP(CHIPS)':
 C_PATH='@baseboard_fab2_lib.baseboard_fab2(sch_1):page149_i86@w_hdl.\hcb1608kf-~
800t30-gp\(chips)',
 P_PATH='@baseboard_fab2_lib.baseboard_fab2(sch_1):page149_i86@w_hdl.\hcb1608kf-~
800t30-gp\(chips)',
 PATH='I86',
 DRAWING='@BASEBOARD_FAB2_LIB.BASEBOARD_FAB2(SCH_1):PAGE149',
 PACK_SIZE='DCR=4MOHM',
 RATED='3A',
 ATTRIBUTE='80OHM@100MHZ',
 PHYS_PAGE='149',
 XY='(-2050,3200)',
 ROT='1',
 VER='1',
 VALUE='HCB1608KF-800T30-GP',
 PACK_TYPE='DISCRET-G9',
 PART_NUMBER='68.00230.231',
 LOCATION='FB2T4',
 CDS_LIB='w_hdl',
 CDS_PART_NAME='HCB1608KF-800T30-GP_DISCRET-G9A',
 PRIM_FILE='C:/<user>/w_hdl/hcb1608kf#2d800t30#2dgp/chips/chips.prt';

PART_NAME
 FB2T5 'HCB1608KF-800T30-GP_DISCRET-G9A':;

SECTION_NUMBER 1
 '@BASEBOARD_FAB2_LIB.BASEBOARD_FAB2(SCH_1):PAGE149_I88@W_HDL.HCB1608KF-800T30-GP(CHIPS)':
 C_PATH='@baseboard_fab2_lib.baseboard_fab2(sch_1):page149_i88@w_hdl.\hcb1608kf-~
800t30-gp\(chips)',
 P_PATH='@baseboard_fab2_lib.baseboard_fab2(sch_1):page149_i88@w_hdl.\hcb1608kf-~
800t30-gp\(chips)',
 PATH='I88',
 DRAWING='@BASEBOARD_FAB2_LIB.BASEBOARD_FAB2(SCH_1):PAGE149',
 PACK_SIZE='DCR=4MOHM',
 RATED='3A',
 ATTRIBUTE='80OHM@100MHZ',
 PHYS_PAGE='149',
 XY='(-2025,2150)',
 ROT='1',
 VER='1',
 VALUE='HCB1608KF-800T30-GP',
 PACK_TYPE='DISCRET-G9',
 PART_NUMBER='68.00230.231',
 LOCATION='FB2T5',
 CDS_LIB='w_hdl',
 CDS_PART_NAME='HCB1608KF-800T30-GP_DISCRET-G9A',
 PRIM_FILE='C:/<user>/w_hdl/hcb1608kf#2d800t30#2dgp/chips/chips.prt';

PART_NAME
 FB2T7 'HCB1608KF-800T30-GP_DISCRET-G9A':;

SECTION_NUMBER 1
 '@BASEBOARD_FAB2_LIB.BASEBOARD_FAB2(SCH_1):PAGE149_I42@W_HDL.HCB1608KF-800T30-GP(CHIPS)':
 C_PATH='@baseboard_fab2_lib.baseboard_fab2(sch_1):page149_i42@w_hdl.\hcb1608kf-~
800t30-gp\(chips)',
 P_PATH='@baseboard_fab2_lib.baseboard_fab2(sch_1):page149_i42@w_hdl.\hcb1608kf-~
800t30-gp\(chips)',
 PATH='I42',
 DRAWING='@BASEBOARD_FAB2_LIB.BASEBOARD_FAB2(SCH_1):PAGE149',
 PACK_SIZE='DCR=4MOHM',
 RATED='3A',
 ATTRIBUTE='80OHM@100MHZ',
 PHYS_PAGE='149',
 XY='(2325,4300)',
 ROT='1',
 VER='1',
 VALUE='HCB1608KF-800T30-GP',
 PACK_TYPE='DISCRET-G9',
 PART_NUMBER='68.00230.231',
 LOCATION='FB2T7',
 CDS_LIB='w_hdl',
 CDS_PART_NAME='HCB1608KF-800T30-GP_DISCRET-G9A',
 PRIM_FILE='C:/<user>/w_hdl/hcb1608kf#2d800t30#2dgp/chips/chips.prt';

PART_NAME
 FB3M1 'FERRITE_SM-120,FB,693286-027':
 ROOM='SB_FILTER_PLL0';

SECTION_NUMBER 1
 '@BASEBOARD_FAB2_LIB.BASEBOARD_FAB2(SCH_1):PAGE127_I8@MSTR_DISCRETE.FERRITE(CHIPS)':
 C_PATH='@baseboard_fab2_lib.baseboard_fab2(sch_1):page127_i8@mstr_discrete.ferr~
ite(chips)',
 P_PATH='@baseboard_fab2_lib.baseboard_fab2(sch_1):page127_i8@mstr_discrete.ferr~
ite(chips)',
 PATH='I8',
 DRAWING='@BASEBOARD_FAB2_LIB.BASEBOARD_FAB2(SCH_1):PAGE127',
 SEC_TYPE='SM',
 MATERIAL='FB',
 BOM_COST='SB',
 PHYS_PAGE='127',
 XY='(-4050,-850)',
 ROT='0',
 VER='1',
 VALUE='120',
 PACK_TYPE='SM',
 PART_NUMBER='693286-027',
 LOCATION='FB3M1',
 ROOM='SB_FILTER_PLL0',
 SEC='1',
 CDS_LIB='mstr_discrete',
 CDS_PART_NAME='FERRITE_SM-120,FB,693286-027',
 PRIM_FILE='./archive_libs/mstr_discrete/ferrite/chips/chips.prt';

PART_NAME
 FB3M2 'FERRITE_SM-120,FB,693286-027':
 ROOM='SB_FILTER_PLL1';

SECTION_NUMBER 1
 '@BASEBOARD_FAB2_LIB.BASEBOARD_FAB2(SCH_1):PAGE127_I17@MSTR_DISCRETE.FERRITE(CHIPS)':
 C_PATH='@baseboard_fab2_lib.baseboard_fab2(sch_1):page127_i17@mstr_discrete.fer~
rite(chips)',
 P_PATH='@baseboard_fab2_lib.baseboard_fab2(sch_1):page127_i17@mstr_discrete.fer~
rite(chips)',
 PATH='I17',
 DRAWING='@BASEBOARD_FAB2_LIB.BASEBOARD_FAB2(SCH_1):PAGE127',
 SEC_TYPE='SM',
 MATERIAL='FB',
 BOM_COST='SB',
 PHYS_PAGE='127',
 XY='(-4025,-2050)',
 ROT='0',
 VER='1',
 VALUE='120',
 PACK_TYPE='SM',
 PART_NUMBER='693286-027',
 LOCATION='FB3M2',
 ROOM='SB_FILTER_PLL1',
 SEC='1',
 CDS_LIB='mstr_discrete',
 CDS_PART_NAME='FERRITE_SM-120,FB,693286-027',
 PRIM_FILE='./archive_libs/mstr_discrete/ferrite/chips/chips.prt';

PART_NAME
 FB3M3 'FERRITE_SM-120,FB,693286-027':
 ROOM='SB_FILTER_XTAL';

SECTION_NUMBER 1
 '@BASEBOARD_FAB2_LIB.BASEBOARD_FAB2(SCH_1):PAGE127_I26@MSTR_DISCRETE.FERRITE(CHIPS)':
 C_PATH='@baseboard_fab2_lib.baseboard_fab2(sch_1):page127_i26@mstr_discrete.fer~
rite(chips)',
 P_PATH='@baseboard_fab2_lib.baseboard_fab2(sch_1):page127_i26@mstr_discrete.fer~
rite(chips)',
 PATH='I26',
 DRAWING='@BASEBOARD_FAB2_LIB.BASEBOARD_FAB2(SCH_1):PAGE127',
 SEC_TYPE='SM',
 MATERIAL='FB',
 BOM_COST='SB',
 PHYS_PAGE='127',
 XY='(-4000,-3350)',
 ROT='0',
 VER='1',
 VALUE='120',
 PACK_TYPE='SM',
 PART_NUMBER='693286-027',
 LOCATION='FB3M3',
 ROOM='SB_FILTER_XTAL',
 SEC='1',
 CDS_LIB='mstr_discrete',
 CDS_PART_NAME='FERRITE_SM-120,FB,693286-027',
 PRIM_FILE='./archive_libs/mstr_discrete/ferrite/chips/chips.prt';

PART_NAME
 FB3M4 'FERRITE_SM-120,FB,693286-027':
 ROOM='SB_FILTER_ISCLK';

SECTION_NUMBER 1
 '@BASEBOARD_FAB2_LIB.BASEBOARD_FAB2(SCH_1):PAGE127_I56@MSTR_DISCRETE.FERRITE(CHIPS)':
 C_PATH='@baseboard_fab2_lib.baseboard_fab2(sch_1):page127_i56@mstr_discrete.fer~
rite(chips)',
 P_PATH='@baseboard_fab2_lib.baseboard_fab2(sch_1):page127_i56@mstr_discrete.fer~
rite(chips)',
 PATH='I56',
 DRAWING='@BASEBOARD_FAB2_LIB.BASEBOARD_FAB2(SCH_1):PAGE127',
 SEC_TYPE='SM',
 MATERIAL='FB',
 BOM_COST='SB',
 PHYS_PAGE='127',
 XY='(1150,-3075)',
 ROT='0',
 VER='1',
 VALUE='120',
 PACK_TYPE='SM',
 PART_NUMBER='693286-027',
 LOCATION='FB3M4',
 ROOM='SB_FILTER_ISCLK',
 SEC='1',
 CDS_LIB='mstr_discrete',
 CDS_PART_NAME='FERRITE_SM-120,FB,693286-027',
 PRIM_FILE='./archive_libs/mstr_discrete/ferrite/chips/chips.prt';

PART_NAME
 FB4A1 'FERRITE_SM-22,FB,656554-051':
 ROOM='PVPP_KLM_VR';

SECTION_NUMBER 1
 '@BASEBOARD_FAB2_LIB.BASEBOARD_FAB2(SCH_1):PAGE234_I154@MSTR_DISCRETE.FERRITE(CHIPS)':
 C_PATH='@baseboard_fab2_lib.baseboard_fab2(sch_1):page234_i154@mstr_discrete.fe~
rrite(chips)',
 P_PATH='@baseboard_fab2_lib.baseboard_fab2(sch_1):page234_i154@mstr_discrete.fe~
rrite(chips)',
 PATH='I154',
 DRAWING='@BASEBOARD_FAB2_LIB.BASEBOARD_FAB2(SCH_1):PAGE234',
 TOLERANCE='1%',
 SEC_TYPE='SM',
 MATERIAL='FB',
 PHYS_PAGE='234',
 XY='(-7650,4300)',
 ROT='0',
 VER='1',
 VALUE='22',
 PACK_TYPE='SM',
 PART_NUMBER='656554-051',
 LOCATION='FB4A1',
 ROOM='PVPP_KLM_VR',
 SEC='1',
 CDS_LIB='mstr_discrete',
 CDS_PART_NAME='FERRITE_SM-22,FB,656554-051',
 PRIM_FILE='./archive_libs/mstr_discrete/ferrite/chips/chips.prt';

PART_NAME
 FB4G1 'FERRITE_SM-22,FB,656554-051':
 ROOM='PVPP_KLM_VR';

SECTION_NUMBER 1
 '@BASEBOARD_FAB2_LIB.BASEBOARD_FAB2(SCH_1):PAGE233_I198@MSTR_DISCRETE.FERRITE(CHIPS)':
 C_PATH='@baseboard_fab2_lib.baseboard_fab2(sch_1):page233_i198@mstr_discrete.fe~
rrite(chips)',
 P_PATH='@baseboard_fab2_lib.baseboard_fab2(sch_1):page233_i198@mstr_discrete.fe~
rrite(chips)',
 PATH='I198',
 DRAWING='@BASEBOARD_FAB2_LIB.BASEBOARD_FAB2(SCH_1):PAGE233',
 TOLERANCE='1%',
 SEC_TYPE='SM',
 MATERIAL='FB',
 PHYS_PAGE='233',
 XY='(-7600,4150)',
 ROT='0',
 VER='1',
 VALUE='22',
 PACK_TYPE='SM',
 PART_NUMBER='656554-051',
 LOCATION='FB4G1',
 ROOM='PVPP_KLM_VR',
 SEC='1',
 CDS_LIB='mstr_discrete',
 CDS_PART_NAME='FERRITE_SM-22,FB,656554-051',
 PRIM_FILE='./archive_libs/mstr_discrete/ferrite/chips/chips.prt';

PART_NAME
 FB6P1 'FERRITE_SMLF-600,FB,656554-043':
 ROOM='DB1200ZL';

SECTION_NUMBER 1
 '@BASEBOARD_FAB2_LIB.BASEBOARD_FAB2(SCH_1):PAGE102_I8@MSTR_DISCRETE.FERRITE(CHIPS)':
 C_PATH='@baseboard_fab2_lib.baseboard_fab2(sch_1):page102_i8@mstr_discrete.ferr~
ite(chips)',
 P_PATH='@baseboard_fab2_lib.baseboard_fab2(sch_1):page102_i8@mstr_discrete.ferr~
ite(chips)',
 PATH='I8',
 DRAWING='@BASEBOARD_FAB2_LIB.BASEBOARD_FAB2(SCH_1):PAGE102',
 SEC_TYPE='SMLF',
 MATERIAL='FB',
 BOM_COST='SYS_CLOCK',
 PHYS_PAGE='102',
 XY='(1700,1125)',
 ROT='0',
 VER='1',
 VALUE='600',
 PACK_TYPE='SMLF',
 PART_NUMBER='656554-043',
 LOCATION='FB6P1',
 ROOM='DB1200ZL',
 SEC='1',
 CDS_LIB='mstr_discrete',
 CDS_PART_NAME='FERRITE_SMLF-600,FB,656554-043',
 PRIM_FILE='./archive_libs/mstr_discrete/ferrite/chips/chips.prt';

PART_NAME
 FB7B1 'FERRITE_SM-22,FB,656554-051':
 ROOM='PVPP_KLM_VR';

SECTION_NUMBER 1
 '@BASEBOARD_FAB2_LIB.BASEBOARD_FAB2(SCH_1):PAGE232_I200@MSTR_DISCRETE.FERRITE(CHIPS)':
 C_PATH='@baseboard_fab2_lib.baseboard_fab2(sch_1):page232_i200@mstr_discrete.fe~
rrite(chips)',
 P_PATH='@baseboard_fab2_lib.baseboard_fab2(sch_1):page232_i200@mstr_discrete.fe~
rrite(chips)',
 PATH='I200',
 DRAWING='@BASEBOARD_FAB2_LIB.BASEBOARD_FAB2(SCH_1):PAGE232',
 TOLERANCE='1%',
 SEC_TYPE='SM',
 MATERIAL='FB',
 PHYS_PAGE='232',
 XY='(-7950,4300)',
 ROT='0',
 VER='1',
 VALUE='22',
 PACK_TYPE='SM',
 PART_NUMBER='656554-051',
 LOCATION='FB7B1',
 ROOM='PVPP_KLM_VR',
 SEC='1',
 CDS_LIB='mstr_discrete',
 CDS_PART_NAME='FERRITE_SM-22,FB,656554-051',
 PRIM_FILE='./archive_libs/mstr_discrete/ferrite/chips/chips.prt';

PART_NAME
 FB7E1 'FERRITE_SM-22,FB,656554-051':
 ROOM='P5V_STBY_VR';

SECTION_NUMBER 1
 '@BASEBOARD_FAB2_LIB.BASEBOARD_FAB2(SCH_1):PAGE241_I82@MSTR_DISCRETE.FERRITE(CHIPS)':
 C_PATH='@baseboard_fab2_lib.baseboard_fab2(sch_1):page241_i82@mstr_discrete.fer~
rite(chips)',
 P_PATH='@baseboard_fab2_lib.baseboard_fab2(sch_1):page241_i82@mstr_discrete.fer~
rite(chips)',
 PATH='I82',
 DRAWING='@BASEBOARD_FAB2_LIB.BASEBOARD_FAB2(SCH_1):PAGE241',
 SEC_TYPE='SM',
 MATERIAL='FB',
 BOM_COST='P5V_STBY_VR',
 PHYS_PAGE='241',
 XY='(-3300,4675)',
 ROT='0',
 VER='1',
 VALUE='22',
 PACK_TYPE='SM',
 PART_NUMBER='656554-051',
 LOCATION='FB7E1',
 ROOM='P5V_STBY_VR',
 SEC='1',
 CDS_LIB='mstr_discrete',
 CDS_PART_NAME='FERRITE_SM-22,FB,656554-051',
 PRIM_FILE='./archive_libs/mstr_discrete/ferrite/chips/chips.prt';

PART_NAME
 FB7F1 'FERRITE_SM-22,FB,656554-051':
 ROOM='PVPP_KLM_VR';

SECTION_NUMBER 1
 '@BASEBOARD_FAB2_LIB.BASEBOARD_FAB2(SCH_1):PAGE231_I162@MSTR_DISCRETE.FERRITE(CHIPS)':
 C_PATH='@baseboard_fab2_lib.baseboard_fab2(sch_1):page231_i162@mstr_discrete.fe~
rrite(chips)',
 P_PATH='@baseboard_fab2_lib.baseboard_fab2(sch_1):page231_i162@mstr_discrete.fe~
rrite(chips)',
 PATH='I162',
 DRAWING='@BASEBOARD_FAB2_LIB.BASEBOARD_FAB2(SCH_1):PAGE231',
 TOLERANCE='1%',
 SEC_TYPE='SM',
 MATERIAL='FB',
 PHYS_PAGE='231',
 XY='(-7300,4550)',
 ROT='0',
 VER='1',
 VALUE='22',
 PACK_TYPE='SM',
 PART_NUMBER='656554-051',
 LOCATION='FB7F1',
 ROOM='PVPP_KLM_VR',
 SEC='1',
 CDS_LIB='mstr_discrete',
 CDS_PART_NAME='FERRITE_SM-22,FB,656554-051',
 PRIM_FILE='./archive_libs/mstr_discrete/ferrite/chips/chips.prt';

PART_NAME
 FB9E1 'BLM31SN500SN1L-GP_DISCRET-GB1-A':;

SECTION_NUMBER 1
 '@BASEBOARD_FAB2_LIB.BASEBOARD_FAB2(SCH_1):PAGE240_I193@W_HDL.BLM31SN500SN1L-GP(CHIPS)':
 C_PATH='@baseboard_fab2_lib.baseboard_fab2(sch_1):page240_i193@w_hdl.\blm31sn50~
0sn1l-gp\(chips)',
 P_PATH='@baseboard_fab2_lib.baseboard_fab2(sch_1):page240_i193@w_hdl.\blm31sn50~
0sn1l-gp\(chips)',
 PATH='I193',
 DRAWING='@BASEBOARD_FAB2_LIB.BASEBOARD_FAB2(SCH_1):PAGE240',
 PACK_SIZE='DCR=1.6MOHM',
 RATED='1MA',
 ATTRIBUTE='50OHM@100MHZ',
 SEC_TYPE='DISCRET-GB1',
 PHYS_PAGE='240',
 XY='(6100,4500)',
 ROT='1',
 VER='1',
 VALUE='BLM31SN500SN1L-GP',
 PACK_TYPE='DISCRET-GB1',
 PART_NUMBER='068.00007.0011',
 LOCATION='FB9E1',
 SEC='1',
 CDS_LIB='w_hdl',
 CDS_PART_NAME='BLM31SN500SN1L-GP_DISCRET-GB1-A',
 PRIM_FILE='C:/<user>/w_hdl/blm31sn500sn1l#2dgp/chips/chips.prt';

PART_NAME
 FB25W1 'BLM15AG121SN-1GP_DISCRET-G-BLMA':;

SECTION_NUMBER 1
 '@BASEBOARD_FAB2_LIB.BASEBOARD_FAB2(SCH_1):PAGE269_I71@W_HDL.BLM15AG121SN-1GP(CHIPS)':
 C_PATH='@baseboard_fab2_lib.baseboard_fab2(sch_1):page269_i71@w_hdl.\blm15ag121~
sn-1gp\(chips)',
 P_PATH='@baseboard_fab2_lib.baseboard_fab2(sch_1):page254_i71@w_hdl.\blm15ag121~
sn-1gp\(chips)',
 PATH='I71',
 DRAWING='@BASEBOARD_FAB2_LIB.BASEBOARD_FAB2(SCH_1):PAGE269',
 SEC_TYPE='DISCRET-G',
 PHYS_PAGE='254',
 XY='(-2800,3700)',
 ROT='1',
 VER='1',
 VALUE='BLM15AG121SN-1GP',
 PACK_TYPE='DISCRET-G',
 PART_NUMBER='68.00084.921',
 LOCATION='FB25W1',
 SEC='1',
 CDS_LIB='w_hdl',
 CDS_PART_NAME='BLM15AG121SN-1GP_DISCRET-G-BLMA',
 PRIM_FILE='C:/<user>/w_hdl/blm15ag121sn#2d1gp/chips/chips.prt';

PART_NAME
 FB25W2 'BLM15AG121SN-1GP_DISCRET-G-BLMA':;

SECTION_NUMBER 1
 '@BASEBOARD_FAB2_LIB.BASEBOARD_FAB2(SCH_1):PAGE269_I72@W_HDL.BLM15AG121SN-1GP(CHIPS)':
 C_PATH='@baseboard_fab2_lib.baseboard_fab2(sch_1):page269_i72@w_hdl.\blm15ag121~
sn-1gp\(chips)',
 P_PATH='@baseboard_fab2_lib.baseboard_fab2(sch_1):page254_i72@w_hdl.\blm15ag121~
sn-1gp\(chips)',
 PATH='I72',
 DRAWING='@BASEBOARD_FAB2_LIB.BASEBOARD_FAB2(SCH_1):PAGE269',
 SEC_TYPE='DISCRET-G',
 PHYS_PAGE='254',
 XY='(-2800,3900)',
 ROT='1',
 VER='1',
 VALUE='BLM15AG121SN-1GP',
 PACK_TYPE='DISCRET-G',
 PART_NUMBER='68.00084.921',
 LOCATION='FB25W2',
 SEC='1',
 CDS_LIB='w_hdl',
 CDS_PART_NAME='BLM15AG121SN-1GP_DISCRET-G-BLMA',
 PRIM_FILE='C:/<user>/w_hdl/blm15ag121sn#2d1gp/chips/chips.prt';

PART_NAME
 FB25W3 'BLM15AG121SN-1GP_DISCRET-G-BLMA':;

SECTION_NUMBER 1
 '@BASEBOARD_FAB2_LIB.BASEBOARD_FAB2(SCH_1):PAGE269_I73@W_HDL.BLM15AG121SN-1GP(CHIPS)':
 C_PATH='@baseboard_fab2_lib.baseboard_fab2(sch_1):page269_i73@w_hdl.\blm15ag121~
sn-1gp\(chips)',
 P_PATH='@baseboard_fab2_lib.baseboard_fab2(sch_1):page254_i73@w_hdl.\blm15ag121~
sn-1gp\(chips)',
 PATH='I73',
 DRAWING='@BASEBOARD_FAB2_LIB.BASEBOARD_FAB2(SCH_1):PAGE269',
 SEC_TYPE='DISCRET-G',
 PHYS_PAGE='254',
 XY='(-2800,4100)',
 ROT='1',
 VER='1',
 VALUE='BLM15AG121SN-1GP',
 PACK_TYPE='DISCRET-G',
 PART_NUMBER='68.00084.921',
 LOCATION='FB25W3',
 SEC='1',
 CDS_LIB='w_hdl',
 CDS_PART_NAME='BLM15AG121SN-1GP_DISCRET-G-BLMA',
 PRIM_FILE='C:/<user>/w_hdl/blm15ag121sn#2d1gp/chips/chips.prt';

PART_NAME
 FB25W4 'BLM15AG121SN-1GP_DISCRET-G-BLMA':;

SECTION_NUMBER 1
 '@BASEBOARD_FAB2_LIB.BASEBOARD_FAB2(SCH_1):PAGE269_I75@W_HDL.BLM15AG121SN-1GP(CHIPS)':
 C_PATH='@baseboard_fab2_lib.baseboard_fab2(sch_1):page269_i75@w_hdl.\blm15ag121~
sn-1gp\(chips)',
 P_PATH='@baseboard_fab2_lib.baseboard_fab2(sch_1):page254_i75@w_hdl.\blm15ag121~
sn-1gp\(chips)',
 PATH='I75',
 DRAWING='@BASEBOARD_FAB2_LIB.BASEBOARD_FAB2(SCH_1):PAGE269',
 SEC_TYPE='DISCRET-G',
 PHYS_PAGE='254',
 XY='(-3850,5450)',
 ROT='1',
 VER='1',
 VALUE='BLM15AG121SN-1GP',
 PACK_TYPE='DISCRET-G',
 PART_NUMBER='68.00084.921',
 LOCATION='FB25W4',
 SEC='1',
 CDS_LIB='w_hdl',
 CDS_PART_NAME='BLM15AG121SN-1GP_DISCRET-G-BLMA',
 PRIM_FILE='C:/<user>/w_hdl/blm15ag121sn#2d1gp/chips/chips.prt';

PART_NAME
 FB25W5 'BLM15AG121SN-1GP_DISCRET-G-BLMA':;

SECTION_NUMBER 1
 '@BASEBOARD_FAB2_LIB.BASEBOARD_FAB2(SCH_1):PAGE269_I74@W_HDL.BLM15AG121SN-1GP(CHIPS)':
 C_PATH='@baseboard_fab2_lib.baseboard_fab2(sch_1):page269_i74@w_hdl.\blm15ag121~
sn-1gp\(chips)',
 P_PATH='@baseboard_fab2_lib.baseboard_fab2(sch_1):page254_i74@w_hdl.\blm15ag121~
sn-1gp\(chips)',
 PATH='I74',
 DRAWING='@BASEBOARD_FAB2_LIB.BASEBOARD_FAB2(SCH_1):PAGE269',
 SEC_TYPE='DISCRET-G',
 PHYS_PAGE='254',
 XY='(-3550,5500)',
 ROT='1',
 VER='1',
 VALUE='BLM15AG121SN-1GP',
 PACK_TYPE='DISCRET-G',
 PART_NUMBER='68.00084.921',
 LOCATION='FB25W5',
 SEC='1',
 CDS_LIB='w_hdl',
 CDS_PART_NAME='BLM15AG121SN-1GP_DISCRET-G-BLMA',
 PRIM_FILE='C:/<user>/w_hdl/blm15ag121sn#2d1gp/chips/chips.prt';

PART_NAME
 J1A1 'SCONN288_H44441004_PIP-SCONN,HA':
 ROOM='DDR4_CH_M';

SECTION_NUMBER 1
 '@BASEBOARD_FAB2_LIB.BASEBOARD_FAB2(SCH_1):PAGE87_I186@MSTR_SCONN.SCONN288_H44441004(CHIPS)':
 C_PATH='@baseboard_fab2_lib.baseboard_fab2(sch_1):page87_i186@mstr_sconn.sconn2~
88_h44441004(chips)',
 P_PATH='@baseboard_fab2_lib.baseboard_fab2(sch_1):page87_i186@mstr_sconn.sconn2~
88_h44441004(chips)',
 PATH='I186',
 DRAWING='@BASEBOARD_FAB2_LIB.BASEBOARD_FAB2(SCH_1):PAGE87',
 SEC_TYPE='PIP',
 MATERIAL='SCONN',
 BOM_COST='MEM',
 PHYS_PAGE='87',
 XY='(-2500,3250)',
 ROT='0',
 VER='1',
 PACK_TYPE='PIP',
 PART_NUMBER='H44441-004',
 LOCATION='J1A1',
 ROOM='DDR4_CH_M',
 SEC='1',
 CDS_LIB='mstr_sconn',
 CDS_PART_NAME='SCONN288_H44441004_PIP-SCONN,HA',
 PRIM_FILE='./archive_libs/mstr_sconn/sconn288_h44441004/chips/chips.prt';

SECTION_NUMBER 2
 '@BASEBOARD_FAB2_LIB.BASEBOARD_FAB2(SCH_1):PAGE87_I187@MSTR_SCONN.SCONN288_H44441004(CHIPS)':
 C_PATH='@baseboard_fab2_lib.baseboard_fab2(sch_1):page87_i187@mstr_sconn.sconn2~
88_h44441004(chips)',
 P_PATH='@baseboard_fab2_lib.baseboard_fab2(sch_1):page87_i187@mstr_sconn.sconn2~
88_h44441004(chips)',
 PATH='I187',
 DRAWING='@BASEBOARD_FAB2_LIB.BASEBOARD_FAB2(SCH_1):PAGE87',
 SEC_TYPE='PIP',
 MATERIAL='SCONN',
 BOM_COST='MEM',
 PHYS_PAGE='87',
 XY='(0,4300)',
 ROT='0',
 VER='2',
 PACK_TYPE='PIP',
 PART_NUMBER='H44441-004',
 LOCATION='J1A1',
 ROOM='DDR4_CH_M',
 SEC='2',
 CDS_LIB='mstr_sconn',
 CDS_PART_NAME='SCONN288_H44441004_PIP-SCONN,HA',
 PRIM_FILE='./archive_libs/mstr_sconn/sconn288_h44441004/chips/chips.prt';

SECTION_NUMBER 3
 '@BASEBOARD_FAB2_LIB.BASEBOARD_FAB2(SCH_1):PAGE87_I185@MSTR_SCONN.SCONN288_H44441004(CHIPS)':
 C_PATH='@baseboard_fab2_lib.baseboard_fab2(sch_1):page87_i185@mstr_sconn.sconn2~
88_h44441004(chips)',
 P_PATH='@baseboard_fab2_lib.baseboard_fab2(sch_1):page87_i185@mstr_sconn.sconn2~
88_h44441004(chips)',
 PATH='I185',
 DRAWING='@BASEBOARD_FAB2_LIB.BASEBOARD_FAB2(SCH_1):PAGE87',
 SEC_TYPE='PIP',
 MATERIAL='SCONN',
 BOM_COST='MEM',
 PHYS_PAGE='87',
 XY='(1800,2450)',
 ROT='0',
 VER='3',
 PACK_TYPE='PIP',
 PART_NUMBER='H44441-004',
 LOCATION='J1A1',
 ROOM='DDR4_CH_M',
 SEC='3',
 CDS_LIB='mstr_sconn',
 CDS_PART_NAME='SCONN288_H44441004_PIP-SCONN,HA',
 PRIM_FILE='./archive_libs/mstr_sconn/sconn288_h44441004/chips/chips.prt';

SECTION_NUMBER 4
 '@BASEBOARD_FAB2_LIB.BASEBOARD_FAB2(SCH_1):PAGE87_I169@MSTR_SCONN.SCONN288_H44441004(CHIPS)':
 C_PATH='@baseboard_fab2_lib.baseboard_fab2(sch_1):page87_i169@mstr_sconn.sconn2~
88_h44441004(chips)',
 P_PATH='@baseboard_fab2_lib.baseboard_fab2(sch_1):page87_i169@mstr_sconn.sconn2~
88_h44441004(chips)',
 PATH='I169',
 DRAWING='@BASEBOARD_FAB2_LIB.BASEBOARD_FAB2(SCH_1):PAGE87',
 SEC_TYPE='PIP',
 MATERIAL='SCONN',
 BOM_COST='MEM',
 PHYS_PAGE='87',
 XY='(-400,2050)',
 ROT='0',
 VER='4',
 PACK_TYPE='PIP',
 PART_NUMBER='H44441-004',
 LOCATION='J1A1',
 ROOM='DDR4_CH_M',
 SEC='4',
 CDS_LIB='mstr_sconn',
 CDS_PART_NAME='SCONN288_H44441004_PIP-SCONN,HA',
 PRIM_FILE='./archive_libs/mstr_sconn/sconn288_h44441004/chips/chips.prt';

PART_NAME
 J1A2 'SCONN288_H44441004_PIP-SCONN,HA':
 ROOM='DDR4_CH_L';

SECTION_NUMBER 1
 '@BASEBOARD_FAB2_LIB.BASEBOARD_FAB2(SCH_1):PAGE85_I111@MSTR_SCONN.SCONN288_H44441004(CHIPS)':
 C_PATH='@baseboard_fab2_lib.baseboard_fab2(sch_1):page85_i111@mstr_sconn.sconn2~
88_h44441004(chips)',
 P_PATH='@baseboard_fab2_lib.baseboard_fab2(sch_1):page85_i111@mstr_sconn.sconn2~
88_h44441004(chips)',
 PATH='I111',
 DRAWING='@BASEBOARD_FAB2_LIB.BASEBOARD_FAB2(SCH_1):PAGE85',
 SEC_TYPE='PIP',
 MATERIAL='SCONN',
 BOM_COST='MEM',
 PHYS_PAGE='85',
 XY='(-2500,3250)',
 ROT='0',
 VER='1',
 PACK_TYPE='PIP',
 PART_NUMBER='H44441-004',
 LOCATION='J1A2',
 ROOM='DDR4_CH_L',
 SEC='1',
 CDS_LIB='mstr_sconn',
 CDS_PART_NAME='SCONN288_H44441004_PIP-SCONN,HA',
 PRIM_FILE='./archive_libs/mstr_sconn/sconn288_h44441004/chips/chips.prt';

SECTION_NUMBER 2
 '@BASEBOARD_FAB2_LIB.BASEBOARD_FAB2(SCH_1):PAGE85_I66@MSTR_SCONN.SCONN288_H44441004(CHIPS)':
 C_PATH='@baseboard_fab2_lib.baseboard_fab2(sch_1):page85_i66@mstr_sconn.sconn28~
8_h44441004(chips)',
 P_PATH='@baseboard_fab2_lib.baseboard_fab2(sch_1):page85_i66@mstr_sconn.sconn28~
8_h44441004(chips)',
 PATH='I66',
 DRAWING='@BASEBOARD_FAB2_LIB.BASEBOARD_FAB2(SCH_1):PAGE85',
 SEC_TYPE='PIP',
 MATERIAL='SCONN',
 BOM_COST='MEM',
 PHYS_PAGE='85',
 XY='(0,4300)',
 ROT='0',
 VER='2',
 PACK_TYPE='PIP',
 PART_NUMBER='H44441-004',
 LOCATION='J1A2',
 ROOM='DDR4_CH_L',
 SEC='2',
 CDS_LIB='mstr_sconn',
 CDS_PART_NAME='SCONN288_H44441004_PIP-SCONN,HA',
 PRIM_FILE='./archive_libs/mstr_sconn/sconn288_h44441004/chips/chips.prt';

SECTION_NUMBER 3
 '@BASEBOARD_FAB2_LIB.BASEBOARD_FAB2(SCH_1):PAGE85_I43@MSTR_SCONN.SCONN288_H44441004(CHIPS)':
 C_PATH='@baseboard_fab2_lib.baseboard_fab2(sch_1):page85_i43@mstr_sconn.sconn28~
8_h44441004(chips)',
 P_PATH='@baseboard_fab2_lib.baseboard_fab2(sch_1):page85_i43@mstr_sconn.sconn28~
8_h44441004(chips)',
 PATH='I43',
 DRAWING='@BASEBOARD_FAB2_LIB.BASEBOARD_FAB2(SCH_1):PAGE85',
 SEC_TYPE='PIP',
 MATERIAL='SCONN',
 BOM_COST='MEM',
 PHYS_PAGE='85',
 XY='(1800,2400)',
 ROT='0',
 VER='3',
 PACK_TYPE='PIP',
 PART_NUMBER='H44441-004',
 LOCATION='J1A2',
 ROOM='DDR4_CH_L',
 SEC='3',
 CDS_LIB='mstr_sconn',
 CDS_PART_NAME='SCONN288_H44441004_PIP-SCONN,HA',
 PRIM_FILE='./archive_libs/mstr_sconn/sconn288_h44441004/chips/chips.prt';

SECTION_NUMBER 4
 '@BASEBOARD_FAB2_LIB.BASEBOARD_FAB2(SCH_1):PAGE85_I172@MSTR_SCONN.SCONN288_H44441004(CHIPS)':
 C_PATH='@baseboard_fab2_lib.baseboard_fab2(sch_1):page85_i172@mstr_sconn.sconn2~
88_h44441004(chips)',
 P_PATH='@baseboard_fab2_lib.baseboard_fab2(sch_1):page85_i172@mstr_sconn.sconn2~
88_h44441004(chips)',
 PATH='I172',
 DRAWING='@BASEBOARD_FAB2_LIB.BASEBOARD_FAB2(SCH_1):PAGE85',
 SEC_TYPE='PIP',
 MATERIAL='SCONN',
 BOM_COST='MEM',
 PHYS_PAGE='85',
 XY='(-250,2050)',
 ROT='0',
 VER='4',
 PACK_TYPE='PIP',
 PART_NUMBER='H44441-004',
 LOCATION='J1A2',
 ROOM='DDR4_CH_L',
 SEC='4',
 CDS_LIB='mstr_sconn',
 CDS_PART_NAME='SCONN288_H44441004_PIP-SCONN,HA',
 PRIM_FILE='./archive_libs/mstr_sconn/sconn288_h44441004/chips/chips.prt';

PART_NAME
 J1B1 'SCONN288_H44441004_PIP-SCONN,HA':
 ROOM='DDR4_CH_K';

SECTION_NUMBER 1
 '@BASEBOARD_FAB2_LIB.BASEBOARD_FAB2(SCH_1):PAGE83_I111@MSTR_SCONN.SCONN288_H44441004(CHIPS)':
 C_PATH='@baseboard_fab2_lib.baseboard_fab2(sch_1):page83_i111@mstr_sconn.sconn2~
88_h44441004(chips)',
 P_PATH='@baseboard_fab2_lib.baseboard_fab2(sch_1):page83_i111@mstr_sconn.sconn2~
88_h44441004(chips)',
 PATH='I111',
 DRAWING='@BASEBOARD_FAB2_LIB.BASEBOARD_FAB2(SCH_1):PAGE83',
 SEC_TYPE='PIP',
 MATERIAL='SCONN',
 BOM_COST='MEM',
 PHYS_PAGE='83',
 XY='(-2450,3200)',
 ROT='0',
 VER='1',
 PACK_TYPE='PIP',
 PART_NUMBER='H44441-004',
 LOCATION='J1B1',
 ROOM='DDR4_CH_K',
 SEC='1',
 CDS_LIB='mstr_sconn',
 CDS_PART_NAME='SCONN288_H44441004_PIP-SCONN,HA',
 PRIM_FILE='./archive_libs/mstr_sconn/sconn288_h44441004/chips/chips.prt';

SECTION_NUMBER 2
 '@BASEBOARD_FAB2_LIB.BASEBOARD_FAB2(SCH_1):PAGE83_I66@MSTR_SCONN.SCONN288_H44441004(CHIPS)':
 C_PATH='@baseboard_fab2_lib.baseboard_fab2(sch_1):page83_i66@mstr_sconn.sconn28~
8_h44441004(chips)',
 P_PATH='@baseboard_fab2_lib.baseboard_fab2(sch_1):page83_i66@mstr_sconn.sconn28~
8_h44441004(chips)',
 PATH='I66',
 DRAWING='@BASEBOARD_FAB2_LIB.BASEBOARD_FAB2(SCH_1):PAGE83',
 SEC_TYPE='PIP',
 MATERIAL='SCONN',
 BOM_COST='MEM',
 PHYS_PAGE='83',
 XY='(0,4350)',
 ROT='0',
 VER='2',
 PACK_TYPE='PIP',
 PART_NUMBER='H44441-004',
 LOCATION='J1B1',
 ROOM='DDR4_CH_K',
 SEC='2',
 CDS_LIB='mstr_sconn',
 CDS_PART_NAME='SCONN288_H44441004_PIP-SCONN,HA',
 PRIM_FILE='./archive_libs/mstr_sconn/sconn288_h44441004/chips/chips.prt';

SECTION_NUMBER 3
 '@BASEBOARD_FAB2_LIB.BASEBOARD_FAB2(SCH_1):PAGE83_I43@MSTR_SCONN.SCONN288_H44441004(CHIPS)':
 C_PATH='@baseboard_fab2_lib.baseboard_fab2(sch_1):page83_i43@mstr_sconn.sconn28~
8_h44441004(chips)',
 P_PATH='@baseboard_fab2_lib.baseboard_fab2(sch_1):page83_i43@mstr_sconn.sconn28~
8_h44441004(chips)',
 PATH='I43',
 DRAWING='@BASEBOARD_FAB2_LIB.BASEBOARD_FAB2(SCH_1):PAGE83',
 SEC_TYPE='PIP',
 MATERIAL='SCONN',
 BOM_COST='MEM',
 PHYS_PAGE='83',
 XY='(1800,2400)',
 ROT='0',
 VER='3',
 PACK_TYPE='PIP',
 PART_NUMBER='H44441-004',
 LOCATION='J1B1',
 ROOM='DDR4_CH_K',
 SEC='3',
 CDS_LIB='mstr_sconn',
 CDS_PART_NAME='SCONN288_H44441004_PIP-SCONN,HA',
 PRIM_FILE='./archive_libs/mstr_sconn/sconn288_h44441004/chips/chips.prt';

SECTION_NUMBER 4
 '@BASEBOARD_FAB2_LIB.BASEBOARD_FAB2(SCH_1):PAGE83_I167@MSTR_SCONN.SCONN288_H44441004(CHIPS)':
 C_PATH='@baseboard_fab2_lib.baseboard_fab2(sch_1):page83_i167@mstr_sconn.sconn2~
88_h44441004(chips)',
 P_PATH='@baseboard_fab2_lib.baseboard_fab2(sch_1):page83_i167@mstr_sconn.sconn2~
88_h44441004(chips)',
 PATH='I167',
 DRAWING='@BASEBOARD_FAB2_LIB.BASEBOARD_FAB2(SCH_1):PAGE83',
 SEC_TYPE='PIP',
 MATERIAL='SCONN',
 BOM_COST='MEM',
 PHYS_PAGE='83',
 XY='(-150,2100)',
 ROT='0',
 VER='4',
 PACK_TYPE='PIP',
 PART_NUMBER='H44441-004',
 LOCATION='J1B1',
 ROOM='DDR4_CH_K',
 SEC='4',
 CDS_LIB='mstr_sconn',
 CDS_PART_NAME='SCONN288_H44441004_PIP-SCONN,HA',
 PRIM_FILE='./archive_libs/mstr_sconn/sconn288_h44441004/chips/chips.prt';

PART_NAME
 J1B2 'CONN6_C74770005_PIP-HDR,C74770A':
 ROOM='CPU_FANS';

SECTION_NUMBER 1
 '@BASEBOARD_FAB2_LIB.BASEBOARD_FAB2(SCH_1):PAGE251_I25@MSTR_CONN.CONN6_C74770005(CHIPS)':
 C_PATH='@baseboard_fab2_lib.baseboard_fab2(sch_1):page251_i25@mstr_conn.conn6_c~
74770005(chips)',
 P_PATH='@baseboard_fab2_lib.baseboard_fab2(sch_1):page251_i25@mstr_conn.conn6_c~
74770005(chips)',
 PATH='I25',
 DRAWING='@BASEBOARD_FAB2_LIB.BASEBOARD_FAB2(SCH_1):PAGE251',
 TOLERANCE='10%',
 SEC_TYPE='PIP',
 MATERIAL='HDR',
 BOM_COST='SM_THERM',
 PHYS_PAGE='251',
 XY='(-1550,5200)',
 ROT='0',
 VER='1',
 VALUE='0.22UF',
 PACK_TYPE='PIP',
 PART_NUMBER='C74770-005',
 LOCATION='J1B2',
 ROOM='CPU_FANS',
 SEC='1',
 CDS_LIB='mstr_conn',
 CDS_PART_NAME='CONN6_C74770005_PIP-HDR,C74770A',
 VOLTAGE='16V',
 PRIM_FILE='./archive_libs/mstr_conn/conn6_c74770005/chips/chips.prt';

PART_NAME
 J1B4 'CLX-CONN3A-1-GP_CONN-G3-CLX-COA':;

SECTION_NUMBER 1
 '@BASEBOARD_FAB2_LIB.BASEBOARD_FAB2(SCH_1):PAGE199_I131@W_HDL.CLX-CONN3A-1-GP(CHIPS)':
 C_PATH='@baseboard_fab2_lib.baseboard_fab2(sch_1):page199_i131@w_hdl.\clx-conn3~
a-1-gp\(chips)',
 P_PATH='@baseboard_fab2_lib.baseboard_fab2(sch_1):page199_i131@w_hdl.\clx-conn3~
a-1-gp\(chips)',
 PATH='I131',
 DRAWING='@BASEBOARD_FAB2_LIB.BASEBOARD_FAB2(SCH_1):PAGE199',
 SEC_TYPE='CONN-G3',
 PHYS_PAGE='199',
 XY='(-7750,725)',
 ROT='0',
 VER='1',
 VALUE='CLX-CONN3A-1-GP',
 PACK_TYPE='CONN-G3',
 PART_NUMBER='021.D0139.0103',
 LOCATION='J1B4',
 SEC='1',
 CDS_LIB='w_hdl',
 CDS_PART_NAME='CLX-CONN3A-1-GP_CONN-G3-CLX-COA',
 PRIM_FILE='C:/<user>/w_hdl/clx#2dconn3a#2d1#2dgp/chips/chips.prt';

PART_NAME
 J1C1 'DM-FCI-CONN76-8R-GP-U-01_CONN-A':;

SECTION_NUMBER 1
 '@BASEBOARD_FAB2_LIB.BASEBOARD_FAB2(SCH_1):PAGE182_I79@W_HDL.DM-FCI-CONN76-8R-GP-U-01(CHIPS)':
 C_PATH='@baseboard_fab2_lib.baseboard_fab2(sch_1):page182_i79@w_hdl.\dm-fci-con~
n76-8r-gp-u-01\(chips)',
 P_PATH='@baseboard_fab2_lib.baseboard_fab2(sch_1):page182_i79@w_hdl.\dm-fci-con~
n76-8r-gp-u-01\(chips)',
 PATH='I79',
 DRAWING='@BASEBOARD_FAB2_LIB.BASEBOARD_FAB2(SCH_1):PAGE182',
 NEW_PN='20.82092.076',
 CONFIG='H22707-001',
 SEC_TYPE='CONN-G4',
 PHYS_PAGE='182',
 XY='(-5000,2050)',
 ROT='0',
 VER='1',
 VALUE='DM-FCI-CONN76-8R-GP-U-01',
 PACK_TYPE='CONN-G4',
 PART_NUMBER='ZZ.82092.07601',
 LOCATION='J1C1',
 SEC='1',
 CDS_LIB='w_hdl',
 CDS_PART_NAME='DM-FCI-CONN76-8R-GP-U-01_CONN-A',
 PRIM_FILE='C:/<user>/w_hdl/dm#2dfci#2dconn76#2d8r#2dgp#2du#2d01/chips/chips~
.prt';

PART_NAME
 J1D1 'FCI-CONN12-2R-GP_CONN-G5-FCI-CA':;

SECTION_NUMBER 1
 '@BASEBOARD_FAB2_LIB.BASEBOARD_FAB2(SCH_1):PAGE195_I115@W_HDL.FCI-CONN12-2R-GP(CHIPS)':
 C_PATH='@baseboard_fab2_lib.baseboard_fab2(sch_1):page195_i115@w_hdl.\fci-conn1~
2-2r-gp\(chips)',
 P_PATH='@baseboard_fab2_lib.baseboard_fab2(sch_1):page195_i115@w_hdl.\fci-conn1~
2-2r-gp\(chips)',
 PATH='I115',
 DRAWING='@BASEBOARD_FAB2_LIB.BASEBOARD_FAB2(SCH_1):PAGE195',
 POP='NOPOP',
 SEC_TYPE='CONN-G5',
 PHYS_PAGE='195',
 XY='(-1250,2150)',
 ROT='0',
 VER='1',
 VALUE='FCI-CONN12-2R-GP',
 PACK_TYPE='CONN-G5',
 PART_NUMBER='20.82093.012',
 LOCATION='J1D1',
 SEC='1',
 CDS_LIB='w_hdl',
 CDS_PART_NAME='FCI-CONN12-2R-GP_CONN-G5-FCI-CA',
 PRIM_FILE='C:/<user>/w_hdl/fci#2dconn12#2d2r#2dgp/chips/chips.prt';

PART_NAME
 J1E1 'FCI-CONN12-2R-GP_CONN-G5-FCI-CA':;

SECTION_NUMBER 1
 '@BASEBOARD_FAB2_LIB.BASEBOARD_FAB2(SCH_1):PAGE195_I114@W_HDL.FCI-CONN12-2R-GP(CHIPS)':
 C_PATH='@baseboard_fab2_lib.baseboard_fab2(sch_1):page195_i114@w_hdl.\fci-conn1~
2-2r-gp\(chips)',
 P_PATH='@baseboard_fab2_lib.baseboard_fab2(sch_1):page195_i114@w_hdl.\fci-conn1~
2-2r-gp\(chips)',
 PATH='I114',
 DRAWING='@BASEBOARD_FAB2_LIB.BASEBOARD_FAB2(SCH_1):PAGE195',
 SEC_TYPE='CONN-G5',
 PHYS_PAGE='195',
 XY='(-3025,2150)',
 ROT='0',
 VER='1',
 VALUE='FCI-CONN12-2R-GP',
 PACK_TYPE='CONN-G5',
 PART_NUMBER='20.82093.012',
 LOCATION='J1E1',
 SEC='1',
 CDS_LIB='w_hdl',
 CDS_PART_NAME='FCI-CONN12-2R-GP_CONN-G5-FCI-CA',
 PRIM_FILE='C:/<user>/w_hdl/fci#2dconn12#2d2r#2dgp/chips/chips.prt';

PART_NAME
 J1F1 'DM-FCI-CONN76-8R-GP-U-01_CONN-A':;

SECTION_NUMBER 1
 '@BASEBOARD_FAB2_LIB.BASEBOARD_FAB2(SCH_1):PAGE181_I134@W_HDL.DM-FCI-CONN76-8R-GP-U-01(CHIPS)':
 C_PATH='@baseboard_fab2_lib.baseboard_fab2(sch_1):page181_i134@w_hdl.\dm-fci-co~
nn76-8r-gp-u-01\(chips)',
 P_PATH='@baseboard_fab2_lib.baseboard_fab2(sch_1):page181_i134@w_hdl.\dm-fci-co~
nn76-8r-gp-u-01\(chips)',
 PATH='I134',
 DRAWING='@BASEBOARD_FAB2_LIB.BASEBOARD_FAB2(SCH_1):PAGE181',
 NEW_PN='20.82092.076',
 CONFIG='H22707-001',
 SEC_TYPE='CONN-G4',
 PHYS_PAGE='181',
 XY='(100,3475)',
 ROT='0',
 VER='1',
 VALUE='DM-FCI-CONN76-8R-GP-U-01',
 PACK_TYPE='CONN-G4',
 PART_NUMBER='ZZ.82092.07601',
 LOCATION='J1F1',
 SEC='1',
 CDS_LIB='w_hdl',
 CDS_PART_NAME='DM-FCI-CONN76-8R-GP-U-01_CONN-A',
 PRIM_FILE='C:/<user>/w_hdl/dm#2dfci#2dconn76#2d8r#2dgp#2du#2d01/chips/chips~
.prt';

PART_NAME
 J1F2 'LOTES-CON4-S1-GP_CONN-G7-LOTESA':;

SECTION_NUMBER 1
 '@BASEBOARD_FAB2_LIB.BASEBOARD_FAB2(SCH_1):PAGE161_I139@W_HDL.LOTES-CON4-S1-GP(CHIPS)':
 C_PATH='@baseboard_fab2_lib.baseboard_fab2(sch_1):page161_i139@w_hdl.\lotes-con~
4-s1-gp\(chips)',
 P_PATH='@baseboard_fab2_lib.baseboard_fab2(sch_1):page161_i139@w_hdl.\lotes-con~
4-s1-gp\(chips)',
 PATH='I139',
 DRAWING='@BASEBOARD_FAB2_LIB.BASEBOARD_FAB2(SCH_1):PAGE161',
 SEC_TYPE='CONN-G7',
 PHYS_PAGE='161',
 XY='(-600,3875)',
 ROT='0',
 VER='1',
 VALUE='LOTES-CON4-S1-GP',
 PACK_TYPE='CONN-G7',
 PART_NUMBER='021.60521.0104',
 LOCATION='J1F2',
 SEC='1',
 CDS_LIB='w_hdl',
 CDS_PART_NAME='LOTES-CON4-S1-GP_CONN-G7-LOTESA',
 PRIM_FILE='C:/<user>/w_hdl/lotes#2dcon4#2ds1#2dgp/chips/chips.prt';

PART_NAME
 J1F3 'CONN8_H62179001_PIP-CONN,H6217A':
 ROOM='IO_SLOT';

SECTION_NUMBER 1
 '@BASEBOARD_FAB2_LIB.BASEBOARD_FAB2(SCH_1):PAGE181_I106@MSTR_CONN.CONN8_H62179001(CHIPS)':
 C_PATH='@baseboard_fab2_lib.baseboard_fab2(sch_1):page181_i106@mstr_conn.conn8_~
h62179001(chips)',
 P_PATH='@baseboard_fab2_lib.baseboard_fab2(sch_1):page181_i106@mstr_conn.conn8_~
h62179001(chips)',
 PATH='I106',
 DRAWING='@BASEBOARD_FAB2_LIB.BASEBOARD_FAB2(SCH_1):PAGE181',
 POP='NOPOP',
 MATERIAL='CONN',
 PHYS_PAGE='181',
 XY='(4100,1250)',
 ROT='0',
 VER='1',
 PACK_TYPE='PIP',
 PART_NUMBER='H62179-001',
 LOCATION='J1F3',
 ROOM='IO_SLOT',
 CDS_LIB='mstr_conn',
 CDS_PART_NAME='CONN8_H62179001_PIP-CONN,H6217A',
 PRIM_FILE='./archive_libs/mstr_conn/conn8_h62179001/chips/chips.prt';

PART_NAME
 J1G1 'SCONN288_H44441004_PIP-SCONN,HA':
 ROOM='DDR4_CH_G';

SECTION_NUMBER 1
 '@BASEBOARD_FAB2_LIB.BASEBOARD_FAB2(SCH_1):PAGE77_I111@MSTR_SCONN.SCONN288_H44441004(CHIPS)':
 C_PATH='@baseboard_fab2_lib.baseboard_fab2(sch_1):page77_i111@mstr_sconn.sconn2~
88_h44441004(chips)',
 P_PATH='@baseboard_fab2_lib.baseboard_fab2(sch_1):page77_i111@mstr_sconn.sconn2~
88_h44441004(chips)',
 PATH='I111',
 DRAWING='@BASEBOARD_FAB2_LIB.BASEBOARD_FAB2(SCH_1):PAGE77',
 SEC_TYPE='PIP',
 MATERIAL='SCONN',
 BOM_COST='MEM',
 PHYS_PAGE='77',
 XY='(-2375,2775)',
 ROT='0',
 VER='1',
 PACK_TYPE='PIP',
 PART_NUMBER='H44441-004',
 LOCATION='J1G1',
 ROOM='DDR4_CH_G',
 SEC='1',
 CDS_LIB='mstr_sconn',
 CDS_PART_NAME='SCONN288_H44441004_PIP-SCONN,HA',
 PRIM_FILE='./archive_libs/mstr_sconn/sconn288_h44441004/chips/chips.prt';

SECTION_NUMBER 2
 '@BASEBOARD_FAB2_LIB.BASEBOARD_FAB2(SCH_1):PAGE77_I66@MSTR_SCONN.SCONN288_H44441004(CHIPS)':
 C_PATH='@baseboard_fab2_lib.baseboard_fab2(sch_1):page77_i66@mstr_sconn.sconn28~
8_h44441004(chips)',
 P_PATH='@baseboard_fab2_lib.baseboard_fab2(sch_1):page77_i66@mstr_sconn.sconn28~
8_h44441004(chips)',
 PATH='I66',
 DRAWING='@BASEBOARD_FAB2_LIB.BASEBOARD_FAB2(SCH_1):PAGE77',
 SEC_TYPE='PIP',
 MATERIAL='SCONN',
 BOM_COST='MEM',
 PHYS_PAGE='77',
 XY='(0,4200)',
 ROT='0',
 VER='2',
 PACK_TYPE='PIP',
 PART_NUMBER='H44441-004',
 LOCATION='J1G1',
 ROOM='DDR4_CH_G',
 SEC='2',
 CDS_LIB='mstr_sconn',
 CDS_PART_NAME='SCONN288_H44441004_PIP-SCONN,HA',
 PRIM_FILE='./archive_libs/mstr_sconn/sconn288_h44441004/chips/chips.prt';

SECTION_NUMBER 3
 '@BASEBOARD_FAB2_LIB.BASEBOARD_FAB2(SCH_1):PAGE77_I43@MSTR_SCONN.SCONN288_H44441004(CHIPS)':
 C_PATH='@baseboard_fab2_lib.baseboard_fab2(sch_1):page77_i43@mstr_sconn.sconn28~
8_h44441004(chips)',
 P_PATH='@baseboard_fab2_lib.baseboard_fab2(sch_1):page77_i43@mstr_sconn.sconn28~
8_h44441004(chips)',
 PATH='I43',
 DRAWING='@BASEBOARD_FAB2_LIB.BASEBOARD_FAB2(SCH_1):PAGE77',
 SEC_TYPE='PIP',
 MATERIAL='SCONN',
 BOM_COST='MEM',
 PHYS_PAGE='77',
 XY='(1800,2200)',
 ROT='0',
 VER='3',
 PACK_TYPE='PIP',
 PART_NUMBER='H44441-004',
 LOCATION='J1G1',
 ROOM='DDR4_CH_G',
 SEC='3',
 CDS_LIB='mstr_sconn',
 CDS_PART_NAME='SCONN288_H44441004_PIP-SCONN,HA',
 PRIM_FILE='./archive_libs/mstr_sconn/sconn288_h44441004/chips/chips.prt';

SECTION_NUMBER 4
 '@BASEBOARD_FAB2_LIB.BASEBOARD_FAB2(SCH_1):PAGE77_I171@MSTR_SCONN.SCONN288_H44441004(CHIPS)':
 C_PATH='@baseboard_fab2_lib.baseboard_fab2(sch_1):page77_i171@mstr_sconn.sconn2~
88_h44441004(chips)',
 P_PATH='@baseboard_fab2_lib.baseboard_fab2(sch_1):page77_i171@mstr_sconn.sconn2~
88_h44441004(chips)',
 PATH='I171',
 DRAWING='@BASEBOARD_FAB2_LIB.BASEBOARD_FAB2(SCH_1):PAGE77',
 SEC_TYPE='PIP',
 MATERIAL='SCONN',
 BOM_COST='MEM',
 PHYS_PAGE='77',
 XY='(-300,1950)',
 ROT='0',
 VER='4',
 PACK_TYPE='PIP',
 PART_NUMBER='H44441-004',
 LOCATION='J1G1',
 ROOM='DDR4_CH_G',
 SEC='4',
 CDS_LIB='mstr_sconn',
 CDS_PART_NAME='SCONN288_H44441004_PIP-SCONN,HA',
 PRIM_FILE='./archive_libs/mstr_sconn/sconn288_h44441004/chips/chips.prt';

PART_NAME
 J1G2 'SCONN288_H44441004_PIP-SCONN,HA':
 ROOM='DDR4_CH_H';

SECTION_NUMBER 1
 '@BASEBOARD_FAB2_LIB.BASEBOARD_FAB2(SCH_1):PAGE79_I111@MSTR_SCONN.SCONN288_H44441004(CHIPS)':
 C_PATH='@baseboard_fab2_lib.baseboard_fab2(sch_1):page79_i111@mstr_sconn.sconn2~
88_h44441004(chips)',
 P_PATH='@baseboard_fab2_lib.baseboard_fab2(sch_1):page79_i111@mstr_sconn.sconn2~
88_h44441004(chips)',
 PATH='I111',
 DRAWING='@BASEBOARD_FAB2_LIB.BASEBOARD_FAB2(SCH_1):PAGE79',
 SEC_TYPE='PIP',
 MATERIAL='SCONN',
 BOM_COST='MEM',
 PHYS_PAGE='79',
 XY='(-2600,3250)',
 ROT='0',
 VER='1',
 PACK_TYPE='PIP',
 PART_NUMBER='H44441-004',
 LOCATION='J1G2',
 ROOM='DDR4_CH_H',
 SEC='1',
 CDS_LIB='mstr_sconn',
 CDS_PART_NAME='SCONN288_H44441004_PIP-SCONN,HA',
 PRIM_FILE='./archive_libs/mstr_sconn/sconn288_h44441004/chips/chips.prt';

SECTION_NUMBER 2
 '@BASEBOARD_FAB2_LIB.BASEBOARD_FAB2(SCH_1):PAGE79_I64@MSTR_SCONN.SCONN288_H44441004(CHIPS)':
 C_PATH='@baseboard_fab2_lib.baseboard_fab2(sch_1):page79_i64@mstr_sconn.sconn28~
8_h44441004(chips)',
 P_PATH='@baseboard_fab2_lib.baseboard_fab2(sch_1):page79_i64@mstr_sconn.sconn28~
8_h44441004(chips)',
 PATH='I64',
 DRAWING='@BASEBOARD_FAB2_LIB.BASEBOARD_FAB2(SCH_1):PAGE79',
 SEC_TYPE='PIP',
 MATERIAL='SCONN',
 BOM_COST='MEM',
 PHYS_PAGE='79',
 XY='(-50,4300)',
 ROT='0',
 VER='2',
 PACK_TYPE='PIP',
 PART_NUMBER='H44441-004',
 LOCATION='J1G2',
 ROOM='DDR4_CH_H',
 SEC='2',
 CDS_LIB='mstr_sconn',
 CDS_PART_NAME='SCONN288_H44441004_PIP-SCONN,HA',
 PRIM_FILE='./archive_libs/mstr_sconn/sconn288_h44441004/chips/chips.prt';

SECTION_NUMBER 3
 '@BASEBOARD_FAB2_LIB.BASEBOARD_FAB2(SCH_1):PAGE79_I43@MSTR_SCONN.SCONN288_H44441004(CHIPS)':
 C_PATH='@baseboard_fab2_lib.baseboard_fab2(sch_1):page79_i43@mstr_sconn.sconn28~
8_h44441004(chips)',
 P_PATH='@baseboard_fab2_lib.baseboard_fab2(sch_1):page79_i43@mstr_sconn.sconn28~
8_h44441004(chips)',
 PATH='I43',
 DRAWING='@BASEBOARD_FAB2_LIB.BASEBOARD_FAB2(SCH_1):PAGE79',
 SEC_TYPE='PIP',
 MATERIAL='SCONN',
 BOM_COST='MEM',
 PHYS_PAGE='79',
 XY='(1750,2400)',
 ROT='0',
 VER='3',
 PACK_TYPE='PIP',
 PART_NUMBER='H44441-004',
 LOCATION='J1G2',
 ROOM='DDR4_CH_H',
 SEC='3',
 CDS_LIB='mstr_sconn',
 CDS_PART_NAME='SCONN288_H44441004_PIP-SCONN,HA',
 PRIM_FILE='./archive_libs/mstr_sconn/sconn288_h44441004/chips/chips.prt';

SECTION_NUMBER 4
 '@BASEBOARD_FAB2_LIB.BASEBOARD_FAB2(SCH_1):PAGE79_I169@MSTR_SCONN.SCONN288_H44441004(CHIPS)':
 C_PATH='@baseboard_fab2_lib.baseboard_fab2(sch_1):page79_i169@mstr_sconn.sconn2~
88_h44441004(chips)',
 P_PATH='@baseboard_fab2_lib.baseboard_fab2(sch_1):page79_i169@mstr_sconn.sconn2~
88_h44441004(chips)',
 PATH='I169',
 DRAWING='@BASEBOARD_FAB2_LIB.BASEBOARD_FAB2(SCH_1):PAGE79',
 SEC_TYPE='PIP',
 MATERIAL='SCONN',
 BOM_COST='MEM',
 PHYS_PAGE='79',
 XY='(-450,2000)',
 ROT='0',
 VER='4',
 PACK_TYPE='PIP',
 PART_NUMBER='H44441-004',
 LOCATION='J1G2',
 ROOM='DDR4_CH_H',
 SEC='4',
 CDS_LIB='mstr_sconn',
 CDS_PART_NAME='SCONN288_H44441004_PIP-SCONN,HA',
 PRIM_FILE='./archive_libs/mstr_sconn/sconn288_h44441004/chips/chips.prt';

PART_NAME
 J1G3 'SCONN288_H44441004_PIP-SCONN,HA':
 ROOM='DDR4_CH_J';

SECTION_NUMBER 1
 '@BASEBOARD_FAB2_LIB.BASEBOARD_FAB2(SCH_1):PAGE81_I186@MSTR_SCONN.SCONN288_H44441004(CHIPS)':
 C_PATH='@baseboard_fab2_lib.baseboard_fab2(sch_1):page81_i186@mstr_sconn.sconn2~
88_h44441004(chips)',
 P_PATH='@baseboard_fab2_lib.baseboard_fab2(sch_1):page81_i186@mstr_sconn.sconn2~
88_h44441004(chips)',
 PATH='I186',
 DRAWING='@BASEBOARD_FAB2_LIB.BASEBOARD_FAB2(SCH_1):PAGE81',
 SEC_TYPE='PIP',
 MATERIAL='SCONN',
 BOM_COST='MEM',
 PHYS_PAGE='81',
 XY='(-2550,3150)',
 ROT='0',
 VER='1',
 PACK_TYPE='PIP',
 PART_NUMBER='H44441-004',
 LOCATION='J1G3',
 ROOM='DDR4_CH_J',
 SEC='1',
 CDS_LIB='mstr_sconn',
 CDS_PART_NAME='SCONN288_H44441004_PIP-SCONN,HA',
 PRIM_FILE='./archive_libs/mstr_sconn/sconn288_h44441004/chips/chips.prt';

SECTION_NUMBER 2
 '@BASEBOARD_FAB2_LIB.BASEBOARD_FAB2(SCH_1):PAGE81_I67@MSTR_SCONN.SCONN288_H44441004(CHIPS)':
 C_PATH='@baseboard_fab2_lib.baseboard_fab2(sch_1):page81_i67@mstr_sconn.sconn28~
8_h44441004(chips)',
 P_PATH='@baseboard_fab2_lib.baseboard_fab2(sch_1):page81_i67@mstr_sconn.sconn28~
8_h44441004(chips)',
 PATH='I67',
 DRAWING='@BASEBOARD_FAB2_LIB.BASEBOARD_FAB2(SCH_1):PAGE81',
 SEC_TYPE='PIP',
 MATERIAL='SCONN',
 BOM_COST='MEM',
 PHYS_PAGE='81',
 XY='(-50,4300)',
 ROT='0',
 VER='2',
 PACK_TYPE='PIP',
 PART_NUMBER='H44441-004',
 LOCATION='J1G3',
 ROOM='DDR4_CH_J',
 SEC='2',
 CDS_LIB='mstr_sconn',
 CDS_PART_NAME='SCONN288_H44441004_PIP-SCONN,HA',
 PRIM_FILE='./archive_libs/mstr_sconn/sconn288_h44441004/chips/chips.prt';

SECTION_NUMBER 3
 '@BASEBOARD_FAB2_LIB.BASEBOARD_FAB2(SCH_1):PAGE81_I185@MSTR_SCONN.SCONN288_H44441004(CHIPS)':
 C_PATH='@baseboard_fab2_lib.baseboard_fab2(sch_1):page81_i185@mstr_sconn.sconn2~
88_h44441004(chips)',
 P_PATH='@baseboard_fab2_lib.baseboard_fab2(sch_1):page81_i185@mstr_sconn.sconn2~
88_h44441004(chips)',
 PATH='I185',
 DRAWING='@BASEBOARD_FAB2_LIB.BASEBOARD_FAB2(SCH_1):PAGE81',
 SEC_TYPE='PIP',
 MATERIAL='SCONN',
 BOM_COST='MEM',
 PHYS_PAGE='81',
 XY='(1750,2400)',
 ROT='0',
 VER='3',
 PACK_TYPE='PIP',
 PART_NUMBER='H44441-004',
 LOCATION='J1G3',
 ROOM='DDR4_CH_J',
 SEC='3',
 CDS_LIB='mstr_sconn',
 CDS_PART_NAME='SCONN288_H44441004_PIP-SCONN,HA',
 PRIM_FILE='./archive_libs/mstr_sconn/sconn288_h44441004/chips/chips.prt';

SECTION_NUMBER 4
 '@BASEBOARD_FAB2_LIB.BASEBOARD_FAB2(SCH_1):PAGE81_I169@MSTR_SCONN.SCONN288_H44441004(CHIPS)':
 C_PATH='@baseboard_fab2_lib.baseboard_fab2(sch_1):page81_i169@mstr_sconn.sconn2~
88_h44441004(chips)',
 P_PATH='@baseboard_fab2_lib.baseboard_fab2(sch_1):page81_i169@mstr_sconn.sconn2~
88_h44441004(chips)',
 PATH='I169',
 DRAWING='@BASEBOARD_FAB2_LIB.BASEBOARD_FAB2(SCH_1):PAGE81',
 SEC_TYPE='PIP',
 MATERIAL='SCONN',
 BOM_COST='MEM',
 PHYS_PAGE='81',
 XY='(-350,2000)',
 ROT='0',
 VER='4',
 PACK_TYPE='PIP',
 PART_NUMBER='H44441-004',
 LOCATION='J1G3',
 ROOM='DDR4_CH_J',
 SEC='4',
 CDS_LIB='mstr_sconn',
 CDS_PART_NAME='SCONN288_H44441004_PIP-SCONN,HA',
 PRIM_FILE='./archive_libs/mstr_sconn/sconn288_h44441004/chips/chips.prt';

PART_NAME
 J2W1 'SKT-SATA7P-6P-165-GP-U1_SOCKETA':;

SECTION_NUMBER 1
 '@BASEBOARD_FAB2_LIB.BASEBOARD_FAB2(SCH_1):PAGE172_I67@W_HDL.SKT-SATA7P-6P-165-GP-U1(CHIPS)':
 C_PATH='@baseboard_fab2_lib.baseboard_fab2(sch_1):page172_i67@w_hdl.\skt-sata7p~
-6p-165-gp-u1\(chips)',
 P_PATH='@baseboard_fab2_lib.baseboard_fab2(sch_1):page172_i67@w_hdl.\skt-sata7p~
-6p-165-gp-u1\(chips)',
 PATH='I67',
 DRAWING='@BASEBOARD_FAB2_LIB.BASEBOARD_FAB2(SCH_1):PAGE172',
 BOM_SS='NOPOP',
 SEC_TYPE='SOCKET-G6',
 PHYS_PAGE='172',
 XY='(-2300,800)',
 ROT='0',
 VER='1',
 VALUE='SKT-SATA7P-6P-165-GP-U1',
 PACK_TYPE='SOCKET-G6',
 PART_NUMBER='022.10014.0121',
 LOCATION='J2W1',
 SEC='1',
 CDS_LIB='w_hdl',
 CDS_PART_NAME='SKT-SATA7P-6P-165-GP-U1_SOCKETA',
 PRIM_FILE='C:/<user>/w_hdl/skt#2dsata7p#2d6p#2d165#2dgp#2du1/chips/chips.pr~
t';

PART_NAME
 J2W2 'SKT-SATA7P-6P-165-GP-U1_SOCKETA':;

SECTION_NUMBER 1
 '@BASEBOARD_FAB2_LIB.BASEBOARD_FAB2(SCH_1):PAGE172_I68@W_HDL.SKT-SATA7P-6P-165-GP-U1(CHIPS)':
 C_PATH='@baseboard_fab2_lib.baseboard_fab2(sch_1):page172_i68@w_hdl.\skt-sata7p~
-6p-165-gp-u1\(chips)',
 P_PATH='@baseboard_fab2_lib.baseboard_fab2(sch_1):page172_i68@w_hdl.\skt-sata7p~
-6p-165-gp-u1\(chips)',
 PATH='I68',
 DRAWING='@BASEBOARD_FAB2_LIB.BASEBOARD_FAB2(SCH_1):PAGE172',
 BOM_DS='NOPOP',
 SEC_TYPE='SOCKET-G6',
 PHYS_PAGE='172',
 XY='(-2300,2050)',
 ROT='0',
 VER='1',
 VALUE='SKT-SATA7P-6P-165-GP-U1',
 PACK_TYPE='SOCKET-G6',
 PART_NUMBER='022.10014.0121',
 LOCATION='J2W2',
 SEC='1',
 CDS_LIB='w_hdl',
 CDS_PART_NAME='SKT-SATA7P-6P-165-GP-U1_SOCKETA',
 PRIM_FILE='C:/<user>/w_hdl/skt#2dsata7p#2d6p#2d165#2dgp#2du1/chips/chips.pr~
t';

PART_NAME
 J4A1 'SCONN288_H44441004_PIP-SCONN,HA':
 ROOM='DDR4_CH_F';

SECTION_NUMBER 1
 '@BASEBOARD_FAB2_LIB.BASEBOARD_FAB2(SCH_1):PAGE53_I111@MSTR_SCONN.SCONN288_H44441004(CHIPS)':
 C_PATH='@baseboard_fab2_lib.baseboard_fab2(sch_1):page53_i111@mstr_sconn.sconn2~
88_h44441004(chips)',
 P_PATH='@baseboard_fab2_lib.baseboard_fab2(sch_1):page53_i111@mstr_sconn.sconn2~
88_h44441004(chips)',
 PATH='I111',
 DRAWING='@BASEBOARD_FAB2_LIB.BASEBOARD_FAB2(SCH_1):PAGE53',
 SEC_TYPE='PIP',
 MATERIAL='SCONN',
 BOM_COST='MEM',
 PHYS_PAGE='53',
 XY='(-2300,2825)',
 ROT='0',
 VER='1',
 PACK_TYPE='PIP',
 PART_NUMBER='H44441-004',
 LOCATION='J4A1',
 ROOM='DDR4_CH_F',
 SEC='1',
 CDS_LIB='mstr_sconn',
 CDS_PART_NAME='SCONN288_H44441004_PIP-SCONN,HA',
 PRIM_FILE='./archive_libs/mstr_sconn/sconn288_h44441004/chips/chips.prt';

SECTION_NUMBER 2
 '@BASEBOARD_FAB2_LIB.BASEBOARD_FAB2(SCH_1):PAGE53_I66@MSTR_SCONN.SCONN288_H44441004(CHIPS)':
 C_PATH='@baseboard_fab2_lib.baseboard_fab2(sch_1):page53_i66@mstr_sconn.sconn28~
8_h44441004(chips)',
 P_PATH='@baseboard_fab2_lib.baseboard_fab2(sch_1):page53_i66@mstr_sconn.sconn28~
8_h44441004(chips)',
 PATH='I66',
 DRAWING='@BASEBOARD_FAB2_LIB.BASEBOARD_FAB2(SCH_1):PAGE53',
 SEC_TYPE='PIP',
 MATERIAL='SCONN',
 BOM_COST='MEM',
 PHYS_PAGE='53',
 XY='(-50,4350)',
 ROT='0',
 VER='2',
 PACK_TYPE='PIP',
 PART_NUMBER='H44441-004',
 LOCATION='J4A1',
 ROOM='DDR4_CH_F',
 SEC='2',
 CDS_LIB='mstr_sconn',
 CDS_PART_NAME='SCONN288_H44441004_PIP-SCONN,HA',
 PRIM_FILE='./archive_libs/mstr_sconn/sconn288_h44441004/chips/chips.prt';

SECTION_NUMBER 3
 '@BASEBOARD_FAB2_LIB.BASEBOARD_FAB2(SCH_1):PAGE53_I43@MSTR_SCONN.SCONN288_H44441004(CHIPS)':
 C_PATH='@baseboard_fab2_lib.baseboard_fab2(sch_1):page53_i43@mstr_sconn.sconn28~
8_h44441004(chips)',
 P_PATH='@baseboard_fab2_lib.baseboard_fab2(sch_1):page53_i43@mstr_sconn.sconn28~
8_h44441004(chips)',
 PATH='I43',
 DRAWING='@BASEBOARD_FAB2_LIB.BASEBOARD_FAB2(SCH_1):PAGE53',
 SEC_TYPE='PIP',
 MATERIAL='SCONN',
 BOM_COST='MEM',
 PHYS_PAGE='53',
 XY='(1750,2400)',
 ROT='0',
 VER='3',
 PACK_TYPE='PIP',
 PART_NUMBER='H44441-004',
 LOCATION='J4A1',
 ROOM='DDR4_CH_F',
 SEC='3',
 CDS_LIB='mstr_sconn',
 CDS_PART_NAME='SCONN288_H44441004_PIP-SCONN,HA',
 PRIM_FILE='./archive_libs/mstr_sconn/sconn288_h44441004/chips/chips.prt';

SECTION_NUMBER 4
 '@BASEBOARD_FAB2_LIB.BASEBOARD_FAB2(SCH_1):PAGE53_I171@MSTR_SCONN.SCONN288_H44441004(CHIPS)':
 C_PATH='@baseboard_fab2_lib.baseboard_fab2(sch_1):page53_i171@mstr_sconn.sconn2~
88_h44441004(chips)',
 P_PATH='@baseboard_fab2_lib.baseboard_fab2(sch_1):page53_i171@mstr_sconn.sconn2~
88_h44441004(chips)',
 PATH='I171',
 DRAWING='@BASEBOARD_FAB2_LIB.BASEBOARD_FAB2(SCH_1):PAGE53',
 SEC_TYPE='PIP',
 MATERIAL='SCONN',
 BOM_COST='MEM',
 PHYS_PAGE='53',
 XY='(-250,2050)',
 ROT='0',
 VER='4',
 PACK_TYPE='PIP',
 PART_NUMBER='H44441-004',
 LOCATION='J4A1',
 ROOM='DDR4_CH_F',
 SEC='4',
 CDS_LIB='mstr_sconn',
 CDS_PART_NAME='SCONN288_H44441004_PIP-SCONN,HA',
 PRIM_FILE='./archive_libs/mstr_sconn/sconn288_h44441004/chips/chips.prt';

PART_NAME
 J4A2 'SCONN288_H44441004_PIP-SCONN,HA':
 ROOM='DDR4_CH_E';

SECTION_NUMBER 1
 '@BASEBOARD_FAB2_LIB.BASEBOARD_FAB2(SCH_1):PAGE51_I111@MSTR_SCONN.SCONN288_H44441004(CHIPS)':
 C_PATH='@baseboard_fab2_lib.baseboard_fab2(sch_1):page51_i111@mstr_sconn.sconn2~
88_h44441004(chips)',
 P_PATH='@baseboard_fab2_lib.baseboard_fab2(sch_1):page51_i111@mstr_sconn.sconn2~
88_h44441004(chips)',
 PATH='I111',
 DRAWING='@BASEBOARD_FAB2_LIB.BASEBOARD_FAB2(SCH_1):PAGE51',
 SEC_TYPE='PIP',
 MATERIAL='SCONN',
 BOM_COST='MEM',
 PHYS_PAGE='51',
 XY='(-2350,3250)',
 ROT='0',
 VER='1',
 PACK_TYPE='PIP',
 PART_NUMBER='H44441-004',
 LOCATION='J4A2',
 ROOM='DDR4_CH_E',
 SEC='1',
 CDS_LIB='mstr_sconn',
 CDS_PART_NAME='SCONN288_H44441004_PIP-SCONN,HA',
 PRIM_FILE='./archive_libs/mstr_sconn/sconn288_h44441004/chips/chips.prt';

SECTION_NUMBER 2
 '@BASEBOARD_FAB2_LIB.BASEBOARD_FAB2(SCH_1):PAGE51_I66@MSTR_SCONN.SCONN288_H44441004(CHIPS)':
 C_PATH='@baseboard_fab2_lib.baseboard_fab2(sch_1):page51_i66@mstr_sconn.sconn28~
8_h44441004(chips)',
 P_PATH='@baseboard_fab2_lib.baseboard_fab2(sch_1):page51_i66@mstr_sconn.sconn28~
8_h44441004(chips)',
 PATH='I66',
 DRAWING='@BASEBOARD_FAB2_LIB.BASEBOARD_FAB2(SCH_1):PAGE51',
 SEC_TYPE='PIP',
 MATERIAL='SCONN',
 BOM_COST='MEM',
 PHYS_PAGE='51',
 XY='(0,4300)',
 ROT='0',
 VER='2',
 PACK_TYPE='PIP',
 PART_NUMBER='H44441-004',
 LOCATION='J4A2',
 ROOM='DDR4_CH_E',
 SEC='2',
 CDS_LIB='mstr_sconn',
 CDS_PART_NAME='SCONN288_H44441004_PIP-SCONN,HA',
 PRIM_FILE='./archive_libs/mstr_sconn/sconn288_h44441004/chips/chips.prt';

SECTION_NUMBER 3
 '@BASEBOARD_FAB2_LIB.BASEBOARD_FAB2(SCH_1):PAGE51_I43@MSTR_SCONN.SCONN288_H44441004(CHIPS)':
 C_PATH='@baseboard_fab2_lib.baseboard_fab2(sch_1):page51_i43@mstr_sconn.sconn28~
8_h44441004(chips)',
 P_PATH='@baseboard_fab2_lib.baseboard_fab2(sch_1):page51_i43@mstr_sconn.sconn28~
8_h44441004(chips)',
 PATH='I43',
 DRAWING='@BASEBOARD_FAB2_LIB.BASEBOARD_FAB2(SCH_1):PAGE51',
 SEC_TYPE='PIP',
 MATERIAL='SCONN',
 BOM_COST='MEM',
 PHYS_PAGE='51',
 XY='(1800,2500)',
 ROT='0',
 VER='3',
 PACK_TYPE='PIP',
 PART_NUMBER='H44441-004',
 LOCATION='J4A2',
 ROOM='DDR4_CH_E',
 SEC='3',
 CDS_LIB='mstr_sconn',
 CDS_PART_NAME='SCONN288_H44441004_PIP-SCONN,HA',
 PRIM_FILE='./archive_libs/mstr_sconn/sconn288_h44441004/chips/chips.prt';

SECTION_NUMBER 4
 '@BASEBOARD_FAB2_LIB.BASEBOARD_FAB2(SCH_1):PAGE51_I167@MSTR_SCONN.SCONN288_H44441004(CHIPS)':
 C_PATH='@baseboard_fab2_lib.baseboard_fab2(sch_1):page51_i167@mstr_sconn.sconn2~
88_h44441004(chips)',
 P_PATH='@baseboard_fab2_lib.baseboard_fab2(sch_1):page51_i167@mstr_sconn.sconn2~
88_h44441004(chips)',
 PATH='I167',
 DRAWING='@BASEBOARD_FAB2_LIB.BASEBOARD_FAB2(SCH_1):PAGE51',
 SEC_TYPE='PIP',
 MATERIAL='SCONN',
 BOM_COST='MEM',
 PHYS_PAGE='51',
 XY='(-150,2050)',
 ROT='0',
 VER='4',
 PACK_TYPE='PIP',
 PART_NUMBER='H44441-004',
 LOCATION='J4A2',
 ROOM='DDR4_CH_E',
 SEC='4',
 CDS_LIB='mstr_sconn',
 CDS_PART_NAME='SCONN288_H44441004_PIP-SCONN,HA',
 PRIM_FILE='./archive_libs/mstr_sconn/sconn288_h44441004/chips/chips.prt';

PART_NAME
 J4B1 'SCONN288_H44441004_PIP-SCONN,HA':
 ROOM='DDR4_CH_D';

SECTION_NUMBER 1
 '@BASEBOARD_FAB2_LIB.BASEBOARD_FAB2(SCH_1):PAGE49_I111@MSTR_SCONN.SCONN288_H44441004(CHIPS)':
 C_PATH='@baseboard_fab2_lib.baseboard_fab2(sch_1):page49_i111@mstr_sconn.sconn2~
88_h44441004(chips)',
 P_PATH='@baseboard_fab2_lib.baseboard_fab2(sch_1):page49_i111@mstr_sconn.sconn2~
88_h44441004(chips)',
 PATH='I111',
 DRAWING='@BASEBOARD_FAB2_LIB.BASEBOARD_FAB2(SCH_1):PAGE49',
 SEC_TYPE='PIP',
 MATERIAL='SCONN',
 BOM_COST='MEM',
 PHYS_PAGE='49',
 XY='(-2500,3500)',
 ROT='0',
 VER='1',
 PACK_TYPE='PIP',
 PART_NUMBER='H44441-004',
 LOCATION='J4B1',
 ROOM='DDR4_CH_D',
 SEC='1',
 CDS_LIB='mstr_sconn',
 CDS_PART_NAME='SCONN288_H44441004_PIP-SCONN,HA',
 PRIM_FILE='./archive_libs/mstr_sconn/sconn288_h44441004/chips/chips.prt';

SECTION_NUMBER 2
 '@BASEBOARD_FAB2_LIB.BASEBOARD_FAB2(SCH_1):PAGE49_I66@MSTR_SCONN.SCONN288_H44441004(CHIPS)':
 C_PATH='@baseboard_fab2_lib.baseboard_fab2(sch_1):page49_i66@mstr_sconn.sconn28~
8_h44441004(chips)',
 P_PATH='@baseboard_fab2_lib.baseboard_fab2(sch_1):page49_i66@mstr_sconn.sconn28~
8_h44441004(chips)',
 PATH='I66',
 DRAWING='@BASEBOARD_FAB2_LIB.BASEBOARD_FAB2(SCH_1):PAGE49',
 SEC_TYPE='PIP',
 MATERIAL='SCONN',
 BOM_COST='MEM',
 PHYS_PAGE='49',
 XY='(-50,4350)',
 ROT='0',
 VER='2',
 PACK_TYPE='PIP',
 PART_NUMBER='H44441-004',
 LOCATION='J4B1',
 ROOM='DDR4_CH_D',
 SEC='2',
 CDS_LIB='mstr_sconn',
 CDS_PART_NAME='SCONN288_H44441004_PIP-SCONN,HA',
 PRIM_FILE='./archive_libs/mstr_sconn/sconn288_h44441004/chips/chips.prt';

SECTION_NUMBER 3
 '@BASEBOARD_FAB2_LIB.BASEBOARD_FAB2(SCH_1):PAGE49_I43@MSTR_SCONN.SCONN288_H44441004(CHIPS)':
 C_PATH='@baseboard_fab2_lib.baseboard_fab2(sch_1):page49_i43@mstr_sconn.sconn28~
8_h44441004(chips)',
 P_PATH='@baseboard_fab2_lib.baseboard_fab2(sch_1):page49_i43@mstr_sconn.sconn28~
8_h44441004(chips)',
 PATH='I43',
 DRAWING='@BASEBOARD_FAB2_LIB.BASEBOARD_FAB2(SCH_1):PAGE49',
 SEC_TYPE='PIP',
 MATERIAL='SCONN',
 BOM_COST='MEM',
 PHYS_PAGE='49',
 XY='(1800,2450)',
 ROT='0',
 VER='3',
 PACK_TYPE='PIP',
 PART_NUMBER='H44441-004',
 LOCATION='J4B1',
 ROOM='DDR4_CH_D',
 SEC='3',
 CDS_LIB='mstr_sconn',
 CDS_PART_NAME='SCONN288_H44441004_PIP-SCONN,HA',
 PRIM_FILE='./archive_libs/mstr_sconn/sconn288_h44441004/chips/chips.prt';

SECTION_NUMBER 4
 '@BASEBOARD_FAB2_LIB.BASEBOARD_FAB2(SCH_1):PAGE49_I169@MSTR_SCONN.SCONN288_H44441004(CHIPS)':
 C_PATH='@baseboard_fab2_lib.baseboard_fab2(sch_1):page49_i169@mstr_sconn.sconn2~
88_h44441004(chips)',
 P_PATH='@baseboard_fab2_lib.baseboard_fab2(sch_1):page49_i169@mstr_sconn.sconn2~
88_h44441004(chips)',
 PATH='I169',
 DRAWING='@BASEBOARD_FAB2_LIB.BASEBOARD_FAB2(SCH_1):PAGE49',
 SEC_TYPE='PIP',
 MATERIAL='SCONN',
 BOM_COST='MEM',
 PHYS_PAGE='49',
 XY='(-50,1950)',
 ROT='0',
 VER='4',
 PACK_TYPE='PIP',
 PART_NUMBER='H44441-004',
 LOCATION='J4B1',
 ROOM='DDR4_CH_D',
 SEC='4',
 CDS_LIB='mstr_sconn',
 CDS_PART_NAME='SCONN288_H44441004_PIP-SCONN,HA',
 PRIM_FILE='./archive_libs/mstr_sconn/sconn288_h44441004/chips/chips.prt';

PART_NAME
 J4B2 'SCONN120_H61426002_SM-CONN,H61A':
 GROUP='MCP',
 ROOM='MCP VRM CPU1';

SECTION_NUMBER 1
 '@BASEBOARD_FAB2_LIB.BASEBOARD_FAB2(SCH_1):PAGE193_I46@MSTR_SCONN.SCONN120_H61426002(CHIPS)':
 C_PATH='@baseboard_fab2_lib.baseboard_fab2(sch_1):page193_i46@mstr_sconn.sconn1~
20_h61426002(chips)',
 P_PATH='@baseboard_fab2_lib.baseboard_fab2(sch_1):page193_i46@mstr_sconn.sconn1~
20_h61426002(chips)',
 PATH='I46',
 DRAWING='@BASEBOARD_FAB2_LIB.BASEBOARD_FAB2(SCH_1):PAGE193',
 SEC_TYPE='SM',
 MATERIAL='CONN',
 PHYS_PAGE='193',
 XY='(-6325,2725)',
 ROT='0',
 VER='1',
 PACK_TYPE='SM',
 PART_NUMBER='H61426-002',
 LOCATION='J4B2',
 ROOM='MCP VRM CPU1',
 GROUP='MCP',
 SEC='1',
 CDS_LIB='mstr_sconn',
 CDS_PART_NAME='SCONN120_H61426002_SM-CONN,H61A',
 PRIM_FILE='./archive_libs/mstr_sconn/sconn120_h61426002/chips/chips.prt';

PART_NAME
 J4E1 'SCONN120_H61426002_SM-CONN,H61A':
 GROUP='MCP',
 ROOM='MCP VRM CPU1';

SECTION_NUMBER 1
 '@BASEBOARD_FAB2_LIB.BASEBOARD_FAB2(SCH_1):PAGE193_I45@MSTR_SCONN.SCONN120_H61426002(CHIPS)':
 C_PATH='@baseboard_fab2_lib.baseboard_fab2(sch_1):page193_i45@mstr_sconn.sconn1~
20_h61426002(chips)',
 P_PATH='@baseboard_fab2_lib.baseboard_fab2(sch_1):page193_i45@mstr_sconn.sconn1~
20_h61426002(chips)',
 PATH='I45',
 DRAWING='@BASEBOARD_FAB2_LIB.BASEBOARD_FAB2(SCH_1):PAGE193',
 SEC_TYPE='SM',
 MATERIAL='CONN',
 PHYS_PAGE='193',
 XY='(-3150,2800)',
 ROT='0',
 VER='1',
 PACK_TYPE='SM',
 PART_NUMBER='H61426-002',
 LOCATION='J4E1',
 ROOM='MCP VRM CPU1',
 GROUP='MCP',
 SEC='1',
 CDS_LIB='mstr_sconn',
 CDS_PART_NAME='SCONN120_H61426002_SM-CONN,H61A',
 PRIM_FILE='./archive_libs/mstr_sconn/sconn120_h61426002/chips/chips.prt';

PART_NAME
 J4G1 'SCONN288_H44441004_PIP-SCONN,HA':
 ROOM='DDR4_CH_A';

SECTION_NUMBER 1
 '@BASEBOARD_FAB2_LIB.BASEBOARD_FAB2(SCH_1):PAGE43_I1@MSTR_SCONN.SCONN288_H44441004(CHIPS)':
 C_PATH='@baseboard_fab2_lib.baseboard_fab2(sch_1):page43_i1@mstr_sconn.sconn288~
_h44441004(chips)',
 P_PATH='@baseboard_fab2_lib.baseboard_fab2(sch_1):page43_i1@mstr_sconn.sconn288~
_h44441004(chips)',
 PATH='I1',
 DRAWING='@BASEBOARD_FAB2_LIB.BASEBOARD_FAB2(SCH_1):PAGE43',
 SEC_TYPE='PIP',
 MATERIAL='SCONN',
 BOM_COST='MEM',
 PHYS_PAGE='43',
 XY='(-2400,2750)',
 ROT='0',
 VER='1',
 PACK_TYPE='PIP',
 PART_NUMBER='H44441-004',
 LOCATION='J4G1',
 ROOM='DDR4_CH_A',
 SEC='1',
 CDS_LIB='mstr_sconn',
 CDS_PART_NAME='SCONN288_H44441004_PIP-SCONN,HA',
 PRIM_FILE='./archive_libs/mstr_sconn/sconn288_h44441004/chips/chips.prt';

SECTION_NUMBER 2
 '@BASEBOARD_FAB2_LIB.BASEBOARD_FAB2(SCH_1):PAGE43_I2@MSTR_SCONN.SCONN288_H44441004(CHIPS)':
 C_PATH='@baseboard_fab2_lib.baseboard_fab2(sch_1):page43_i2@mstr_sconn.sconn288~
_h44441004(chips)',
 P_PATH='@baseboard_fab2_lib.baseboard_fab2(sch_1):page43_i2@mstr_sconn.sconn288~
_h44441004(chips)',
 PATH='I2',
 DRAWING='@BASEBOARD_FAB2_LIB.BASEBOARD_FAB2(SCH_1):PAGE43',
 SEC_TYPE='PIP',
 MATERIAL='SCONN',
 BOM_COST='MEM',
 PHYS_PAGE='43',
 XY='(-50,4050)',
 ROT='0',
 VER='2',
 PACK_TYPE='PIP',
 PART_NUMBER='H44441-004',
 LOCATION='J4G1',
 ROOM='DDR4_CH_A',
 SEC='2',
 CDS_LIB='mstr_sconn',
 CDS_PART_NAME='SCONN288_H44441004_PIP-SCONN,HA',
 PRIM_FILE='./archive_libs/mstr_sconn/sconn288_h44441004/chips/chips.prt';

SECTION_NUMBER 3
 '@BASEBOARD_FAB2_LIB.BASEBOARD_FAB2(SCH_1):PAGE43_I259@MSTR_SCONN.SCONN288_H44441004(CHIPS)':
 C_PATH='@baseboard_fab2_lib.baseboard_fab2(sch_1):page43_i259@mstr_sconn.sconn2~
88_h44441004(chips)',
 P_PATH='@baseboard_fab2_lib.baseboard_fab2(sch_1):page43_i259@mstr_sconn.sconn2~
88_h44441004(chips)',
 PATH='I259',
 DRAWING='@BASEBOARD_FAB2_LIB.BASEBOARD_FAB2(SCH_1):PAGE43',
 SEC_TYPE='PIP',
 MATERIAL='SCONN',
 BOM_COST='MEM',
 PHYS_PAGE='43',
 XY='(1750,2450)',
 ROT='0',
 VER='3',
 PACK_TYPE='PIP',
 PART_NUMBER='H44441-004',
 LOCATION='J4G1',
 ROOM='DDR4_CH_A',
 SEC='3',
 CDS_LIB='mstr_sconn',
 CDS_PART_NAME='SCONN288_H44441004_PIP-SCONN,HA',
 PRIM_FILE='./archive_libs/mstr_sconn/sconn288_h44441004/chips/chips.prt';

SECTION_NUMBER 4
 '@BASEBOARD_FAB2_LIB.BASEBOARD_FAB2(SCH_1):PAGE43_I260@MSTR_SCONN.SCONN288_H44441004(CHIPS)':
 C_PATH='@baseboard_fab2_lib.baseboard_fab2(sch_1):page43_i260@mstr_sconn.sconn2~
88_h44441004(chips)',
 P_PATH='@baseboard_fab2_lib.baseboard_fab2(sch_1):page43_i260@mstr_sconn.sconn2~
88_h44441004(chips)',
 PATH='I260',
 DRAWING='@BASEBOARD_FAB2_LIB.BASEBOARD_FAB2(SCH_1):PAGE43',
 SEC_TYPE='PIP',
 MATERIAL='SCONN',
 BOM_COST='MEM',
 PHYS_PAGE='43',
 XY='(-100,1700)',
 ROT='0',
 VER='4',
 PACK_TYPE='PIP',
 PART_NUMBER='H44441-004',
 LOCATION='J4G1',
 ROOM='DDR4_CH_A',
 SEC='4',
 CDS_LIB='mstr_sconn',
 CDS_PART_NAME='SCONN288_H44441004_PIP-SCONN,HA',
 PRIM_FILE='./archive_libs/mstr_sconn/sconn288_h44441004/chips/chips.prt';

PART_NAME
 J4G2 'SCONN288_H44441004_PIP-SCONN,HA':
 ROOM='DDR4_CH_B';

SECTION_NUMBER 1
 '@BASEBOARD_FAB2_LIB.BASEBOARD_FAB2(SCH_1):PAGE45_I111@MSTR_SCONN.SCONN288_H44441004(CHIPS)':
 C_PATH='@baseboard_fab2_lib.baseboard_fab2(sch_1):page45_i111@mstr_sconn.sconn2~
88_h44441004(chips)',
 P_PATH='@baseboard_fab2_lib.baseboard_fab2(sch_1):page45_i111@mstr_sconn.sconn2~
88_h44441004(chips)',
 PATH='I111',
 DRAWING='@BASEBOARD_FAB2_LIB.BASEBOARD_FAB2(SCH_1):PAGE45',
 SEC_TYPE='PIP',
 MATERIAL='SCONN',
 BOM_COST='MEM',
 PHYS_PAGE='45',
 XY='(-2450,2950)',
 ROT='0',
 VER='1',
 PACK_TYPE='PIP',
 PART_NUMBER='H44441-004',
 LOCATION='J4G2',
 ROOM='DDR4_CH_B',
 SEC='1',
 CDS_LIB='mstr_sconn',
 CDS_PART_NAME='SCONN288_H44441004_PIP-SCONN,HA',
 PRIM_FILE='./archive_libs/mstr_sconn/sconn288_h44441004/chips/chips.prt';

SECTION_NUMBER 2
 '@BASEBOARD_FAB2_LIB.BASEBOARD_FAB2(SCH_1):PAGE45_I61@MSTR_SCONN.SCONN288_H44441004(CHIPS)':
 C_PATH='@baseboard_fab2_lib.baseboard_fab2(sch_1):page45_i61@mstr_sconn.sconn28~
8_h44441004(chips)',
 P_PATH='@baseboard_fab2_lib.baseboard_fab2(sch_1):page45_i61@mstr_sconn.sconn28~
8_h44441004(chips)',
 PATH='I61',
 DRAWING='@BASEBOARD_FAB2_LIB.BASEBOARD_FAB2(SCH_1):PAGE45',
 SEC_TYPE='PIP',
 MATERIAL='SCONN',
 BOM_COST='MEM',
 PHYS_PAGE='45',
 XY='(0,4300)',
 ROT='0',
 VER='2',
 PACK_TYPE='PIP',
 PART_NUMBER='H44441-004',
 LOCATION='J4G2',
 ROOM='DDR4_CH_B',
 SEC='2',
 CDS_LIB='mstr_sconn',
 CDS_PART_NAME='SCONN288_H44441004_PIP-SCONN,HA',
 PRIM_FILE='./archive_libs/mstr_sconn/sconn288_h44441004/chips/chips.prt';

SECTION_NUMBER 3
 '@BASEBOARD_FAB2_LIB.BASEBOARD_FAB2(SCH_1):PAGE45_I43@MSTR_SCONN.SCONN288_H44441004(CHIPS)':
 C_PATH='@baseboard_fab2_lib.baseboard_fab2(sch_1):page45_i43@mstr_sconn.sconn28~
8_h44441004(chips)',
 P_PATH='@baseboard_fab2_lib.baseboard_fab2(sch_1):page45_i43@mstr_sconn.sconn28~
8_h44441004(chips)',
 PATH='I43',
 DRAWING='@BASEBOARD_FAB2_LIB.BASEBOARD_FAB2(SCH_1):PAGE45',
 SEC_TYPE='PIP',
 MATERIAL='SCONN',
 BOM_COST='MEM',
 PHYS_PAGE='45',
 XY='(1800,2600)',
 ROT='0',
 VER='3',
 PACK_TYPE='PIP',
 PART_NUMBER='H44441-004',
 LOCATION='J4G2',
 ROOM='DDR4_CH_B',
 SEC='3',
 CDS_LIB='mstr_sconn',
 CDS_PART_NAME='SCONN288_H44441004_PIP-SCONN,HA',
 PRIM_FILE='./archive_libs/mstr_sconn/sconn288_h44441004/chips/chips.prt';

SECTION_NUMBER 4
 '@BASEBOARD_FAB2_LIB.BASEBOARD_FAB2(SCH_1):PAGE45_I169@MSTR_SCONN.SCONN288_H44441004(CHIPS)':
 C_PATH='@baseboard_fab2_lib.baseboard_fab2(sch_1):page45_i169@mstr_sconn.sconn2~
88_h44441004(chips)',
 P_PATH='@baseboard_fab2_lib.baseboard_fab2(sch_1):page45_i169@mstr_sconn.sconn2~
88_h44441004(chips)',
 PATH='I169',
 DRAWING='@BASEBOARD_FAB2_LIB.BASEBOARD_FAB2(SCH_1):PAGE45',
 SEC_TYPE='PIP',
 MATERIAL='SCONN',
 BOM_COST='MEM',
 PHYS_PAGE='45',
 XY='(50,2000)',
 ROT='0',
 VER='4',
 PACK_TYPE='PIP',
 PART_NUMBER='H44441-004',
 LOCATION='J4G2',
 ROOM='DDR4_CH_B',
 SEC='4',
 CDS_LIB='mstr_sconn',
 CDS_PART_NAME='SCONN288_H44441004_PIP-SCONN,HA',
 PRIM_FILE='./archive_libs/mstr_sconn/sconn288_h44441004/chips/chips.prt';

PART_NAME
 J4G3 'SCONN288_H44441004_PIP-SCONN,HA':
 ROOM='DDR4_CH_C';

SECTION_NUMBER 1
 '@BASEBOARD_FAB2_LIB.BASEBOARD_FAB2(SCH_1):PAGE47_I111@MSTR_SCONN.SCONN288_H44441004(CHIPS)':
 C_PATH='@baseboard_fab2_lib.baseboard_fab2(sch_1):page47_i111@mstr_sconn.sconn2~
88_h44441004(chips)',
 P_PATH='@baseboard_fab2_lib.baseboard_fab2(sch_1):page47_i111@mstr_sconn.sconn2~
88_h44441004(chips)',
 PATH='I111',
 DRAWING='@BASEBOARD_FAB2_LIB.BASEBOARD_FAB2(SCH_1):PAGE47',
 SEC_TYPE='PIP',
 MATERIAL='SCONN',
 BOM_COST='MEM',
 PHYS_PAGE='47',
 XY='(-2450,3000)',
 ROT='0',
 VER='1',
 PACK_TYPE='PIP',
 PART_NUMBER='H44441-004',
 LOCATION='J4G3',
 ROOM='DDR4_CH_C',
 SEC='1',
 CDS_LIB='mstr_sconn',
 CDS_PART_NAME='SCONN288_H44441004_PIP-SCONN,HA',
 PRIM_FILE='./archive_libs/mstr_sconn/sconn288_h44441004/chips/chips.prt';

SECTION_NUMBER 2
 '@BASEBOARD_FAB2_LIB.BASEBOARD_FAB2(SCH_1):PAGE47_I61@MSTR_SCONN.SCONN288_H44441004(CHIPS)':
 C_PATH='@baseboard_fab2_lib.baseboard_fab2(sch_1):page47_i61@mstr_sconn.sconn28~
8_h44441004(chips)',
 P_PATH='@baseboard_fab2_lib.baseboard_fab2(sch_1):page47_i61@mstr_sconn.sconn28~
8_h44441004(chips)',
 PATH='I61',
 DRAWING='@BASEBOARD_FAB2_LIB.BASEBOARD_FAB2(SCH_1):PAGE47',
 SEC_TYPE='PIP',
 MATERIAL='SCONN',
 BOM_COST='MEM',
 PHYS_PAGE='47',
 XY='(0,4350)',
 ROT='0',
 VER='2',
 PACK_TYPE='PIP',
 PART_NUMBER='H44441-004',
 LOCATION='J4G3',
 ROOM='DDR4_CH_C',
 SEC='2',
 CDS_LIB='mstr_sconn',
 CDS_PART_NAME='SCONN288_H44441004_PIP-SCONN,HA',
 PRIM_FILE='./archive_libs/mstr_sconn/sconn288_h44441004/chips/chips.prt';

SECTION_NUMBER 3
 '@BASEBOARD_FAB2_LIB.BASEBOARD_FAB2(SCH_1):PAGE47_I43@MSTR_SCONN.SCONN288_H44441004(CHIPS)':
 C_PATH='@baseboard_fab2_lib.baseboard_fab2(sch_1):page47_i43@mstr_sconn.sconn28~
8_h44441004(chips)',
 P_PATH='@baseboard_fab2_lib.baseboard_fab2(sch_1):page47_i43@mstr_sconn.sconn28~
8_h44441004(chips)',
 PATH='I43',
 DRAWING='@BASEBOARD_FAB2_LIB.BASEBOARD_FAB2(SCH_1):PAGE47',
 SEC_TYPE='PIP',
 MATERIAL='SCONN',
 BOM_COST='MEM',
 PHYS_PAGE='47',
 XY='(1800,2650)',
 ROT='0',
 VER='3',
 PACK_TYPE='PIP',
 PART_NUMBER='H44441-004',
 LOCATION='J4G3',
 ROOM='DDR4_CH_C',
 SEC='3',
 CDS_LIB='mstr_sconn',
 CDS_PART_NAME='SCONN288_H44441004_PIP-SCONN,HA',
 PRIM_FILE='./archive_libs/mstr_sconn/sconn288_h44441004/chips/chips.prt';

SECTION_NUMBER 4
 '@BASEBOARD_FAB2_LIB.BASEBOARD_FAB2(SCH_1):PAGE47_I179@MSTR_SCONN.SCONN288_H44441004(CHIPS)':
 C_PATH='@baseboard_fab2_lib.baseboard_fab2(sch_1):page47_i179@mstr_sconn.sconn2~
88_h44441004(chips)',
 P_PATH='@baseboard_fab2_lib.baseboard_fab2(sch_1):page47_i179@mstr_sconn.sconn2~
88_h44441004(chips)',
 PATH='I179',
 DRAWING='@BASEBOARD_FAB2_LIB.BASEBOARD_FAB2(SCH_1):PAGE47',
 SEC_TYPE='PIP',
 MATERIAL='SCONN',
 BOM_COST='MEM',
 PHYS_PAGE='47',
 XY='(0,2050)',
 ROT='0',
 VER='4',
 PACK_TYPE='PIP',
 PART_NUMBER='H44441-004',
 LOCATION='J4G3',
 ROOM='DDR4_CH_C',
 SEC='4',
 CDS_LIB='mstr_sconn',
 CDS_PART_NAME='SCONN288_H44441004_PIP-SCONN,HA',
 PRIM_FILE='./archive_libs/mstr_sconn/sconn288_h44441004/chips/chips.prt';

PART_NAME
 J6B1 'SCONN120_H61426002_SM-CONN,H61A':
 GROUP='MCP',
 ROOM='MCP VRM CPU0';

SECTION_NUMBER 1
 '@BASEBOARD_FAB2_LIB.BASEBOARD_FAB2(SCH_1):PAGE194_I56@MSTR_SCONN.SCONN120_H61426002(CHIPS)':
 C_PATH='@baseboard_fab2_lib.baseboard_fab2(sch_1):page194_i56@mstr_sconn.sconn1~
20_h61426002(chips)',
 P_PATH='@baseboard_fab2_lib.baseboard_fab2(sch_1):page194_i56@mstr_sconn.sconn1~
20_h61426002(chips)',
 PATH='I56',
 DRAWING='@BASEBOARD_FAB2_LIB.BASEBOARD_FAB2(SCH_1):PAGE194',
 SEC_TYPE='SM',
 MATERIAL='CONN',
 PHYS_PAGE='194',
 XY='(-6550,2075)',
 ROT='0',
 VER='1',
 PACK_TYPE='SM',
 PART_NUMBER='H61426-002',
 LOCATION='J6B1',
 ROOM='MCP VRM CPU0',
 GROUP='MCP',
 SEC='1',
 CDS_LIB='mstr_sconn',
 CDS_PART_NAME='SCONN120_H61426002_SM-CONN,H61A',
 PRIM_FILE='./archive_libs/mstr_sconn/sconn120_h61426002/chips/chips.prt';

PART_NAME
 J6E1 'SCONN120_H61426002_SM-CONN,H61A':
 GROUP='MCP',
 ROOM='MCP VRM CPU0';

SECTION_NUMBER 1
 '@BASEBOARD_FAB2_LIB.BASEBOARD_FAB2(SCH_1):PAGE194_I55@MSTR_SCONN.SCONN120_H61426002(CHIPS)':
 C_PATH='@baseboard_fab2_lib.baseboard_fab2(sch_1):page194_i55@mstr_sconn.sconn1~
20_h61426002(chips)',
 P_PATH='@baseboard_fab2_lib.baseboard_fab2(sch_1):page194_i55@mstr_sconn.sconn1~
20_h61426002(chips)',
 PATH='I55',
 DRAWING='@BASEBOARD_FAB2_LIB.BASEBOARD_FAB2(SCH_1):PAGE194',
 SEC_TYPE='SM',
 MATERIAL='CONN',
 PHYS_PAGE='194',
 XY='(-3150,2100)',
 ROT='0',
 VER='1',
 PACK_TYPE='SM',
 PART_NUMBER='H61426-002',
 LOCATION='J6E1',
 ROOM='MCP VRM CPU0',
 GROUP='MCP',
 SEC='1',
 CDS_LIB='mstr_sconn',
 CDS_PART_NAME='SCONN120_H61426002_SM-CONN,H61A',
 PRIM_FILE='./archive_libs/mstr_sconn/sconn120_h61426002/chips/chips.prt';

PART_NAME
 J6L1 'SCONN288_H44441003_PIP-SCONN,HA':
 ROOM='DDR4_CH_F1';

SECTION_NUMBER 1
 '@BASEBOARD_FAB2_LIB.BASEBOARD_FAB2(SCH_1):PAGE54_I111@MSTR_SCONN.SCONN288_H44441003(CHIPS)':
 C_PATH='@baseboard_fab2_lib.baseboard_fab2(sch_1):page54_i111@mstr_sconn.sconn2~
88_h44441003(chips)',
 P_PATH='@baseboard_fab2_lib.baseboard_fab2(sch_1):page54_i111@mstr_sconn.sconn2~
88_h44441003(chips)',
 PATH='I111',
 DRAWING='@BASEBOARD_FAB2_LIB.BASEBOARD_FAB2(SCH_1):PAGE54',
 BOM_SS='NOPOP',
 SEC_TYPE='PIP',
 MATERIAL='SCONN',
 BOM_COST='MEM',
 PHYS_PAGE='54',
 XY='(-2400,3100)',
 ROT='0',
 VER='1',
 PACK_TYPE='PIP',
 PART_NUMBER='H44441-003',
 LOCATION='J6L1',
 ROOM='DDR4_CH_F1',
 SEC='1',
 CDS_LIB='mstr_sconn',
 CDS_PART_NAME='SCONN288_H44441003_PIP-SCONN,HA',
 PRIM_FILE='./archive_libs/mstr_sconn/sconn288_h44441003/chips/chips.prt';

SECTION_NUMBER 2
 '@BASEBOARD_FAB2_LIB.BASEBOARD_FAB2(SCH_1):PAGE54_I66@MSTR_SCONN.SCONN288_H44441003(CHIPS)':
 C_PATH='@baseboard_fab2_lib.baseboard_fab2(sch_1):page54_i66@mstr_sconn.sconn28~
8_h44441003(chips)',
 P_PATH='@baseboard_fab2_lib.baseboard_fab2(sch_1):page54_i66@mstr_sconn.sconn28~
8_h44441003(chips)',
 PATH='I66',
 DRAWING='@BASEBOARD_FAB2_LIB.BASEBOARD_FAB2(SCH_1):PAGE54',
 BOM_SS='NOPOP',
 SEC_TYPE='PIP',
 MATERIAL='SCONN',
 BOM_COST='MEM',
 PHYS_PAGE='54',
 XY='(0,4300)',
 ROT='0',
 VER='2',
 PACK_TYPE='PIP',
 PART_NUMBER='H44441-003',
 LOCATION='J6L1',
 ROOM='DDR4_CH_F1',
 SEC='2',
 CDS_LIB='mstr_sconn',
 CDS_PART_NAME='SCONN288_H44441003_PIP-SCONN,HA',
 PRIM_FILE='./archive_libs/mstr_sconn/sconn288_h44441003/chips/chips.prt';

SECTION_NUMBER 3
 '@BASEBOARD_FAB2_LIB.BASEBOARD_FAB2(SCH_1):PAGE54_I43@MSTR_SCONN.SCONN288_H44441003(CHIPS)':
 C_PATH='@baseboard_fab2_lib.baseboard_fab2(sch_1):page54_i43@mstr_sconn.sconn28~
8_h44441003(chips)',
 P_PATH='@baseboard_fab2_lib.baseboard_fab2(sch_1):page54_i43@mstr_sconn.sconn28~
8_h44441003(chips)',
 PATH='I43',
 DRAWING='@BASEBOARD_FAB2_LIB.BASEBOARD_FAB2(SCH_1):PAGE54',
 BOM_SS='NOPOP',
 SEC_TYPE='PIP',
 MATERIAL='SCONN',
 BOM_COST='MEM',
 PHYS_PAGE='54',
 XY='(1800,2550)',
 ROT='0',
 VER='3',
 PACK_TYPE='PIP',
 PART_NUMBER='H44441-003',
 LOCATION='J6L1',
 ROOM='DDR4_CH_F1',
 SEC='3',
 CDS_LIB='mstr_sconn',
 CDS_PART_NAME='SCONN288_H44441003_PIP-SCONN,HA',
 PRIM_FILE='./archive_libs/mstr_sconn/sconn288_h44441003/chips/chips.prt';

SECTION_NUMBER 4
 '@BASEBOARD_FAB2_LIB.BASEBOARD_FAB2(SCH_1):PAGE54_I170@MSTR_SCONN.SCONN288_H44441003(CHIPS)':
 C_PATH='@baseboard_fab2_lib.baseboard_fab2(sch_1):page54_i170@mstr_sconn.sconn2~
88_h44441003(chips)',
 P_PATH='@baseboard_fab2_lib.baseboard_fab2(sch_1):page54_i170@mstr_sconn.sconn2~
88_h44441003(chips)',
 PATH='I170',
 DRAWING='@BASEBOARD_FAB2_LIB.BASEBOARD_FAB2(SCH_1):PAGE54',
 BOM_SS='NOPOP',
 SEC_TYPE='PIP',
 MATERIAL='SCONN',
 BOM_COST='MEM',
 PHYS_PAGE='54',
 XY='(-50,1900)',
 ROT='0',
 VER='4',
 PACK_TYPE='PIP',
 PART_NUMBER='H44441-003',
 LOCATION='J6L1',
 ROOM='DDR4_CH_F1',
 SEC='4',
 CDS_LIB='mstr_sconn',
 CDS_PART_NAME='SCONN288_H44441003_PIP-SCONN,HA',
 PRIM_FILE='./archive_libs/mstr_sconn/sconn288_h44441003/chips/chips.prt';

PART_NAME
 J6L2 'SCONN288_H44441003_PIP-SCONN,HA':
 ROOM='DDR4_CH_E';

SECTION_NUMBER 1
 '@BASEBOARD_FAB2_LIB.BASEBOARD_FAB2(SCH_1):PAGE52_I12@MSTR_SCONN.SCONN288_H44441003(CHIPS)':
 C_PATH='@baseboard_fab2_lib.baseboard_fab2(sch_1):page52_i12@mstr_sconn.sconn28~
8_h44441003(chips)',
 P_PATH='@baseboard_fab2_lib.baseboard_fab2(sch_1):page52_i12@mstr_sconn.sconn28~
8_h44441003(chips)',
 PATH='I12',
 DRAWING='@BASEBOARD_FAB2_LIB.BASEBOARD_FAB2(SCH_1):PAGE52',
 BOM_SS='NOPOP',
 SEC_TYPE='PIP',
 MATERIAL='SCONN',
 BOM_COST='MEM',
 PHYS_PAGE='52',
 XY='(-725,2850)',
 ROT='0',
 VER='1',
 PACK_TYPE='PIP',
 PART_NUMBER='H44441-003',
 LOCATION='J6L2',
 ROOM='DDR4_CH_E',
 SEC='1',
 CDS_LIB='mstr_sconn',
 CDS_PART_NAME='SCONN288_H44441003_PIP-SCONN,HA',
 PRIM_FILE='./archive_libs/mstr_sconn/sconn288_h44441003/chips/chips.prt';

SECTION_NUMBER 2
 '@BASEBOARD_FAB2_LIB.BASEBOARD_FAB2(SCH_1):PAGE52_I100@MSTR_SCONN.SCONN288_H44441003(CHIPS)':
 C_PATH='@baseboard_fab2_lib.baseboard_fab2(sch_1):page52_i100@mstr_sconn.sconn2~
88_h44441003(chips)',
 P_PATH='@baseboard_fab2_lib.baseboard_fab2(sch_1):page52_i100@mstr_sconn.sconn2~
88_h44441003(chips)',
 PATH='I100',
 DRAWING='@BASEBOARD_FAB2_LIB.BASEBOARD_FAB2(SCH_1):PAGE52',
 BOM_SS='NOPOP',
 SEC_TYPE='PIP',
 MATERIAL='SCONN',
 BOM_COST='MEM',
 PHYS_PAGE='52',
 XY='(1625,3900)',
 ROT='0',
 VER='2',
 PACK_TYPE='PIP',
 PART_NUMBER='H44441-003',
 LOCATION='J6L2',
 ROOM='DDR4_CH_E',
 SEC='2',
 CDS_LIB='mstr_sconn',
 CDS_PART_NAME='SCONN288_H44441003_PIP-SCONN,HA',
 PRIM_FILE='./archive_libs/mstr_sconn/sconn288_h44441003/chips/chips.prt';

SECTION_NUMBER 3
 '@BASEBOARD_FAB2_LIB.BASEBOARD_FAB2(SCH_1):PAGE52_I138@MSTR_SCONN.SCONN288_H44441003(CHIPS)':
 C_PATH='@baseboard_fab2_lib.baseboard_fab2(sch_1):page52_i138@mstr_sconn.sconn2~
88_h44441003(chips)',
 P_PATH='@baseboard_fab2_lib.baseboard_fab2(sch_1):page52_i138@mstr_sconn.sconn2~
88_h44441003(chips)',
 PATH='I138',
 DRAWING='@BASEBOARD_FAB2_LIB.BASEBOARD_FAB2(SCH_1):PAGE52',
 BOM_SS='NOPOP',
 SEC_TYPE='PIP',
 MATERIAL='SCONN',
 BOM_COST='MEM',
 PHYS_PAGE='52',
 XY='(3425,2100)',
 ROT='0',
 VER='3',
 PACK_TYPE='PIP',
 PART_NUMBER='H44441-003',
 LOCATION='J6L2',
 ROOM='DDR4_CH_E',
 SEC='3',
 CDS_LIB='mstr_sconn',
 CDS_PART_NAME='SCONN288_H44441003_PIP-SCONN,HA',
 PRIM_FILE='./archive_libs/mstr_sconn/sconn288_h44441003/chips/chips.prt';

SECTION_NUMBER 4
 '@BASEBOARD_FAB2_LIB.BASEBOARD_FAB2(SCH_1):PAGE52_I55@MSTR_SCONN.SCONN288_H44441003(CHIPS)':
 C_PATH='@baseboard_fab2_lib.baseboard_fab2(sch_1):page52_i55@mstr_sconn.sconn28~
8_h44441003(chips)',
 P_PATH='@baseboard_fab2_lib.baseboard_fab2(sch_1):page52_i55@mstr_sconn.sconn28~
8_h44441003(chips)',
 PATH='I55',
 DRAWING='@BASEBOARD_FAB2_LIB.BASEBOARD_FAB2(SCH_1):PAGE52',
 BOM_SS='NOPOP',
 SEC_TYPE='PIP',
 MATERIAL='SCONN',
 BOM_COST='MEM',
 PHYS_PAGE='52',
 XY='(1475,1650)',
 ROT='0',
 VER='4',
 PACK_TYPE='PIP',
 PART_NUMBER='H44441-003',
 LOCATION='J6L2',
 ROOM='DDR4_CH_E',
 SEC='4',
 CDS_LIB='mstr_sconn',
 CDS_PART_NAME='SCONN288_H44441003_PIP-SCONN,HA',
 PRIM_FILE='./archive_libs/mstr_sconn/sconn288_h44441003/chips/chips.prt';

PART_NAME
 J6M1 'SCONN288_H44441003_PIP-SCONN,HA':
 ROOM='DDR4_CH_D';

SECTION_NUMBER 1
 '@BASEBOARD_FAB2_LIB.BASEBOARD_FAB2(SCH_1):PAGE50_I158@MSTR_SCONN.SCONN288_H44441003(CHIPS)':
 C_PATH='@baseboard_fab2_lib.baseboard_fab2(sch_1):page50_i158@mstr_sconn.sconn2~
88_h44441003(chips)',
 P_PATH='@baseboard_fab2_lib.baseboard_fab2(sch_1):page50_i158@mstr_sconn.sconn2~
88_h44441003(chips)',
 PATH='I158',
 DRAWING='@BASEBOARD_FAB2_LIB.BASEBOARD_FAB2(SCH_1):PAGE50',
 BOM_SS='NOPOP',
 SEC_TYPE='PIP',
 MATERIAL='SCONN',
 BOM_COST='MEM',
 PHYS_PAGE='50',
 XY='(950,3100)',
 ROT='0',
 VER='1',
 PACK_TYPE='PIP',
 PART_NUMBER='H44441-003',
 LOCATION='J6M1',
 ROOM='DDR4_CH_D',
 SEC='1',
 CDS_LIB='mstr_sconn',
 CDS_PART_NAME='SCONN288_H44441003_PIP-SCONN,HA',
 PRIM_FILE='./archive_libs/mstr_sconn/sconn288_h44441003/chips/chips.prt';

SECTION_NUMBER 2
 '@BASEBOARD_FAB2_LIB.BASEBOARD_FAB2(SCH_1):PAGE50_I46@MSTR_SCONN.SCONN288_H44441003(CHIPS)':
 C_PATH='@baseboard_fab2_lib.baseboard_fab2(sch_1):page50_i46@mstr_sconn.sconn28~
8_h44441003(chips)',
 P_PATH='@baseboard_fab2_lib.baseboard_fab2(sch_1):page50_i46@mstr_sconn.sconn28~
8_h44441003(chips)',
 PATH='I46',
 DRAWING='@BASEBOARD_FAB2_LIB.BASEBOARD_FAB2(SCH_1):PAGE50',
 BOM_SS='NOPOP',
 SEC_TYPE='PIP',
 MATERIAL='SCONN',
 BOM_COST='MEM',
 PHYS_PAGE='50',
 XY='(3400,3950)',
 ROT='0',
 VER='2',
 PACK_TYPE='PIP',
 PART_NUMBER='H44441-003',
 LOCATION='J6M1',
 ROOM='DDR4_CH_D',
 SEC='2',
 CDS_LIB='mstr_sconn',
 CDS_PART_NAME='SCONN288_H44441003_PIP-SCONN,HA',
 PRIM_FILE='./archive_libs/mstr_sconn/sconn288_h44441003/chips/chips.prt';

SECTION_NUMBER 3
 '@BASEBOARD_FAB2_LIB.BASEBOARD_FAB2(SCH_1):PAGE50_I44@MSTR_SCONN.SCONN288_H44441003(CHIPS)':
 C_PATH='@baseboard_fab2_lib.baseboard_fab2(sch_1):page50_i44@mstr_sconn.sconn28~
8_h44441003(chips)',
 P_PATH='@baseboard_fab2_lib.baseboard_fab2(sch_1):page50_i44@mstr_sconn.sconn28~
8_h44441003(chips)',
 PATH='I44',
 DRAWING='@BASEBOARD_FAB2_LIB.BASEBOARD_FAB2(SCH_1):PAGE50',
 BOM_SS='NOPOP',
 SEC_TYPE='PIP',
 MATERIAL='SCONN',
 BOM_COST='MEM',
 PHYS_PAGE='50',
 XY='(5250,2050)',
 ROT='0',
 VER='3',
 PACK_TYPE='PIP',
 PART_NUMBER='H44441-003',
 LOCATION='J6M1',
 ROOM='DDR4_CH_D',
 SEC='3',
 CDS_LIB='mstr_sconn',
 CDS_PART_NAME='SCONN288_H44441003_PIP-SCONN,HA',
 PRIM_FILE='./archive_libs/mstr_sconn/sconn288_h44441003/chips/chips.prt';

SECTION_NUMBER 4
 '@BASEBOARD_FAB2_LIB.BASEBOARD_FAB2(SCH_1):PAGE50_I50@MSTR_SCONN.SCONN288_H44441003(CHIPS)':
 C_PATH='@baseboard_fab2_lib.baseboard_fab2(sch_1):page50_i50@mstr_sconn.sconn28~
8_h44441003(chips)',
 P_PATH='@baseboard_fab2_lib.baseboard_fab2(sch_1):page50_i50@mstr_sconn.sconn28~
8_h44441003(chips)',
 PATH='I50',
 DRAWING='@BASEBOARD_FAB2_LIB.BASEBOARD_FAB2(SCH_1):PAGE50',
 BOM_SS='NOPOP',
 SEC_TYPE='PIP',
 MATERIAL='SCONN',
 BOM_COST='MEM',
 PHYS_PAGE='50',
 XY='(3400,1550)',
 ROT='0',
 VER='4',
 PACK_TYPE='PIP',
 PART_NUMBER='H44441-003',
 LOCATION='J6M1',
 ROOM='DDR4_CH_D',
 SEC='4',
 CDS_LIB='mstr_sconn',
 CDS_PART_NAME='SCONN288_H44441003_PIP-SCONN,HA',
 PRIM_FILE='./archive_libs/mstr_sconn/sconn288_h44441003/chips/chips.prt';

PART_NAME
 J6T1 'SCONN288_H44441003_PIP-SCONN,HA':
 ROOM='DDR4_CH_A';

SECTION_NUMBER 1
 '@BASEBOARD_FAB2_LIB.BASEBOARD_FAB2(SCH_1):PAGE44_I13@MSTR_SCONN.SCONN288_H44441003(CHIPS)':
 C_PATH='@baseboard_fab2_lib.baseboard_fab2(sch_1):page44_i13@mstr_sconn.sconn28~
8_h44441003(chips)',
 P_PATH='@baseboard_fab2_lib.baseboard_fab2(sch_1):page44_i13@mstr_sconn.sconn28~
8_h44441003(chips)',
 PATH='I13',
 DRAWING='@BASEBOARD_FAB2_LIB.BASEBOARD_FAB2(SCH_1):PAGE44',
 BOM_SS='NOPOP',
 SEC_TYPE='PIP',
 MATERIAL='SCONN',
 BOM_COST='MEM',
 PHYS_PAGE='44',
 XY='(-700,2700)',
 ROT='0',
 VER='1',
 PACK_TYPE='PIP',
 PART_NUMBER='H44441-003',
 LOCATION='J6T1',
 ROOM='DDR4_CH_A',
 SEC='1',
 CDS_LIB='mstr_sconn',
 CDS_PART_NAME='SCONN288_H44441003_PIP-SCONN,HA',
 PRIM_FILE='./archive_libs/mstr_sconn/sconn288_h44441003/chips/chips.prt';

SECTION_NUMBER 2
 '@BASEBOARD_FAB2_LIB.BASEBOARD_FAB2(SCH_1):PAGE44_I120@MSTR_SCONN.SCONN288_H44441003(CHIPS)':
 C_PATH='@baseboard_fab2_lib.baseboard_fab2(sch_1):page44_i120@mstr_sconn.sconn2~
88_h44441003(chips)',
 P_PATH='@baseboard_fab2_lib.baseboard_fab2(sch_1):page44_i120@mstr_sconn.sconn2~
88_h44441003(chips)',
 PATH='I120',
 DRAWING='@BASEBOARD_FAB2_LIB.BASEBOARD_FAB2(SCH_1):PAGE44',
 BOM_SS='NOPOP',
 SEC_TYPE='PIP',
 MATERIAL='SCONN',
 BOM_COST='MEM',
 PHYS_PAGE='44',
 XY='(1650,4000)',
 ROT='0',
 VER='2',
 PACK_TYPE='PIP',
 PART_NUMBER='H44441-003',
 LOCATION='J6T1',
 ROOM='DDR4_CH_A',
 SEC='2',
 CDS_LIB='mstr_sconn',
 CDS_PART_NAME='SCONN288_H44441003_PIP-SCONN,HA',
 PRIM_FILE='./archive_libs/mstr_sconn/sconn288_h44441003/chips/chips.prt';

SECTION_NUMBER 3
 '@BASEBOARD_FAB2_LIB.BASEBOARD_FAB2(SCH_1):PAGE44_I139@MSTR_SCONN.SCONN288_H44441003(CHIPS)':
 C_PATH='@baseboard_fab2_lib.baseboard_fab2(sch_1):page44_i139@mstr_sconn.sconn2~
88_h44441003(chips)',
 P_PATH='@baseboard_fab2_lib.baseboard_fab2(sch_1):page44_i139@mstr_sconn.sconn2~
88_h44441003(chips)',
 PATH='I139',
 DRAWING='@BASEBOARD_FAB2_LIB.BASEBOARD_FAB2(SCH_1):PAGE44',
 BOM_SS='NOPOP',
 SEC_TYPE='PIP',
 MATERIAL='SCONN',
 BOM_COST='MEM',
 PHYS_PAGE='44',
 XY='(3450,2400)',
 ROT='0',
 VER='3',
 PACK_TYPE='PIP',
 PART_NUMBER='H44441-003',
 LOCATION='J6T1',
 ROOM='DDR4_CH_A',
 SEC='3',
 CDS_LIB='mstr_sconn',
 CDS_PART_NAME='SCONN288_H44441003_PIP-SCONN,HA',
 PRIM_FILE='./archive_libs/mstr_sconn/sconn288_h44441003/chips/chips.prt';

SECTION_NUMBER 4
 '@BASEBOARD_FAB2_LIB.BASEBOARD_FAB2(SCH_1):PAGE44_I75@MSTR_SCONN.SCONN288_H44441003(CHIPS)':
 C_PATH='@baseboard_fab2_lib.baseboard_fab2(sch_1):page44_i75@mstr_sconn.sconn28~
8_h44441003(chips)',
 P_PATH='@baseboard_fab2_lib.baseboard_fab2(sch_1):page44_i75@mstr_sconn.sconn28~
8_h44441003(chips)',
 PATH='I75',
 DRAWING='@BASEBOARD_FAB2_LIB.BASEBOARD_FAB2(SCH_1):PAGE44',
 BOM_SS='NOPOP',
 SEC_TYPE='PIP',
 MATERIAL='SCONN',
 BOM_COST='MEM',
 PHYS_PAGE='44',
 XY='(1600,1650)',
 ROT='0',
 VER='4',
 PACK_TYPE='PIP',
 PART_NUMBER='H44441-003',
 LOCATION='J6T1',
 ROOM='DDR4_CH_A',
 SEC='4',
 CDS_LIB='mstr_sconn',
 CDS_PART_NAME='SCONN288_H44441003_PIP-SCONN,HA',
 PRIM_FILE='./archive_libs/mstr_sconn/sconn288_h44441003/chips/chips.prt';

PART_NAME
 J6U1 'SCONN288_H44441003_PIP-SCONN,HA':
 ROOM='DDR4_CH_B';

SECTION_NUMBER 1
 '@BASEBOARD_FAB2_LIB.BASEBOARD_FAB2(SCH_1):PAGE46_I14@MSTR_SCONN.SCONN288_H44441003(CHIPS)':
 C_PATH='@baseboard_fab2_lib.baseboard_fab2(sch_1):page46_i14@mstr_sconn.sconn28~
8_h44441003(chips)',
 P_PATH='@baseboard_fab2_lib.baseboard_fab2(sch_1):page46_i14@mstr_sconn.sconn28~
8_h44441003(chips)',
 PATH='I14',
 DRAWING='@BASEBOARD_FAB2_LIB.BASEBOARD_FAB2(SCH_1):PAGE46',
 BOM_SS='NOPOP',
 SEC_TYPE='PIP',
 MATERIAL='SCONN',
 BOM_COST='MEM',
 PHYS_PAGE='46',
 XY='(-825,2600)',
 ROT='0',
 VER='1',
 PACK_TYPE='PIP',
 PART_NUMBER='H44441-003',
 LOCATION='J6U1',
 ROOM='DDR4_CH_B',
 SEC='1',
 CDS_LIB='mstr_sconn',
 CDS_PART_NAME='SCONN288_H44441003_PIP-SCONN,HA',
 PRIM_FILE='./archive_libs/mstr_sconn/sconn288_h44441003/chips/chips.prt';

SECTION_NUMBER 2
 '@BASEBOARD_FAB2_LIB.BASEBOARD_FAB2(SCH_1):PAGE46_I112@MSTR_SCONN.SCONN288_H44441003(CHIPS)':
 C_PATH='@baseboard_fab2_lib.baseboard_fab2(sch_1):page46_i112@mstr_sconn.sconn2~
88_h44441003(chips)',
 P_PATH='@baseboard_fab2_lib.baseboard_fab2(sch_1):page46_i112@mstr_sconn.sconn2~
88_h44441003(chips)',
 PATH='I112',
 DRAWING='@BASEBOARD_FAB2_LIB.BASEBOARD_FAB2(SCH_1):PAGE46',
 BOM_SS='NOPOP',
 SEC_TYPE='PIP',
 MATERIAL='SCONN',
 BOM_COST='MEM',
 PHYS_PAGE='46',
 XY='(1625,3950)',
 ROT='0',
 VER='2',
 PACK_TYPE='PIP',
 PART_NUMBER='H44441-003',
 LOCATION='J6U1',
 ROOM='DDR4_CH_B',
 SEC='2',
 CDS_LIB='mstr_sconn',
 CDS_PART_NAME='SCONN288_H44441003_PIP-SCONN,HA',
 PRIM_FILE='./archive_libs/mstr_sconn/sconn288_h44441003/chips/chips.prt';

SECTION_NUMBER 3
 '@BASEBOARD_FAB2_LIB.BASEBOARD_FAB2(SCH_1):PAGE46_I138@MSTR_SCONN.SCONN288_H44441003(CHIPS)':
 C_PATH='@baseboard_fab2_lib.baseboard_fab2(sch_1):page46_i138@mstr_sconn.sconn2~
88_h44441003(chips)',
 P_PATH='@baseboard_fab2_lib.baseboard_fab2(sch_1):page46_i138@mstr_sconn.sconn2~
88_h44441003(chips)',
 PATH='I138',
 DRAWING='@BASEBOARD_FAB2_LIB.BASEBOARD_FAB2(SCH_1):PAGE46',
 BOM_SS='NOPOP',
 SEC_TYPE='PIP',
 MATERIAL='SCONN',
 BOM_COST='MEM',
 PHYS_PAGE='46',
 XY='(3425,2250)',
 ROT='0',
 VER='3',
 PACK_TYPE='PIP',
 PART_NUMBER='H44441-003',
 LOCATION='J6U1',
 ROOM='DDR4_CH_B',
 SEC='3',
 CDS_LIB='mstr_sconn',
 CDS_PART_NAME='SCONN288_H44441003_PIP-SCONN,HA',
 PRIM_FILE='./archive_libs/mstr_sconn/sconn288_h44441003/chips/chips.prt';

SECTION_NUMBER 4
 '@BASEBOARD_FAB2_LIB.BASEBOARD_FAB2(SCH_1):PAGE46_I67@MSTR_SCONN.SCONN288_H44441003(CHIPS)':
 C_PATH='@baseboard_fab2_lib.baseboard_fab2(sch_1):page46_i67@mstr_sconn.sconn28~
8_h44441003(chips)',
 P_PATH='@baseboard_fab2_lib.baseboard_fab2(sch_1):page46_i67@mstr_sconn.sconn28~
8_h44441003(chips)',
 PATH='I67',
 DRAWING='@BASEBOARD_FAB2_LIB.BASEBOARD_FAB2(SCH_1):PAGE46',
 BOM_SS='NOPOP',
 SEC_TYPE='PIP',
 MATERIAL='SCONN',
 BOM_COST='MEM',
 PHYS_PAGE='46',
 XY='(1675,1650)',
 ROT='0',
 VER='4',
 PACK_TYPE='PIP',
 PART_NUMBER='H44441-003',
 LOCATION='J6U1',
 ROOM='DDR4_CH_B',
 SEC='4',
 CDS_LIB='mstr_sconn',
 CDS_PART_NAME='SCONN288_H44441003_PIP-SCONN,HA',
 PRIM_FILE='./archive_libs/mstr_sconn/sconn288_h44441003/chips/chips.prt';

PART_NAME
 J6U2 'SCONN288_H44441003_PIP-SCONN,HA':
 ROOM='DDR4_CH_C1';

SECTION_NUMBER 1
 '@BASEBOARD_FAB2_LIB.BASEBOARD_FAB2(SCH_1):PAGE48_I111@MSTR_SCONN.SCONN288_H44441003(CHIPS)':
 C_PATH='@baseboard_fab2_lib.baseboard_fab2(sch_1):page48_i111@mstr_sconn.sconn2~
88_h44441003(chips)',
 P_PATH='@baseboard_fab2_lib.baseboard_fab2(sch_1):page48_i111@mstr_sconn.sconn2~
88_h44441003(chips)',
 PATH='I111',
 DRAWING='@BASEBOARD_FAB2_LIB.BASEBOARD_FAB2(SCH_1):PAGE48',
 BOM_SS='NOPOP',
 SEC_TYPE='PIP',
 MATERIAL='SCONN',
 BOM_COST='MEM',
 PHYS_PAGE='48',
 XY='(-2400,3200)',
 ROT='0',
 VER='1',
 PACK_TYPE='PIP',
 PART_NUMBER='H44441-003',
 LOCATION='J6U2',
 ROOM='DDR4_CH_C1',
 SEC='1',
 CDS_LIB='mstr_sconn',
 CDS_PART_NAME='SCONN288_H44441003_PIP-SCONN,HA',
 PRIM_FILE='./archive_libs/mstr_sconn/sconn288_h44441003/chips/chips.prt';

SECTION_NUMBER 2
 '@BASEBOARD_FAB2_LIB.BASEBOARD_FAB2(SCH_1):PAGE48_I61@MSTR_SCONN.SCONN288_H44441003(CHIPS)':
 C_PATH='@baseboard_fab2_lib.baseboard_fab2(sch_1):page48_i61@mstr_sconn.sconn28~
8_h44441003(chips)',
 P_PATH='@baseboard_fab2_lib.baseboard_fab2(sch_1):page48_i61@mstr_sconn.sconn28~
8_h44441003(chips)',
 PATH='I61',
 DRAWING='@BASEBOARD_FAB2_LIB.BASEBOARD_FAB2(SCH_1):PAGE48',
 BOM_SS='NOPOP',
 SEC_TYPE='PIP',
 MATERIAL='SCONN',
 BOM_COST='MEM',
 PHYS_PAGE='48',
 XY='(0,4300)',
 ROT='0',
 VER='2',
 PACK_TYPE='PIP',
 PART_NUMBER='H44441-003',
 LOCATION='J6U2',
 ROOM='DDR4_CH_C1',
 SEC='2',
 CDS_LIB='mstr_sconn',
 CDS_PART_NAME='SCONN288_H44441003_PIP-SCONN,HA',
 PRIM_FILE='./archive_libs/mstr_sconn/sconn288_h44441003/chips/chips.prt';

SECTION_NUMBER 3
 '@BASEBOARD_FAB2_LIB.BASEBOARD_FAB2(SCH_1):PAGE48_I43@MSTR_SCONN.SCONN288_H44441003(CHIPS)':
 C_PATH='@baseboard_fab2_lib.baseboard_fab2(sch_1):page48_i43@mstr_sconn.sconn28~
8_h44441003(chips)',
 P_PATH='@baseboard_fab2_lib.baseboard_fab2(sch_1):page48_i43@mstr_sconn.sconn28~
8_h44441003(chips)',
 PATH='I43',
 DRAWING='@BASEBOARD_FAB2_LIB.BASEBOARD_FAB2(SCH_1):PAGE48',
 BOM_SS='NOPOP',
 SEC_TYPE='PIP',
 MATERIAL='SCONN',
 BOM_COST='MEM',
 PHYS_PAGE='48',
 XY='(1800,2600)',
 ROT='0',
 VER='3',
 PACK_TYPE='PIP',
 PART_NUMBER='H44441-003',
 LOCATION='J6U2',
 ROOM='DDR4_CH_C1',
 SEC='3',
 CDS_LIB='mstr_sconn',
 CDS_PART_NAME='SCONN288_H44441003_PIP-SCONN,HA',
 PRIM_FILE='./archive_libs/mstr_sconn/sconn288_h44441003/chips/chips.prt';

SECTION_NUMBER 4
 '@BASEBOARD_FAB2_LIB.BASEBOARD_FAB2(SCH_1):PAGE48_I171@MSTR_SCONN.SCONN288_H44441003(CHIPS)':
 C_PATH='@baseboard_fab2_lib.baseboard_fab2(sch_1):page48_i171@mstr_sconn.sconn2~
88_h44441003(chips)',
 P_PATH='@baseboard_fab2_lib.baseboard_fab2(sch_1):page48_i171@mstr_sconn.sconn2~
88_h44441003(chips)',
 PATH='I171',
 DRAWING='@BASEBOARD_FAB2_LIB.BASEBOARD_FAB2(SCH_1):PAGE48',
 BOM_SS='NOPOP',
 SEC_TYPE='PIP',
 MATERIAL='SCONN',
 BOM_COST='MEM',
 PHYS_PAGE='48',
 XY='(-100,2000)',
 ROT='0',
 VER='4',
 PACK_TYPE='PIP',
 PART_NUMBER='H44441-003',
 LOCATION='J6U2',
 ROOM='DDR4_CH_C1',
 SEC='4',
 CDS_LIB='mstr_sconn',
 CDS_PART_NAME='SCONN288_H44441003_PIP-SCONN,HA',
 PRIM_FILE='./archive_libs/mstr_sconn/sconn288_h44441003/chips/chips.prt';

PART_NAME
 J7G2 'CONN8_C77962004_PIP-CONN,C7796A':
 ROOM='BMC_DEBUG_HEADER';

SECTION_NUMBER 1
 '@BASEBOARD_FAB2_LIB.BASEBOARD_FAB2(SCH_1):PAGE189_I47@MSTR_CONN.CONN8_C77962004(CHIPS)':
 C_PATH='@baseboard_fab2_lib.baseboard_fab2(sch_1):page189_i47@mstr_conn.conn8_c~
77962004(chips)',
 P_PATH='@baseboard_fab2_lib.baseboard_fab2(sch_1):page189_i47@mstr_conn.conn8_c~
77962004(chips)',
 PATH='I47',
 DRAWING='@BASEBOARD_FAB2_LIB.BASEBOARD_FAB2(SCH_1):PAGE189',
 SEC_TYPE='PIP',
 MATERIAL='CONN',
 BOM_COST='DEBUG',
 PHYS_PAGE='189',
 XY='(4000,3125)',
 ROT='2',
 VER='1',
 PACK_TYPE='PIP',
 PART_NUMBER='C77962-004',
 LOCATION='J7G2',
 ROOM='BMC_DEBUG_HEADER',
 SEC='1',
 CDS_LIB='mstr_conn',
 CDS_PART_NAME='CONN8_C77962004_PIP-CONN,C7796A',
 PRIM_FILE='./archive_libs/mstr_conn/conn8_c77962004/chips/chips.prt';

PART_NAME
 J7G3 'CONN12_C73564003_PIP-CONN,C735A':
 ROOM='SB';

SECTION_NUMBER 1
 '@BASEBOARD_FAB2_LIB.BASEBOARD_FAB2(SCH_1):PAGE136_I174@MSTR_CONN.CONN12_C73564003(CHIPS)':
 C_PATH='@baseboard_fab2_lib.baseboard_fab2(sch_1):page136_i174@mstr_conn.conn12~
_c73564003(chips)',
 P_PATH='@baseboard_fab2_lib.baseboard_fab2(sch_1):page136_i174@mstr_conn.conn12~
_c73564003(chips)',
 PATH='I174',
 DRAWING='@BASEBOARD_FAB2_LIB.BASEBOARD_FAB2(SCH_1):PAGE136',
 SEC_TYPE='PIP',
 MATERIAL='CONN',
 BOM_COST='SB',
 PHYS_PAGE='136',
 XY='(-1650,4250)',
 ROT='0',
 VER='1',
 PACK_TYPE='PIP',
 PART_NUMBER='C73564-003',
 LOCATION='J7G3',
 ROOM='SB',
 SEC='1',
 CDS_LIB='mstr_conn',
 CDS_PART_NAME='CONN12_C73564003_PIP-CONN,C735A',
 PRIM_FILE='./archive_libs/mstr_conn/conn12_c73564003/chips/chips.prt';

PART_NAME
 J8A1 'CONN72_G97614002_A_CP-CONN,G97A':
 ROOM='ST_SATA';

SECTION_NUMBER 1
 '@BASEBOARD_FAB2_LIB.BASEBOARD_FAB2(SCH_1):PAGE173_I163@MSTR_CONN.CONN72_G97614002_A(CHIPS)':
 C_PATH='@baseboard_fab2_lib.baseboard_fab2(sch_1):page173_i163@mstr_conn.conn72~
_g97614002_a(chips)',
 P_PATH='@baseboard_fab2_lib.baseboard_fab2(sch_1):page173_i163@mstr_conn.conn72~
_g97614002_a(chips)',
 PATH='I163',
 DRAWING='@BASEBOARD_FAB2_LIB.BASEBOARD_FAB2(SCH_1):PAGE173',
 SEC_TYPE='CP',
 MATERIAL='CONN',
 BOM_COST='ST_SATA',
 PHYS_PAGE='173',
 XY='(-2025,3100)',
 ROT='0',
 VER='1',
 PACK_TYPE='CP',
 PART_NUMBER='G97614-002',
 LOCATION='J8A1',
 ROOM='ST_SATA',
 SEC='1',
 CDS_LIB='mstr_conn',
 CDS_PART_NAME='CONN72_G97614002_A_CP-CONN,G97A',
 PRIM_FILE='./archive_libs/mstr_conn/conn72_g97614002_a/chips/chips.prt';

PART_NAME
 J8B1 'SCONN24_H46321001_SM-SCONN,H46A':
 ROOM='HFI';

SECTION_NUMBER 1
 '@BASEBOARD_FAB2_LIB.BASEBOARD_FAB2(SCH_1):PAGE91_I1@MSTR_SCONN.SCONN24_H46321001(CHIPS)':
 C_PATH='@baseboard_fab2_lib.baseboard_fab2(sch_1):page91_i1@mstr_sconn.sconn24_~
h46321001(chips)',
 P_PATH='@baseboard_fab2_lib.baseboard_fab2(sch_1):page91_i1@mstr_sconn.sconn24_~
h46321001(chips)',
 PATH='I1',
 DRAWING='@BASEBOARD_FAB2_LIB.BASEBOARD_FAB2(SCH_1):PAGE91',
 MATERIAL='SCONN',
 PHYS_PAGE='91',
 XY='(-125,2850)',
 ROT='0',
 VER='1',
 PACK_TYPE='SM',
 PART_NUMBER='H46321-001',
 LOCATION='J8B1',
 ROOM='HFI',
 CDS_LIB='mstr_sconn',
 CDS_PART_NAME='SCONN24_H46321001_SM-SCONN,H46A',
 PRIM_FILE='./archive_libs/mstr_sconn/sconn24_h46321001/chips/chips.prt';

PART_NAME
 J8C1 'CONN3_C95678002_PIP-CONN,C9567A':
 ROOM='DEBUG';

SECTION_NUMBER 1
 '@BASEBOARD_FAB2_LIB.BASEBOARD_FAB2(SCH_1):PAGE156_I285@MSTR_CONN.CONN3_C95678002(CHIPS)':
 C_PATH='@baseboard_fab2_lib.baseboard_fab2(sch_1):page156_i285@mstr_conn.conn3_~
c95678002(chips)',
 P_PATH='@baseboard_fab2_lib.baseboard_fab2(sch_1):page156_i285@mstr_conn.conn3_~
c95678002(chips)',
 PATH='I285',
 DRAWING='@BASEBOARD_FAB2_LIB.BASEBOARD_FAB2(SCH_1):PAGE156',
 CONFIG='021.60545.0103',
 SEC_TYPE='PIP',
 MATERIAL='CONN',
 BOM_COST='DEBUG',
 PHYS_PAGE='156',
 XY='(-7600,4475)',
 ROT='0',
 VER='1',
 PACK_TYPE='PIP',
 PART_NUMBER='C95678-002',
 LOCATION='J8C1',
 ROOM='DEBUG',
 SEC='1',
 CDS_LIB='mstr_conn',
 CDS_PART_NAME='CONN3_C95678002_PIP-CONN,C9567A',
 PRIM_FILE='./archive_libs/mstr_conn/conn3_c95678002/chips/chips.prt';

PART_NAME
 J8D4 'PIN-CON3-27-GP_CONN-G7-PIN-CONA':;

SECTION_NUMBER 1
 '@BASEBOARD_FAB2_LIB.BASEBOARD_FAB2(SCH_1):PAGE201_I191@W_HDL.PIN-CON3-27-GP(CHIPS)':
 C_PATH='@baseboard_fab2_lib.baseboard_fab2(sch_1):page201_i191@w_hdl.\pin-con3-~
27-gp\(chips)',
 P_PATH='@baseboard_fab2_lib.baseboard_fab2(sch_1):page201_i191@w_hdl.\pin-con3-~
27-gp\(chips)',
 PATH='I191',
 DRAWING='@BASEBOARD_FAB2_LIB.BASEBOARD_FAB2(SCH_1):PAGE201',
 SEC_TYPE='CONN-G7',
 PHYS_PAGE='201',
 XY='(-3225,850)',
 ROT='2',
 VER='1',
 VALUE='PIN-CON3-27-GP',
 PACK_TYPE='CONN-G7',
 PART_NUMBER='021.60545.0103',
 LOCATION='J8D4',
 SEC='1',
 CDS_LIB='w_hdl',
 CDS_PART_NAME='PIN-CON3-27-GP_CONN-G7-PIN-CONA',
 PRIM_FILE='C:/<user>/w_hdl/pin#2dcon3#2d27#2dgp/chips/chips.prt';

PART_NAME
 J8E1 'SCONN11_H67026001_SM-CONN,H670A':
 ROOM='TPM';

SECTION_NUMBER 1
 '@BASEBOARD_FAB2_LIB.BASEBOARD_FAB2(SCH_1):PAGE184_I87@MSTR_SCONN.SCONN11_H67026001(CHIPS)':
 C_PATH='@baseboard_fab2_lib.baseboard_fab2(sch_1):page184_i87@mstr_sconn.sconn1~
1_h67026001(chips)',
 P_PATH='@baseboard_fab2_lib.baseboard_fab2(sch_1):page184_i87@mstr_sconn.sconn1~
1_h67026001(chips)',
 PATH='I87',
 DRAWING='@BASEBOARD_FAB2_LIB.BASEBOARD_FAB2(SCH_1):PAGE184',
 SEC_TYPE='SM',
 MATERIAL='CONN',
 BOM_COST='MIO_SECURITY',
 PHYS_PAGE='184',
 XY='(-3700,-3375)',
 ROT='0',
 VER='1',
 PACK_TYPE='SM',
 PART_NUMBER='H67026-001',
 LOCATION='J8E1',
 ROOM='TPM',
 SEC='1',
 CDS_LIB='mstr_sconn',
 CDS_PART_NAME='SCONN11_H67026001_SM-CONN,H670A',
 PRIM_FILE='./archive_libs/mstr_sconn/sconn11_h67026001/chips/chips.prt';

PART_NAME
 J8E3 'SCONN80_E67482007_SM-CONN,E674A':
 GROUP='NO_KR',
 ROOM='IO_SLOT';

SECTION_NUMBER 1
 '@BASEBOARD_FAB2_LIB.BASEBOARD_FAB2(SCH_1):PAGE187_I119@MSTR_SCONN.SCONN80_E67482007(CHIPS)':
 C_PATH='@baseboard_fab2_lib.baseboard_fab2(sch_1):page187_i119@mstr_sconn.sconn~
80_e67482007(chips)',
 P_PATH='@baseboard_fab2_lib.baseboard_fab2(sch_1):page187_i119@mstr_sconn.sconn~
80_e67482007(chips)',
 PATH='I119',
 DRAWING='@BASEBOARD_FAB2_LIB.BASEBOARD_FAB2(SCH_1):PAGE187',
 SEC_TYPE='SM',
 MATERIAL='CONN',
 PHYS_PAGE='187',
 XY='(-50,3100)',
 ROT='2',
 VER='1',
 PACK_TYPE='SM',
 PART_NUMBER='E67482-007',
 LOCATION='J8E3',
 ROOM='IO_SLOT',
 GROUP='NO_KR',
 SEC='1',
 CDS_LIB='mstr_sconn',
 CDS_PART_NAME='SCONN80_E67482007_SM-CONN,E674A',
 PRIM_FILE='./archive_libs/mstr_sconn/sconn80_e67482007/chips/chips.prt';

PART_NAME
 J8E4 'SCONN64_H87568002_A_SMT-CONN,HA':
 GROUP='KR',
 ROOM='IO_MODULE';

SECTION_NUMBER 1
 '@BASEBOARD_FAB2_LIB.BASEBOARD_FAB2(SCH_1):PAGE188_I27@MSTR_SCONN.SCONN64_H87568002_A(CHIPS)':
 C_PATH='@baseboard_fab2_lib.baseboard_fab2(sch_1):page188_i27@mstr_sconn.sconn6~
4_h87568002_a(chips)',
 P_PATH='@baseboard_fab2_lib.baseboard_fab2(sch_1):page188_i27@mstr_sconn.sconn6~
4_h87568002_a(chips)',
 PATH='I27',
 DRAWING='@BASEBOARD_FAB2_LIB.BASEBOARD_FAB2(SCH_1):PAGE188',
 SEC_TYPE='SMT',
 MATERIAL='CONN',
 PHYS_PAGE='188',
 XY='(150,3025)',
 ROT='0',
 VER='1',
 PACK_TYPE='SMT',
 PART_NUMBER='H87568-002',
 LOCATION='J8E4',
 ROOM='IO_MODULE',
 GROUP='KR',
 SEC='1',
 CDS_LIB='mstr_sconn',
 CDS_PART_NAME='SCONN64_H87568002_A_SMT-CONN,HA',
 PRIM_FILE='./archive_libs/mstr_sconn/sconn64_h87568002_a/chips/chips.prt';

PART_NAME
 J8F1 'SKT-MINI67P-41-GP_SOCKET-G4-SKA':;

SECTION_NUMBER 1
 '@BASEBOARD_FAB2_LIB.BASEBOARD_FAB2(SCH_1):PAGE185_I143@W_HDL.SKT-MINI67P-41-GP(CHIPS)':
 C_PATH='@baseboard_fab2_lib.baseboard_fab2(sch_1):page185_i143@w_hdl.\skt-mini6~
7p-41-gp\(chips)',
 P_PATH='@baseboard_fab2_lib.baseboard_fab2(sch_1):page185_i143@w_hdl.\skt-mini6~
7p-41-gp\(chips)',
 PATH='I143',
 DRAWING='@BASEBOARD_FAB2_LIB.BASEBOARD_FAB2(SCH_1):PAGE185',
 SEC_TYPE='SOCKET-G4',
 PHYS_PAGE='185',
 XY='(-6450,3650)',
 ROT='0',
 VER='1',
 VALUE='SKT-MINI67P-41-GP',
 PACK_TYPE='SOCKET-G4',
 PART_NUMBER='062.10003.0B21',
 LOCATION='J8F1',
 SEC='1',
 CDS_LIB='w_hdl',
 CDS_PART_NAME='SKT-MINI67P-41-GP_SOCKET-G4-SKA',
 PRIM_FILE='C:/<user>/w_hdl/skt#2dmini67p#2d41#2dgp/chips/chips.prt';

PART_NAME
 J8G1 'SCONN200_H68296001_SM-CONN,H68A':
 ROOM='IO_SLOT';

SECTION_NUMBER 1
 '@BASEBOARD_FAB2_LIB.BASEBOARD_FAB2(SCH_1):PAGE108_I258@MSTR_SCONN.SCONN200_H68296001(CHIPS)':
 C_PATH='@baseboard_fab2_lib.baseboard_fab2(sch_1):page108_i258@mstr_sconn.sconn~
200_h68296001(chips)',
 P_PATH='@baseboard_fab2_lib.baseboard_fab2(sch_1):page108_i258@mstr_sconn.sconn~
200_h68296001(chips)',
 PATH='I258',
 DRAWING='@BASEBOARD_FAB2_LIB.BASEBOARD_FAB2(SCH_1):PAGE108',
 SEC_TYPE='SM',
 MATERIAL='CONN',
 PHYS_PAGE='108',
 XY='(500,3075)',
 ROT='0',
 VER='1',
 PACK_TYPE='SM',
 PART_NUMBER='H68296-001',
 LOCATION='J8G1',
 ROOM='IO_SLOT',
 SEC='1',
 CDS_LIB='mstr_sconn',
 CDS_PART_NAME='SCONN200_H68296001_SM-CONN,H68A',
 PRIM_FILE='./archive_libs/mstr_sconn/sconn200_h68296001/chips/chips.prt';

SECTION_NUMBER 2
 '@BASEBOARD_FAB2_LIB.BASEBOARD_FAB2(SCH_1):PAGE109_I78@MSTR_SCONN.SCONN200_H68296001(CHIPS)':
 C_PATH='@baseboard_fab2_lib.baseboard_fab2(sch_1):page109_i78@mstr_sconn.sconn2~
00_h68296001(chips)',
 P_PATH='@baseboard_fab2_lib.baseboard_fab2(sch_1):page109_i78@mstr_sconn.sconn2~
00_h68296001(chips)',
 PATH='I78',
 DRAWING='@BASEBOARD_FAB2_LIB.BASEBOARD_FAB2(SCH_1):PAGE109',
 SEC_TYPE='SM',
 MATERIAL='CONN',
 PHYS_PAGE='109',
 XY='(-1000,3200)',
 ROT='0',
 VER='2',
 PACK_TYPE='SM',
 PART_NUMBER='H68296-001',
 LOCATION='J8G1',
 ROOM='IO_SLOT',
 SEC='2',
 CDS_LIB='mstr_sconn',
 CDS_PART_NAME='SCONN200_H68296001_SM-CONN,H68A',
 PRIM_FILE='./archive_libs/mstr_sconn/sconn200_h68296001/chips/chips.prt';

PART_NAME
 J8G2 'CONN12_C73564003_PIP-CONN,C735A':
 ROOM='SB';

SECTION_NUMBER 1
 '@BASEBOARD_FAB2_LIB.BASEBOARD_FAB2(SCH_1):PAGE135_I124@MSTR_CONN.CONN12_C73564003(CHIPS)':
 C_PATH='@baseboard_fab2_lib.baseboard_fab2(sch_1):page135_i124@mstr_conn.conn12~
_c73564003(chips)',
 P_PATH='@baseboard_fab2_lib.baseboard_fab2(sch_1):page135_i124@mstr_conn.conn12~
_c73564003(chips)',
 PATH='I124',
 DRAWING='@BASEBOARD_FAB2_LIB.BASEBOARD_FAB2(SCH_1):PAGE135',
 SEC_TYPE='PIP',
 MATERIAL='CONN',
 BOM_COST='SB',
 PHYS_PAGE='135',
 XY='(-775,1900)',
 ROT='0',
 VER='1',
 PACK_TYPE='PIP',
 PART_NUMBER='C73564-003',
 LOCATION='J8G2',
 ROOM='SB',
 SEC='1',
 CDS_LIB='mstr_conn',
 CDS_PART_NAME='CONN12_C73564003_PIP-CONN,C735A',
 PRIM_FILE='./archive_libs/mstr_conn/conn12_c73564003/chips/chips.prt';

PART_NAME
 J9A1 'CONN4_D42317002_PIP-CONN,D4231A':
 ROOM='SB';

SECTION_NUMBER 1
 '@BASEBOARD_FAB2_LIB.BASEBOARD_FAB2(SCH_1):PAGE135_I131@MSTR_CONN.CONN4_D42317002(CHIPS)':
 C_PATH='@baseboard_fab2_lib.baseboard_fab2(sch_1):page135_i131@mstr_conn.conn4_~
d42317002(chips)',
 P_PATH='@baseboard_fab2_lib.baseboard_fab2(sch_1):page135_i131@mstr_conn.conn4_~
d42317002(chips)',
 PATH='I131',
 DRAWING='@BASEBOARD_FAB2_LIB.BASEBOARD_FAB2(SCH_1):PAGE135',
 POP='NOPOP',
 MATERIAL='CONN',
 BOM_COST='SB',
 PHYS_PAGE='135',
 XY='(-5075,4600)',
 ROT='2',
 VER='1',
 PACK_TYPE='PIP',
 PART_NUMBER='D42317-002',
 LOCATION='J9A1',
 ROOM='SB',
 CDS_LIB='mstr_conn',
 CDS_PART_NAME='CONN4_D42317002_PIP-CONN,D4231A',
 PRIM_FILE='./archive_libs/mstr_conn/conn4_d42317002/chips/chips.prt';

PART_NAME
 J9A2 'CONN14_H54902001_PIP-CONN,H549A':
 ROOM='BMC_DEBUG_HEADER';

SECTION_NUMBER 1
 '@BASEBOARD_FAB2_LIB.BASEBOARD_FAB2(SCH_1):PAGE155_I171@MSTR_CONN.CONN14_H54902001(CHIPS)':
 C_PATH='@baseboard_fab2_lib.baseboard_fab2(sch_1):page155_i171@mstr_conn.conn14~
_h54902001(chips)',
 P_PATH='@baseboard_fab2_lib.baseboard_fab2(sch_1):page155_i171@mstr_conn.conn14~
_h54902001(chips)',
 PATH='I171',
 DRAWING='@BASEBOARD_FAB2_LIB.BASEBOARD_FAB2(SCH_1):PAGE155',
 MATERIAL='CONN',
 BOM_COST='DEBUG',
 PHYS_PAGE='155',
 XY='(-4450,1500)',
 ROT='0',
 VER='1',
 PACK_TYPE='PIP',
 PART_NUMBER='H54902-001',
 LOCATION='J9A2',
 ROOM='BMC_DEBUG_HEADER',
 CDS_LIB='mstr_conn',
 CDS_PART_NAME='CONN14_H54902001_PIP-CONN,H549A',
 PRIM_FILE='./archive_libs/mstr_conn/conn14_h54902001/chips/chips.prt';

PART_NAME
 J9A3 'SCONN60_C21100002_SMLF-CONN,C2A':
 ROOM='DEBUG';

SECTION_NUMBER 1
 '@BASEBOARD_FAB2_LIB.BASEBOARD_FAB2(SCH_1):PAGE111_I26@MSTR_SCONN.SCONN60_C21100002(CHIPS)':
 C_PATH='@baseboard_fab2_lib.baseboard_fab2(sch_1):page111_i26@mstr_sconn.sconn6~
0_c21100002(chips)',
 P_PATH='@baseboard_fab2_lib.baseboard_fab2(sch_1):page111_i26@mstr_sconn.sconn6~
0_c21100002(chips)',
 PATH='I26',
 DRAWING='@BASEBOARD_FAB2_LIB.BASEBOARD_FAB2(SCH_1):PAGE111',
 SEC_TYPE='SMLF',
 MATERIAL='CONN',
 BOM_COST='DEBUG',
 PHYS_PAGE='111',
 XY='(350,3950)',
 ROT='0',
 VER='1',
 PACK_TYPE='SMLF',
 PART_NUMBER='C21100-002',
 LOCATION='J9A3',
 ALLOW_CONNECT='TRUE',
 ROOM='DEBUG',
 SEC='1',
 CDS_LIB='mstr_sconn',
 CDS_PART_NAME='SCONN60_C21100002_SMLF-CONN,C2A',
 PRIM_FILE='./archive_libs/mstr_sconn/sconn60_c21100002/chips/chips.prt';

PART_NAME
 J9B1 'CONN9_H51826001_PIP2-CONN,H518A':
 ROOM='USB_REAR';

SECTION_NUMBER 1
 '@BASEBOARD_FAB2_LIB.BASEBOARD_FAB2(SCH_1):PAGE176_I69@MSTR_CONN.CONN9_H51826001(CHIPS)':
 C_PATH='@baseboard_fab2_lib.baseboard_fab2(sch_1):page176_i69@mstr_conn.conn9_h~
51826001(chips)',
 P_PATH='@baseboard_fab2_lib.baseboard_fab2(sch_1):page176_i69@mstr_conn.conn9_h~
51826001(chips)',
 PATH='I69',
 DRAWING='@BASEBOARD_FAB2_LIB.BASEBOARD_FAB2(SCH_1):PAGE176',
 MATERIAL='CONN',
 PHYS_PAGE='176',
 XY='(-1300,4550)',
 ROT='0',
 VER='2',
 PACK_TYPE='PIP2',
 PART_NUMBER='H51826-001',
 LOCATION='J9B1',
 ROOM='USB_REAR',
 CDS_LIB='mstr_conn',
 CDS_PART_NAME='CONN9_H51826001_PIP2-CONN,H518A',
 PRIM_FILE='./archive_libs/mstr_conn/conn9_h51826001/chips/chips.prt';

PART_NAME
 J9B2 'CONN3_C95678002_PIP-CONN,C9567A':
 ROOM='DEBUG';

SECTION_NUMBER 1
 '@BASEBOARD_FAB2_LIB.BASEBOARD_FAB2(SCH_1):PAGE156_I281@MSTR_CONN.CONN3_C95678002(CHIPS)':
 C_PATH='@baseboard_fab2_lib.baseboard_fab2(sch_1):page156_i281@mstr_conn.conn3_~
c95678002(chips)',
 P_PATH='@baseboard_fab2_lib.baseboard_fab2(sch_1):page156_i281@mstr_conn.conn3_~
c95678002(chips)',
 PATH='I281',
 DRAWING='@BASEBOARD_FAB2_LIB.BASEBOARD_FAB2(SCH_1):PAGE156',
 CONFIG='021.60545.0103',
 SEC_TYPE='PIP',
 MATERIAL='CONN',
 BOM_COST='DEBUG',
 PHYS_PAGE='156',
 XY='(-7575,3700)',
 ROT='0',
 VER='1',
 PACK_TYPE='PIP',
 PART_NUMBER='C95678-002',
 LOCATION='J9B2',
 ROOM='DEBUG',
 SEC='1',
 CDS_LIB='mstr_conn',
 CDS_PART_NAME='CONN3_C95678002_PIP-CONN,C9567A',
 PRIM_FILE='./archive_libs/mstr_conn/conn3_c95678002/chips/chips.prt';

PART_NAME
 J9B3 'SCONN120_A28699018_SM-SCONN,A2A':
 GROUP='NO_KR',
 ROOM='IO_SLOT';

SECTION_NUMBER 1
 '@BASEBOARD_FAB2_LIB.BASEBOARD_FAB2(SCH_1):PAGE186_I336@MSTR_SCONN.SCONN120_A28699018(CHIPS)':
 C_PATH='@baseboard_fab2_lib.baseboard_fab2(sch_1):page186_i336@mstr_sconn.sconn~
120_a28699018(chips)',
 P_PATH='@baseboard_fab2_lib.baseboard_fab2(sch_1):page186_i336@mstr_sconn.sconn~
120_a28699018(chips)',
 PATH='I336',
 DRAWING='@BASEBOARD_FAB2_LIB.BASEBOARD_FAB2(SCH_1):PAGE186',
 SEC_TYPE='SM',
 MATERIAL='SCONN',
 PHYS_PAGE='186',
 XY='(8250,2350)',
 ROT='0',
 VER='1',
 PACK_TYPE='SM',
 PART_NUMBER='A28699-018',
 LOCATION='J9B3',
 ROOM='IO_SLOT',
 GROUP='NO_KR',
 SEC='1',
 CDS_LIB='mstr_sconn',
 CDS_PART_NAME='SCONN120_A28699018_SM-SCONN,A2A',
 PRIM_FILE='./archive_libs/mstr_sconn/sconn120_a28699018/chips/chips.prt';

PART_NAME
 J9B4 'SCONN10_C12536004_SMLF-CONN,C1A':
 GROUP='MCP',
 ROOM='DEBUG';

SECTION_NUMBER 1
 '@BASEBOARD_FAB2_LIB.BASEBOARD_FAB2(SCH_1):PAGE113_I175@MSTR_SCONN.SCONN10_C12536004(CHIPS)':
 C_PATH='@baseboard_fab2_lib.baseboard_fab2(sch_1):page113_i175@mstr_sconn.sconn~
10_c12536004(chips)',
 P_PATH='@baseboard_fab2_lib.baseboard_fab2(sch_1):page113_i175@mstr_sconn.sconn~
10_c12536004(chips)',
 PATH='I175',
 DRAWING='@BASEBOARD_FAB2_LIB.BASEBOARD_FAB2(SCH_1):PAGE113',
 SEC_TYPE='SMLF',
 MATERIAL='CONN',
 PHYS_PAGE='113',
 XY='(-1375,4375)',
 ROT='0',
 VER='1',
 PACK_TYPE='SMLF',
 PART_NUMBER='C12536-004',
 LOCATION='J9B4',
 ROOM='DEBUG',
 GROUP='MCP',
 SEC='1',
 CDS_LIB='mstr_sconn',
 CDS_PART_NAME='SCONN10_C12536004_SMLF-CONN,C1A',
 PRIM_FILE='./archive_libs/mstr_sconn/sconn10_c12536004/chips/chips.prt';

PART_NAME
 J9G1 'CONN12_C73564003_PIP-CONN,C735A':
 ROOM='SB';

SECTION_NUMBER 1
 '@BASEBOARD_FAB2_LIB.BASEBOARD_FAB2(SCH_1):PAGE137_I128@MSTR_CONN.CONN12_C73564003(CHIPS)':
 C_PATH='@baseboard_fab2_lib.baseboard_fab2(sch_1):page137_i128@mstr_conn.conn12~
_c73564003(chips)',
 P_PATH='@baseboard_fab2_lib.baseboard_fab2(sch_1):page137_i128@mstr_conn.conn12~
_c73564003(chips)',
 PATH='I128',
 DRAWING='@BASEBOARD_FAB2_LIB.BASEBOARD_FAB2(SCH_1):PAGE137',
 SEC_TYPE='PIP',
 MATERIAL='CONN',
 BOM_COST='SB',
 PHYS_PAGE='137',
 XY='(-2175,3675)',
 ROT='0',
 VER='1',
 PACK_TYPE='PIP',
 PART_NUMBER='C73564-003',
 LOCATION='J9G1',
 ROOM='SB',
 SEC='1',
 CDS_LIB='mstr_conn',
 CDS_PART_NAME='CONN12_C73564003_PIP-CONN,C735A',
 PRIM_FILE='./archive_libs/mstr_conn/conn12_c73564003/chips/chips.prt';

PART_NAME
 J9L1 'SCONN288_H44441003_PIP-SCONN,HA':
 ROOM='DDR4_CH_M';

SECTION_NUMBER 1
 '@BASEBOARD_FAB2_LIB.BASEBOARD_FAB2(SCH_1):PAGE88_I111@MSTR_SCONN.SCONN288_H44441003(CHIPS)':
 C_PATH='@baseboard_fab2_lib.baseboard_fab2(sch_1):page88_i111@mstr_sconn.sconn2~
88_h44441003(chips)',
 P_PATH='@baseboard_fab2_lib.baseboard_fab2(sch_1):page88_i111@mstr_sconn.sconn2~
88_h44441003(chips)',
 PATH='I111',
 DRAWING='@BASEBOARD_FAB2_LIB.BASEBOARD_FAB2(SCH_1):PAGE88',
 BOM_SS='NOPOP',
 SEC_TYPE='PIP',
 MATERIAL='SCONN',
 BOM_COST='DDR4_CH_M',
 PHYS_PAGE='88',
 XY='(-2450,3100)',
 ROT='0',
 VER='1',
 PACK_TYPE='PIP',
 PART_NUMBER='H44441-003',
 LOCATION='J9L1',
 ROOM='DDR4_CH_M',
 SEC='1',
 CDS_LIB='mstr_sconn',
 CDS_PART_NAME='SCONN288_H44441003_PIP-SCONN,HA',
 PRIM_FILE='./archive_libs/mstr_sconn/sconn288_h44441003/chips/chips.prt';

SECTION_NUMBER 2
 '@BASEBOARD_FAB2_LIB.BASEBOARD_FAB2(SCH_1):PAGE88_I87@MSTR_SCONN.SCONN288_H44441003(CHIPS)':
 C_PATH='@baseboard_fab2_lib.baseboard_fab2(sch_1):page88_i87@mstr_sconn.sconn28~
8_h44441003(chips)',
 P_PATH='@baseboard_fab2_lib.baseboard_fab2(sch_1):page88_i87@mstr_sconn.sconn28~
8_h44441003(chips)',
 PATH='I87',
 DRAWING='@BASEBOARD_FAB2_LIB.BASEBOARD_FAB2(SCH_1):PAGE88',
 BOM_SS='NOPOP',
 SEC_TYPE='PIP',
 MATERIAL='SCONN',
 BOM_COST='DDR4_CH_M',
 PHYS_PAGE='88',
 XY='(0,4300)',
 ROT='0',
 VER='2',
 PACK_TYPE='PIP',
 PART_NUMBER='H44441-003',
 LOCATION='J9L1',
 ROOM='DDR4_CH_M',
 SEC='2',
 CDS_LIB='mstr_sconn',
 CDS_PART_NAME='SCONN288_H44441003_PIP-SCONN,HA',
 PRIM_FILE='./archive_libs/mstr_sconn/sconn288_h44441003/chips/chips.prt';

SECTION_NUMBER 3
 '@BASEBOARD_FAB2_LIB.BASEBOARD_FAB2(SCH_1):PAGE88_I25@MSTR_SCONN.SCONN288_H44441003(CHIPS)':
 C_PATH='@baseboard_fab2_lib.baseboard_fab2(sch_1):page88_i25@mstr_sconn.sconn28~
8_h44441003(chips)',
 P_PATH='@baseboard_fab2_lib.baseboard_fab2(sch_1):page88_i25@mstr_sconn.sconn28~
8_h44441003(chips)',
 PATH='I25',
 DRAWING='@BASEBOARD_FAB2_LIB.BASEBOARD_FAB2(SCH_1):PAGE88',
 BOM_SS='NOPOP',
 SEC_TYPE='PIP',
 MATERIAL='SCONN',
 BOM_COST='DDR4_CH_M',
 PHYS_PAGE='88',
 XY='(1800,2400)',
 ROT='0',
 VER='3',
 PACK_TYPE='PIP',
 PART_NUMBER='H44441-003',
 LOCATION='J9L1',
 ROOM='DDR4_CH_M',
 SEC='3',
 CDS_LIB='mstr_sconn',
 CDS_PART_NAME='SCONN288_H44441003_PIP-SCONN,HA',
 PRIM_FILE='./archive_libs/mstr_sconn/sconn288_h44441003/chips/chips.prt';

SECTION_NUMBER 4
 '@BASEBOARD_FAB2_LIB.BASEBOARD_FAB2(SCH_1):PAGE88_I168@MSTR_SCONN.SCONN288_H44441003(CHIPS)':
 C_PATH='@baseboard_fab2_lib.baseboard_fab2(sch_1):page88_i168@mstr_sconn.sconn2~
88_h44441003(chips)',
 P_PATH='@baseboard_fab2_lib.baseboard_fab2(sch_1):page88_i168@mstr_sconn.sconn2~
88_h44441003(chips)',
 PATH='I168',
 DRAWING='@BASEBOARD_FAB2_LIB.BASEBOARD_FAB2(SCH_1):PAGE88',
 BOM_SS='NOPOP',
 SEC_TYPE='PIP',
 MATERIAL='SCONN',
 BOM_COST='MEM',
 PHYS_PAGE='88',
 XY='(-300,2000)',
 ROT='0',
 VER='4',
 PACK_TYPE='PIP',
 PART_NUMBER='H44441-003',
 LOCATION='J9L1',
 ROOM='DDR4_CH_M',
 SEC='4',
 CDS_LIB='mstr_sconn',
 CDS_PART_NAME='SCONN288_H44441003_PIP-SCONN,HA',
 PRIM_FILE='./archive_libs/mstr_sconn/sconn288_h44441003/chips/chips.prt';

PART_NAME
 J9L2 'SCONN288_H44441003_PIP-SCONN,HA':
 ROOM='DDR4_CH_L';

SECTION_NUMBER 1
 '@BASEBOARD_FAB2_LIB.BASEBOARD_FAB2(SCH_1):PAGE86_I12@MSTR_SCONN.SCONN288_H44441003(CHIPS)':
 C_PATH='@baseboard_fab2_lib.baseboard_fab2(sch_1):page86_i12@mstr_sconn.sconn28~
8_h44441003(chips)',
 P_PATH='@baseboard_fab2_lib.baseboard_fab2(sch_1):page86_i12@mstr_sconn.sconn28~
8_h44441003(chips)',
 PATH='I12',
 DRAWING='@BASEBOARD_FAB2_LIB.BASEBOARD_FAB2(SCH_1):PAGE86',
 BOM_SS='NOPOP',
 SEC_TYPE='PIP',
 MATERIAL='SCONN',
 BOM_COST='MEM',
 PHYS_PAGE='86',
 XY='(-875,2925)',
 ROT='0',
 VER='1',
 PACK_TYPE='PIP',
 PART_NUMBER='H44441-003',
 LOCATION='J9L2',
 ROOM='DDR4_CH_L',
 SEC='1',
 CDS_LIB='mstr_sconn',
 CDS_PART_NAME='SCONN288_H44441003_PIP-SCONN,HA',
 PRIM_FILE='./archive_libs/mstr_sconn/sconn288_h44441003/chips/chips.prt';

SECTION_NUMBER 2
 '@BASEBOARD_FAB2_LIB.BASEBOARD_FAB2(SCH_1):PAGE86_I100@MSTR_SCONN.SCONN288_H44441003(CHIPS)':
 C_PATH='@baseboard_fab2_lib.baseboard_fab2(sch_1):page86_i100@mstr_sconn.sconn2~
88_h44441003(chips)',
 P_PATH='@baseboard_fab2_lib.baseboard_fab2(sch_1):page86_i100@mstr_sconn.sconn2~
88_h44441003(chips)',
 PATH='I100',
 DRAWING='@BASEBOARD_FAB2_LIB.BASEBOARD_FAB2(SCH_1):PAGE86',
 BOM_SS='NOPOP',
 SEC_TYPE='PIP',
 MATERIAL='SCONN',
 BOM_COST='MEM',
 PHYS_PAGE='86',
 XY='(1625,3975)',
 ROT='0',
 VER='2',
 PACK_TYPE='PIP',
 PART_NUMBER='H44441-003',
 LOCATION='J9L2',
 ROOM='DDR4_CH_L',
 SEC='2',
 CDS_LIB='mstr_sconn',
 CDS_PART_NAME='SCONN288_H44441003_PIP-SCONN,HA',
 PRIM_FILE='./archive_libs/mstr_sconn/sconn288_h44441003/chips/chips.prt';

SECTION_NUMBER 3
 '@BASEBOARD_FAB2_LIB.BASEBOARD_FAB2(SCH_1):PAGE86_I138@MSTR_SCONN.SCONN288_H44441003(CHIPS)':
 C_PATH='@baseboard_fab2_lib.baseboard_fab2(sch_1):page86_i138@mstr_sconn.sconn2~
88_h44441003(chips)',
 P_PATH='@baseboard_fab2_lib.baseboard_fab2(sch_1):page86_i138@mstr_sconn.sconn2~
88_h44441003(chips)',
 PATH='I138',
 DRAWING='@BASEBOARD_FAB2_LIB.BASEBOARD_FAB2(SCH_1):PAGE86',
 BOM_SS='NOPOP',
 SEC_TYPE='PIP',
 MATERIAL='SCONN',
 BOM_COST='MEM',
 PHYS_PAGE='86',
 XY='(3425,2075)',
 ROT='0',
 VER='3',
 PACK_TYPE='PIP',
 PART_NUMBER='H44441-003',
 LOCATION='J9L2',
 ROOM='DDR4_CH_L',
 SEC='3',
 CDS_LIB='mstr_sconn',
 CDS_PART_NAME='SCONN288_H44441003_PIP-SCONN,HA',
 PRIM_FILE='./archive_libs/mstr_sconn/sconn288_h44441003/chips/chips.prt';

SECTION_NUMBER 4
 '@BASEBOARD_FAB2_LIB.BASEBOARD_FAB2(SCH_1):PAGE86_I55@MSTR_SCONN.SCONN288_H44441003(CHIPS)':
 C_PATH='@baseboard_fab2_lib.baseboard_fab2(sch_1):page86_i55@mstr_sconn.sconn28~
8_h44441003(chips)',
 P_PATH='@baseboard_fab2_lib.baseboard_fab2(sch_1):page86_i55@mstr_sconn.sconn28~
8_h44441003(chips)',
 PATH='I55',
 DRAWING='@BASEBOARD_FAB2_LIB.BASEBOARD_FAB2(SCH_1):PAGE86',
 BOM_SS='NOPOP',
 SEC_TYPE='PIP',
 MATERIAL='SCONN',
 BOM_COST='MEM',
 PHYS_PAGE='86',
 XY='(1375,1725)',
 ROT='0',
 VER='4',
 PACK_TYPE='PIP',
 PART_NUMBER='H44441-003',
 LOCATION='J9L2',
 ROOM='DDR4_CH_L',
 SEC='4',
 CDS_LIB='mstr_sconn',
 CDS_PART_NAME='SCONN288_H44441003_PIP-SCONN,HA',
 PRIM_FILE='./archive_libs/mstr_sconn/sconn288_h44441003/chips/chips.prt';

PART_NAME
 J9M1 'SCONN288_H44441003_PIP-SCONN,HA':
 ROOM='DDR4_CH_K';

SECTION_NUMBER 1
 '@BASEBOARD_FAB2_LIB.BASEBOARD_FAB2(SCH_1):PAGE84_I14@MSTR_SCONN.SCONN288_H44441003(CHIPS)':
 C_PATH='@baseboard_fab2_lib.baseboard_fab2(sch_1):page84_i14@mstr_sconn.sconn28~
8_h44441003(chips)',
 P_PATH='@baseboard_fab2_lib.baseboard_fab2(sch_1):page84_i14@mstr_sconn.sconn28~
8_h44441003(chips)',
 PATH='I14',
 DRAWING='@BASEBOARD_FAB2_LIB.BASEBOARD_FAB2(SCH_1):PAGE84',
 BOM_SS='NOPOP',
 SEC_TYPE='PIP',
 MATERIAL='SCONN',
 BOM_COST='MEM',
 PHYS_PAGE='84',
 XY='(-850,2825)',
 ROT='0',
 VER='1',
 PACK_TYPE='PIP',
 PART_NUMBER='H44441-003',
 LOCATION='J9M1',
 ROOM='DDR4_CH_K',
 SEC='1',
 CDS_LIB='mstr_sconn',
 CDS_PART_NAME='SCONN288_H44441003_PIP-SCONN,HA',
 PRIM_FILE='./archive_libs/mstr_sconn/sconn288_h44441003/chips/chips.prt';

SECTION_NUMBER 2
 '@BASEBOARD_FAB2_LIB.BASEBOARD_FAB2(SCH_1):PAGE84_I102@MSTR_SCONN.SCONN288_H44441003(CHIPS)':
 C_PATH='@baseboard_fab2_lib.baseboard_fab2(sch_1):page84_i102@mstr_sconn.sconn2~
88_h44441003(chips)',
 P_PATH='@baseboard_fab2_lib.baseboard_fab2(sch_1):page84_i102@mstr_sconn.sconn2~
88_h44441003(chips)',
 PATH='I102',
 DRAWING='@BASEBOARD_FAB2_LIB.BASEBOARD_FAB2(SCH_1):PAGE84',
 BOM_SS='NOPOP',
 SEC_TYPE='PIP',
 MATERIAL='SCONN',
 BOM_COST='MEM',
 PHYS_PAGE='84',
 XY='(1600,3975)',
 ROT='0',
 VER='2',
 PACK_TYPE='PIP',
 PART_NUMBER='H44441-003',
 LOCATION='J9M1',
 ROOM='DDR4_CH_K',
 SEC='2',
 CDS_LIB='mstr_sconn',
 CDS_PART_NAME='SCONN288_H44441003_PIP-SCONN,HA',
 PRIM_FILE='./archive_libs/mstr_sconn/sconn288_h44441003/chips/chips.prt';

SECTION_NUMBER 3
 '@BASEBOARD_FAB2_LIB.BASEBOARD_FAB2(SCH_1):PAGE84_I138@MSTR_SCONN.SCONN288_H44441003(CHIPS)':
 C_PATH='@baseboard_fab2_lib.baseboard_fab2(sch_1):page84_i138@mstr_sconn.sconn2~
88_h44441003(chips)',
 P_PATH='@baseboard_fab2_lib.baseboard_fab2(sch_1):page84_i138@mstr_sconn.sconn2~
88_h44441003(chips)',
 PATH='I138',
 DRAWING='@BASEBOARD_FAB2_LIB.BASEBOARD_FAB2(SCH_1):PAGE84',
 BOM_SS='NOPOP',
 SEC_TYPE='PIP',
 MATERIAL='SCONN',
 BOM_COST='MEM',
 PHYS_PAGE='84',
 XY='(3400,2025)',
 ROT='0',
 VER='3',
 PACK_TYPE='PIP',
 PART_NUMBER='H44441-003',
 LOCATION='J9M1',
 ROOM='DDR4_CH_K',
 SEC='3',
 CDS_LIB='mstr_sconn',
 CDS_PART_NAME='SCONN288_H44441003_PIP-SCONN,HA',
 PRIM_FILE='./archive_libs/mstr_sconn/sconn288_h44441003/chips/chips.prt';

SECTION_NUMBER 4
 '@BASEBOARD_FAB2_LIB.BASEBOARD_FAB2(SCH_1):PAGE84_I57@MSTR_SCONN.SCONN288_H44441003(CHIPS)':
 C_PATH='@baseboard_fab2_lib.baseboard_fab2(sch_1):page84_i57@mstr_sconn.sconn28~
8_h44441003(chips)',
 P_PATH='@baseboard_fab2_lib.baseboard_fab2(sch_1):page84_i57@mstr_sconn.sconn28~
8_h44441003(chips)',
 PATH='I57',
 DRAWING='@BASEBOARD_FAB2_LIB.BASEBOARD_FAB2(SCH_1):PAGE84',
 BOM_SS='NOPOP',
 SEC_TYPE='PIP',
 MATERIAL='SCONN',
 BOM_COST='MEM',
 PHYS_PAGE='84',
 XY='(1450,1725)',
 ROT='0',
 VER='4',
 PACK_TYPE='PIP',
 PART_NUMBER='H44441-003',
 LOCATION='J9M1',
 ROOM='DDR4_CH_K',
 SEC='4',
 CDS_LIB='mstr_sconn',
 CDS_PART_NAME='SCONN288_H44441003_PIP-SCONN,HA',
 PRIM_FILE='./archive_libs/mstr_sconn/sconn288_h44441003/chips/chips.prt';

PART_NAME
 J9T1 'SCONN288_H44441003_PIP-SCONN,HA':
 ROOM='DDR4_GH_G';

SECTION_NUMBER 1
 '@BASEBOARD_FAB2_LIB.BASEBOARD_FAB2(SCH_1):PAGE78_I13@MSTR_SCONN.SCONN288_H44441003(CHIPS)':
 C_PATH='@baseboard_fab2_lib.baseboard_fab2(sch_1):page78_i13@mstr_sconn.sconn28~
8_h44441003(chips)',
 P_PATH='@baseboard_fab2_lib.baseboard_fab2(sch_1):page78_i13@mstr_sconn.sconn28~
8_h44441003(chips)',
 PATH='I13',
 DRAWING='@BASEBOARD_FAB2_LIB.BASEBOARD_FAB2(SCH_1):PAGE78',
 BOM_SS='NOPOP',
 SEC_TYPE='PIP',
 MATERIAL='SCONN',
 BOM_COST='MEM',
 PHYS_PAGE='78',
 XY='(-625,2575)',
 ROT='0',
 VER='1',
 PACK_TYPE='PIP',
 PART_NUMBER='H44441-003',
 LOCATION='J9T1',
 ROOM='DDR4_GH_G',
 SEC='1',
 CDS_LIB='mstr_sconn',
 CDS_PART_NAME='SCONN288_H44441003_PIP-SCONN,HA',
 PRIM_FILE='./archive_libs/mstr_sconn/sconn288_h44441003/chips/chips.prt';

SECTION_NUMBER 2
 '@BASEBOARD_FAB2_LIB.BASEBOARD_FAB2(SCH_1):PAGE78_I120@MSTR_SCONN.SCONN288_H44441003(CHIPS)':
 C_PATH='@baseboard_fab2_lib.baseboard_fab2(sch_1):page78_i120@mstr_sconn.sconn2~
88_h44441003(chips)',
 P_PATH='@baseboard_fab2_lib.baseboard_fab2(sch_1):page78_i120@mstr_sconn.sconn2~
88_h44441003(chips)',
 PATH='I120',
 DRAWING='@BASEBOARD_FAB2_LIB.BASEBOARD_FAB2(SCH_1):PAGE78',
 BOM_SS='NOPOP',
 SEC_TYPE='PIP',
 MATERIAL='SCONN',
 BOM_COST='MEM',
 PHYS_PAGE='78',
 XY='(1750,4000)',
 ROT='0',
 VER='2',
 PACK_TYPE='PIP',
 PART_NUMBER='H44441-003',
 LOCATION='J9T1',
 ROOM='DDR4_GH_G',
 SEC='2',
 CDS_LIB='mstr_sconn',
 CDS_PART_NAME='SCONN288_H44441003_PIP-SCONN,HA',
 PRIM_FILE='./archive_libs/mstr_sconn/sconn288_h44441003/chips/chips.prt';

SECTION_NUMBER 3
 '@BASEBOARD_FAB2_LIB.BASEBOARD_FAB2(SCH_1):PAGE78_I144@MSTR_SCONN.SCONN288_H44441003(CHIPS)':
 C_PATH='@baseboard_fab2_lib.baseboard_fab2(sch_1):page78_i144@mstr_sconn.sconn2~
88_h44441003(chips)',
 P_PATH='@baseboard_fab2_lib.baseboard_fab2(sch_1):page78_i144@mstr_sconn.sconn2~
88_h44441003(chips)',
 PATH='I144',
 DRAWING='@BASEBOARD_FAB2_LIB.BASEBOARD_FAB2(SCH_1):PAGE78',
 BOM_SS='NOPOP',
 SEC_TYPE='PIP',
 MATERIAL='SCONN',
 BOM_COST='MEM',
 PHYS_PAGE='78',
 XY='(3550,2000)',
 ROT='0',
 VER='3',
 PACK_TYPE='PIP',
 PART_NUMBER='H44441-003',
 LOCATION='J9T1',
 ROOM='DDR4_GH_G',
 SEC='3',
 CDS_LIB='mstr_sconn',
 CDS_PART_NAME='SCONN288_H44441003_PIP-SCONN,HA',
 PRIM_FILE='./archive_libs/mstr_sconn/sconn288_h44441003/chips/chips.prt';

SECTION_NUMBER 4
 '@BASEBOARD_FAB2_LIB.BASEBOARD_FAB2(SCH_1):PAGE78_I75@MSTR_SCONN.SCONN288_H44441003(CHIPS)':
 C_PATH='@baseboard_fab2_lib.baseboard_fab2(sch_1):page78_i75@mstr_sconn.sconn28~
8_h44441003(chips)',
 P_PATH='@baseboard_fab2_lib.baseboard_fab2(sch_1):page78_i75@mstr_sconn.sconn28~
8_h44441003(chips)',
 PATH='I75',
 DRAWING='@BASEBOARD_FAB2_LIB.BASEBOARD_FAB2(SCH_1):PAGE78',
 BOM_SS='NOPOP',
 SEC_TYPE='PIP',
 MATERIAL='SCONN',
 BOM_COST='MEM',
 PHYS_PAGE='78',
 XY='(1450,1750)',
 ROT='0',
 VER='4',
 PACK_TYPE='PIP',
 PART_NUMBER='H44441-003',
 LOCATION='J9T1',
 ROOM='DDR4_GH_G',
 SEC='4',
 CDS_LIB='mstr_sconn',
 CDS_PART_NAME='SCONN288_H44441003_PIP-SCONN,HA',
 PRIM_FILE='./archive_libs/mstr_sconn/sconn288_h44441003/chips/chips.prt';

PART_NAME
 J9U1 'SCONN288_H44441003_PIP-SCONN,HA':
 ROOM='DDR4_GH_H';

SECTION_NUMBER 1
 '@BASEBOARD_FAB2_LIB.BASEBOARD_FAB2(SCH_1):PAGE80_I24@MSTR_SCONN.SCONN288_H44441003(CHIPS)':
 C_PATH='@baseboard_fab2_lib.baseboard_fab2(sch_1):page80_i24@mstr_sconn.sconn28~
8_h44441003(chips)',
 P_PATH='@baseboard_fab2_lib.baseboard_fab2(sch_1):page80_i24@mstr_sconn.sconn28~
8_h44441003(chips)',
 PATH='I24',
 DRAWING='@BASEBOARD_FAB2_LIB.BASEBOARD_FAB2(SCH_1):PAGE80',
 BOM_SS='NOPOP',
 SEC_TYPE='PIP',
 MATERIAL='SCONN',
 BOM_COST='MEM',
 PHYS_PAGE='80',
 XY='(-5225,2700)',
 ROT='0',
 VER='1',
 PACK_TYPE='PIP',
 PART_NUMBER='H44441-003',
 LOCATION='J9U1',
 ROOM='DDR4_GH_H',
 SEC='1',
 CDS_LIB='mstr_sconn',
 CDS_PART_NAME='SCONN288_H44441003_PIP-SCONN,HA',
 PRIM_FILE='./archive_libs/mstr_sconn/sconn288_h44441003/chips/chips.prt';

SECTION_NUMBER 2
 '@BASEBOARD_FAB2_LIB.BASEBOARD_FAB2(SCH_1):PAGE80_I101@MSTR_SCONN.SCONN288_H44441003(CHIPS)':
 C_PATH='@baseboard_fab2_lib.baseboard_fab2(sch_1):page80_i101@mstr_sconn.sconn2~
88_h44441003(chips)',
 P_PATH='@baseboard_fab2_lib.baseboard_fab2(sch_1):page80_i101@mstr_sconn.sconn2~
88_h44441003(chips)',
 PATH='I101',
 DRAWING='@BASEBOARD_FAB2_LIB.BASEBOARD_FAB2(SCH_1):PAGE80',
 BOM_SS='NOPOP',
 SEC_TYPE='PIP',
 MATERIAL='SCONN',
 BOM_COST='MEM',
 PHYS_PAGE='80',
 XY='(-2675,3750)',
 ROT='0',
 VER='2',
 PACK_TYPE='PIP',
 PART_NUMBER='H44441-003',
 LOCATION='J9U1',
 ROOM='DDR4_GH_H',
 SEC='2',
 CDS_LIB='mstr_sconn',
 CDS_PART_NAME='SCONN288_H44441003_PIP-SCONN,HA',
 PRIM_FILE='./archive_libs/mstr_sconn/sconn288_h44441003/chips/chips.prt';

SECTION_NUMBER 3
 '@BASEBOARD_FAB2_LIB.BASEBOARD_FAB2(SCH_1):PAGE80_I138@MSTR_SCONN.SCONN288_H44441003(CHIPS)':
 C_PATH='@baseboard_fab2_lib.baseboard_fab2(sch_1):page80_i138@mstr_sconn.sconn2~
88_h44441003(chips)',
 P_PATH='@baseboard_fab2_lib.baseboard_fab2(sch_1):page80_i138@mstr_sconn.sconn2~
88_h44441003(chips)',
 PATH='I138',
 DRAWING='@BASEBOARD_FAB2_LIB.BASEBOARD_FAB2(SCH_1):PAGE80',
 BOM_SS='NOPOP',
 SEC_TYPE='PIP',
 MATERIAL='SCONN',
 BOM_COST='MEM',
 PHYS_PAGE='80',
 XY='(-875,1850)',
 ROT='0',
 VER='3',
 PACK_TYPE='PIP',
 PART_NUMBER='H44441-003',
 LOCATION='J9U1',
 ROOM='DDR4_GH_H',
 SEC='3',
 CDS_LIB='mstr_sconn',
 CDS_PART_NAME='SCONN288_H44441003_PIP-SCONN,HA',
 PRIM_FILE='./archive_libs/mstr_sconn/sconn288_h44441003/chips/chips.prt';

SECTION_NUMBER 4
 '@BASEBOARD_FAB2_LIB.BASEBOARD_FAB2(SCH_1):PAGE80_I56@MSTR_SCONN.SCONN288_H44441003(CHIPS)':
 C_PATH='@baseboard_fab2_lib.baseboard_fab2(sch_1):page80_i56@mstr_sconn.sconn28~
8_h44441003(chips)',
 P_PATH='@baseboard_fab2_lib.baseboard_fab2(sch_1):page80_i56@mstr_sconn.sconn28~
8_h44441003(chips)',
 PATH='I56',
 DRAWING='@BASEBOARD_FAB2_LIB.BASEBOARD_FAB2(SCH_1):PAGE80',
 BOM_SS='NOPOP',
 SEC_TYPE='PIP',
 MATERIAL='SCONN',
 BOM_COST='MEM',
 PHYS_PAGE='80',
 XY='(-3075,1450)',
 ROT='0',
 VER='4',
 PACK_TYPE='PIP',
 PART_NUMBER='H44441-003',
 LOCATION='J9U1',
 ROOM='DDR4_GH_H',
 SEC='4',
 CDS_LIB='mstr_sconn',
 CDS_PART_NAME='SCONN288_H44441003_PIP-SCONN,HA',
 PRIM_FILE='./archive_libs/mstr_sconn/sconn288_h44441003/chips/chips.prt';

PART_NAME
 J9U2 'SCONN288_H44441003_PIP-SCONN,HA':
 ROOM='DDR4_CH_J';

SECTION_NUMBER 1
 '@BASEBOARD_FAB2_LIB.BASEBOARD_FAB2(SCH_1):PAGE82_I187@MSTR_SCONN.SCONN288_H44441003(CHIPS)':
 C_PATH='@baseboard_fab2_lib.baseboard_fab2(sch_1):page82_i187@mstr_sconn.sconn2~
88_h44441003(chips)',
 P_PATH='@baseboard_fab2_lib.baseboard_fab2(sch_1):page82_i187@mstr_sconn.sconn2~
88_h44441003(chips)',
 PATH='I187',
 DRAWING='@BASEBOARD_FAB2_LIB.BASEBOARD_FAB2(SCH_1):PAGE82',
 BOM_SS='NOPOP',
 SEC_TYPE='PIP',
 MATERIAL='SCONN',
 BOM_COST='MEM',
 PHYS_PAGE='82',
 XY='(-2500,3150)',
 ROT='0',
 VER='1',
 PACK_TYPE='PIP',
 PART_NUMBER='H44441-003',
 LOCATION='J9U2',
 ROOM='DDR4_CH_J',
 SEC='1',
 CDS_LIB='mstr_sconn',
 CDS_PART_NAME='SCONN288_H44441003_PIP-SCONN,HA',
 PRIM_FILE='./archive_libs/mstr_sconn/sconn288_h44441003/chips/chips.prt';

SECTION_NUMBER 2
 '@BASEBOARD_FAB2_LIB.BASEBOARD_FAB2(SCH_1):PAGE82_I64@MSTR_SCONN.SCONN288_H44441003(CHIPS)':
 C_PATH='@baseboard_fab2_lib.baseboard_fab2(sch_1):page82_i64@mstr_sconn.sconn28~
8_h44441003(chips)',
 P_PATH='@baseboard_fab2_lib.baseboard_fab2(sch_1):page82_i64@mstr_sconn.sconn28~
8_h44441003(chips)',
 PATH='I64',
 DRAWING='@BASEBOARD_FAB2_LIB.BASEBOARD_FAB2(SCH_1):PAGE82',
 BOM_SS='NOPOP',
 SEC_TYPE='PIP',
 MATERIAL='SCONN',
 BOM_COST='MEM',
 PHYS_PAGE='82',
 XY='(-50,4300)',
 ROT='0',
 VER='2',
 PACK_TYPE='PIP',
 PART_NUMBER='H44441-003',
 LOCATION='J9U2',
 ROOM='DDR4_CH_J',
 SEC='2',
 CDS_LIB='mstr_sconn',
 CDS_PART_NAME='SCONN288_H44441003_PIP-SCONN,HA',
 PRIM_FILE='./archive_libs/mstr_sconn/sconn288_h44441003/chips/chips.prt';

SECTION_NUMBER 3
 '@BASEBOARD_FAB2_LIB.BASEBOARD_FAB2(SCH_1):PAGE82_I188@MSTR_SCONN.SCONN288_H44441003(CHIPS)':
 C_PATH='@baseboard_fab2_lib.baseboard_fab2(sch_1):page82_i188@mstr_sconn.sconn2~
88_h44441003(chips)',
 P_PATH='@baseboard_fab2_lib.baseboard_fab2(sch_1):page82_i188@mstr_sconn.sconn2~
88_h44441003(chips)',
 PATH='I188',
 DRAWING='@BASEBOARD_FAB2_LIB.BASEBOARD_FAB2(SCH_1):PAGE82',
 BOM_SS='NOPOP',
 SEC_TYPE='PIP',
 MATERIAL='SCONN',
 BOM_COST='MEM',
 PHYS_PAGE='82',
 XY='(1750,2350)',
 ROT='0',
 VER='3',
 PACK_TYPE='PIP',
 PART_NUMBER='H44441-003',
 LOCATION='J9U2',
 ROOM='DDR4_CH_J',
 SEC='3',
 CDS_LIB='mstr_sconn',
 CDS_PART_NAME='SCONN288_H44441003_PIP-SCONN,HA',
 PRIM_FILE='./archive_libs/mstr_sconn/sconn288_h44441003/chips/chips.prt';

SECTION_NUMBER 4
 '@BASEBOARD_FAB2_LIB.BASEBOARD_FAB2(SCH_1):PAGE82_I171@MSTR_SCONN.SCONN288_H44441003(CHIPS)':
 C_PATH='@baseboard_fab2_lib.baseboard_fab2(sch_1):page82_i171@mstr_sconn.sconn2~
88_h44441003(chips)',
 P_PATH='@baseboard_fab2_lib.baseboard_fab2(sch_1):page82_i171@mstr_sconn.sconn2~
88_h44441003(chips)',
 PATH='I171',
 DRAWING='@BASEBOARD_FAB2_LIB.BASEBOARD_FAB2(SCH_1):PAGE82',
 BOM_SS='NOPOP',
 SEC_TYPE='PIP',
 MATERIAL='SCONN',
 BOM_COST='MEM',
 PHYS_PAGE='82',
 XY='(-350,2050)',
 ROT='0',
 VER='4',
 PACK_TYPE='PIP',
 PART_NUMBER='H44441-003',
 LOCATION='J9U2',
 ROOM='DDR4_CH_J',
 SEC='4',
 CDS_LIB='mstr_sconn',
 CDS_PART_NAME='SCONN288_H44441003_PIP-SCONN,HA',
 PRIM_FILE='./archive_libs/mstr_sconn/sconn288_h44441003/chips/chips.prt';

PART_NAME
 J10W1 'LOTES-CON4-S1-GP_CONN-G7-LOTESA':;

SECTION_NUMBER 1
 '@BASEBOARD_FAB2_LIB.BASEBOARD_FAB2(SCH_1):PAGE161_I140@W_HDL.LOTES-CON4-S1-GP(CHIPS)':
 C_PATH='@baseboard_fab2_lib.baseboard_fab2(sch_1):page161_i140@w_hdl.\lotes-con~
4-s1-gp\(chips)',
 P_PATH='@baseboard_fab2_lib.baseboard_fab2(sch_1):page161_i140@w_hdl.\lotes-con~
4-s1-gp\(chips)',
 PATH='I140',
 DRAWING='@BASEBOARD_FAB2_LIB.BASEBOARD_FAB2(SCH_1):PAGE161',
 SEC_TYPE='CONN-G7',
 PHYS_PAGE='161',
 XY='(-650,1800)',
 ROT='0',
 VER='1',
 VALUE='LOTES-CON4-S1-GP',
 PACK_TYPE='CONN-G7',
 PART_NUMBER='021.60521.0104',
 LOCATION='J10W1',
 SEC='1',
 CDS_LIB='w_hdl',
 CDS_PART_NAME='LOTES-CON4-S1-GP_CONN-G7-LOTESA',
 PRIM_FILE='C:/<user>/w_hdl/lotes#2dcon4#2ds1#2dgp/chips/chips.prt';

PART_NAME
 J25W1 'SMC-CON13-GP_CONN-GC2-SMC-CON1A':
 GROUP='AST2500';

SECTION_NUMBER 1
 '@BASEBOARD_FAB2_LIB.BASEBOARD_FAB2(SCH_1):PAGE255_I136@W_HDL.SMC-CON13-GP(CHIPS)':
 C_PATH='@baseboard_fab2_lib.baseboard_fab2(sch_1):page255_i136@w_hdl.\smc-con13~
-gp\(chips)',
 P_PATH='@baseboard_fab2_lib.baseboard_fab2(sch_1):page252_i136@w_hdl.\smc-con13~
-gp\(chips)',
 PATH='I136',
 DRAWING='@BASEBOARD_FAB2_LIB.BASEBOARD_FAB2(SCH_1):PAGE255',
 SEC_TYPE='CONN-GC2',
 PHYS_PAGE='252',
 XY='(-9225,2725)',
 ROT='0',
 VER='1',
 VALUE='SMC-CON13-GP',
 PACK_TYPE='CONN-GC2',
 PART_NUMBER='021.D0181.0113',
 LOCATION='J25W1',
 GROUP='AST2500',
 SEC='1',
 CDS_LIB='w_hdl',
 CDS_PART_NAME='SMC-CON13-GP_CONN-GC2-SMC-CON1A',
 PRIM_FILE='C:/<user>/w_hdl/smc#2dcon13#2dgp/chips/chips.prt';

PART_NAME
 J30W1 'SKT-USB32-8-GP_SOCKET-G4-SKT-UA':
 GROUP='NO_KR';

SECTION_NUMBER 1
 '@BASEBOARD_FAB2_LIB.BASEBOARD_FAB2(SCH_1):PAGE253_I26@W_HDL.SKT-USB32-8-GP(CHIPS)':
 C_PATH='@baseboard_fab2_lib.baseboard_fab2(sch_1):page253_i26@w_hdl.\skt-usb32-~
8-gp\(chips)',
 P_PATH='@baseboard_fab2_lib.baseboard_fab2(sch_1):page253_i26@w_hdl.\skt-usb32-~
8-gp\(chips)',
 PATH='I26',
 DRAWING='@BASEBOARD_FAB2_LIB.BASEBOARD_FAB2(SCH_1):PAGE253',
 SEC_TYPE='SOCKET-G4',
 PHYS_PAGE='253',
 XY='(-1750,3775)',
 ROT='0',
 VER='1',
 VALUE='SKT-USB32-8-GP',
 PACK_TYPE='SOCKET-G4',
 PART_NUMBER='062.10009.0621',
 LOCATION='J30W1',
 GROUP='NO_KR',
 SEC='1',
 CDS_LIB='w_hdl',
 CDS_PART_NAME='SKT-USB32-8-GP_SOCKET-G4-SKT-UA',
 PRIM_FILE='C:/<user>/w_hdl/skt#2dusb32#2d8#2dgp/chips/chips.prt';

PART_NAME
 JA9G1 'SKT-RJ45-LED-XFOR-1-GP_SOCKET-A':
 GROUP='NI_I210&RJ45';

SECTION_NUMBER 1
 '@BASEBOARD_FAB2_LIB.BASEBOARD_FAB2(SCH_1):PAGE141_I129@W_HDL.SKT-RJ45-LED-XFOR-1-GP(CHIPS)':
 C_PATH='@baseboard_fab2_lib.baseboard_fab2(sch_1):page141_i129@w_hdl.\skt-rj45-~
led-xfor-1-gp\(chips)',
 P_PATH='@baseboard_fab2_lib.baseboard_fab2(sch_1):page141_i129@w_hdl.\skt-rj45-~
led-xfor-1-gp\(chips)',
 PATH='I129',
 DRAWING='@BASEBOARD_FAB2_LIB.BASEBOARD_FAB2(SCH_1):PAGE141',
 SEC_TYPE='SOCKET-G2',
 PHYS_PAGE='141',
 XY='(-1650,1825)',
 ROT='0',
 VER='1',
 VALUE='SKT-RJ45-LED-XFOR-1-GP',
 PACK_TYPE='SOCKET-G2',
 PART_NUMBER='022.10001.0S51',
 LOCATION='JA9G1',
 GROUP='NI_I210&RJ45',
 SEC='1',
 CDS_LIB='w_hdl',
 CDS_PART_NAME='SKT-RJ45-LED-XFOR-1-GP_SOCKET-A',
 PRIM_FILE='C:/<user>/w_hdl/skt#2drj45#2dled#2dxfor#2d1#2dgp/chips/chips.prt~
';

PART_NAME
 L1A1 'IND-120NH-30-GP_DISCRET-GB2-INA':;

SECTION_NUMBER 1
 '@BASEBOARD_FAB2_LIB.BASEBOARD_FAB2(SCH_1):PAGE227_I153@W_HDL.IND-120NH-30-GP(CHIPS)':
 C_PATH='@baseboard_fab2_lib.baseboard_fab2(sch_1):page227_i153@w_hdl.\ind-120nh~
-30-gp\(chips)',
 P_PATH='@baseboard_fab2_lib.baseboard_fab2(sch_1):page227_i153@w_hdl.\ind-120nh~
-30-gp\(chips)',
 PATH='I153',
 DRAWING='@BASEBOARD_FAB2_LIB.BASEBOARD_FAB2(SCH_1):PAGE227',
 DS_VALUE='90NH',
 NEW_TYPE='IRMS=66A@DELTA_T<40C',
 NEW_RATED='DS_ISAT=134A@25C',
 NEW_PACK_SIZE='DCR=0.17MOHM',
 TYPE='IRMS=66A@DELTA_T<40C',
 PACK_SIZE='DCR=0.17MOHM',
 RATED='ISAT=94A@25C',
 ATTRIBUTE='120NH',
 BOM_SS='NOPOP',
 BOM_DS='068.9002N.1021',
 SEC_TYPE='DISCRET-GB2',
 PHYS_PAGE='227',
 XY='(3775,-300)',
 ROT='1',
 VER='1',
 VALUE='IND-120NH-30-GP',
 PACK_TYPE='DISCRET-GB2',
 PART_NUMBER='068.1202N.M001',
 LOCATION='L1A1',
 SEC='1',
 CDS_LIB='w_hdl',
 CDS_PART_NAME='IND-120NH-30-GP_DISCRET-GB2-INA',
 PRIM_FILE='C:/<user>/w_hdl/ind#2d120nh#2d30#2dgp/chips/chips.prt';

PART_NAME
 L1A2 'IND-120NH-30-GP_DISCRET-GB2-INA':;

SECTION_NUMBER 1
 '@BASEBOARD_FAB2_LIB.BASEBOARD_FAB2(SCH_1):PAGE227_I152@W_HDL.IND-120NH-30-GP(CHIPS)':
 C_PATH='@baseboard_fab2_lib.baseboard_fab2(sch_1):page227_i152@w_hdl.\ind-120nh~
-30-gp\(chips)',
 P_PATH='@baseboard_fab2_lib.baseboard_fab2(sch_1):page227_i152@w_hdl.\ind-120nh~
-30-gp\(chips)',
 PATH='I152',
 DRAWING='@BASEBOARD_FAB2_LIB.BASEBOARD_FAB2(SCH_1):PAGE227',
 SS_ISAT='94A@25C',
 DS_VALUE='90NH',
 SS_VALUE='120NH',
 NEW_TYPE='IRMS=66A@DELTA_T<40C',
 NEW_RATED='DS_ISAT=134A@25C',
 NEW_PACK_SIZE='DCR=0.17MOHM',
 TYPE='IRMS=66A@DELTA_T<40C',
 PACK_SIZE='DCR=0.17MOHM',
 RATED='ISAT=94A@25C',
 ATTRIBUTE='120NH',
 BOM_SS='068.1202N.M001',
 BOM_DS='068.9002N.1021',
 SEC_TYPE='DISCRET-GB2',
 PHYS_PAGE='227',
 XY='(3775,1950)',
 ROT='1',
 VER='1',
 VALUE='IND-120NH-30-GP',
 PACK_TYPE='DISCRET-GB2',
 PART_NUMBER='068.1202N.M001',
 LOCATION='L1A2',
 SEC='1',
 CDS_LIB='w_hdl',
 CDS_PART_NAME='IND-120NH-30-GP_DISCRET-GB2-INA',
 PRIM_FILE='C:/<user>/w_hdl/ind#2d120nh#2d30#2dgp/chips/chips.prt';

PART_NAME
 L1B1 'IND-100NH-35-GP_DISCRET-G8-INDA':;

SECTION_NUMBER 1
 '@BASEBOARD_FAB2_LIB.BASEBOARD_FAB2(SCH_1):PAGE228_I247@W_HDL.IND-100NH-35-GP(CHIPS)':
 C_PATH='@baseboard_fab2_lib.baseboard_fab2(sch_1):page228_i247@w_hdl.\ind-100nh~
-35-gp\(chips)',
 P_PATH='@baseboard_fab2_lib.baseboard_fab2(sch_1):page228_i247@w_hdl.\ind-100nh~
-35-gp\(chips)',
 PATH='I247',
 DRAWING='@BASEBOARD_FAB2_LIB.BASEBOARD_FAB2(SCH_1):PAGE228',
 TYPE='IRMS=29A@DELTA_T<45C',
 PACK_SIZE='DCR=0.16MOHM',
 RATED='ISAT=16A@25C',
 ATTRIBUTE='100NH',
 SEC_TYPE='DISCRET-G8',
 PHYS_PAGE='228',
 XY='(-1050,1125)',
 ROT='1',
 VER='1',
 VALUE='IND-100NH-35-GP',
 PACK_TYPE='DISCRET-G8',
 PART_NUMBER='068.1011N.M001',
 LOCATION='L1B1',
 SEC='1',
 CDS_LIB='w_hdl',
 CDS_PART_NAME='IND-100NH-35-GP_DISCRET-G8-INDA',
 PRIM_FILE='C:/<user>/w_hdl/ind#2d100nh#2d35#2dgp/chips/chips.prt';

PART_NAME
 L1B2 'IND-80NH-1-GP_DISCRET-GC2-IND-A':;

SECTION_NUMBER 1
 '@BASEBOARD_FAB2_LIB.BASEBOARD_FAB2(SCH_1):PAGE209_I81@W_HDL.IND-80NH-1-GP(CHIPS)':
 C_PATH='@baseboard_fab2_lib.baseboard_fab2(sch_1):page209_i81@w_hdl.\ind-80nh-1~
-gp\(chips)',
 P_PATH='@baseboard_fab2_lib.baseboard_fab2(sch_1):page209_i81@w_hdl.\ind-80nh-1~
-gp\(chips)',
 PATH='I81',
 DRAWING='@BASEBOARD_FAB2_LIB.BASEBOARD_FAB2(SCH_1):PAGE209',
 TYPE='IRMS=34A@DELTA_T<45C',
 PACK_SIZE='DCR=0.22MOHM',
 RATED='ISAT=50A@25C',
 ATTRIBUTE='80NH',
 SEC_TYPE='DISCRET-GC2',
 PHYS_PAGE='209',
 XY='(-3050,2275)',
 ROT='1',
 VER='1',
 VALUE='IND-80NH-1-GP',
 PACK_TYPE='DISCRET-GC2',
 PART_NUMBER='068.8001N.M001',
 LOCATION='L1B2',
 SEC='1',
 CDS_LIB='w_hdl',
 CDS_PART_NAME='IND-80NH-1-GP_DISCRET-GC2-IND-A',
 PRIM_FILE='C:/<user>/w_hdl/ind#2d80nh#2d1#2dgp/chips/chips.prt';

PART_NAME
 L1C1 'IND-300NH-20-GP_DISCRET-GB1-INA':;

SECTION_NUMBER 1
 '@BASEBOARD_FAB2_LIB.BASEBOARD_FAB2(SCH_1):PAGE210_I72@W_HDL.IND-300NH-20-GP(CHIPS)':
 C_PATH='@baseboard_fab2_lib.baseboard_fab2(sch_1):page210_i72@w_hdl.\ind-300nh-~
20-gp\(chips)',
 P_PATH='@baseboard_fab2_lib.baseboard_fab2(sch_1):page210_i72@w_hdl.\ind-300nh-~
20-gp\(chips)',
 PATH='I72',
 DRAWING='@BASEBOARD_FAB2_LIB.BASEBOARD_FAB2(SCH_1):PAGE210',
 TYPE='IRMS=66A@DELTA_T<40C',
 PACK_SIZE='DCR=0.17MOHM',
 RATED='ISAT=33A@25C',
 ATTRIBUTE='300NH',
 SEC_TYPE='DISCRET-GB1',
 PHYS_PAGE='210',
 XY='(-1625,3325)',
 ROT='1',
 VER='1',
 VALUE='IND-300NH-20-GP',
 PACK_TYPE='DISCRET-GB1',
 PART_NUMBER='068.3012N.M001',
 LOCATION='L1C1',
 SEC='1',
 CDS_LIB='w_hdl',
 CDS_PART_NAME='IND-300NH-20-GP_DISCRET-GB1-INA',
 PRIM_FILE='C:/<user>/w_hdl/ind#2d300nh#2d20#2dgp/chips/chips.prt';

PART_NAME
 L1C2 'IND-120NH-30-GP_DISCRET-GB2-INA':;

SECTION_NUMBER 1
 '@BASEBOARD_FAB2_LIB.BASEBOARD_FAB2(SCH_1):PAGE209_I80@W_HDL.IND-120NH-30-GP(CHIPS)':
 C_PATH='@baseboard_fab2_lib.baseboard_fab2(sch_1):page209_i80@w_hdl.\ind-120nh-~
30-gp\(chips)',
 P_PATH='@baseboard_fab2_lib.baseboard_fab2(sch_1):page209_i80@w_hdl.\ind-120nh-~
30-gp\(chips)',
 PATH='I80',
 DRAWING='@BASEBOARD_FAB2_LIB.BASEBOARD_FAB2(SCH_1):PAGE209',
 TYPE='IRMS=66A@DELTA_T<40C',
 PACK_SIZE='DCR=0.17MOHM',
 RATED='ISAT=94A@25C',
 ATTRIBUTE='120NH',
 SEC_TYPE='DISCRET-GB2',
 PHYS_PAGE='209',
 XY='(-1400,3500)',
 ROT='1',
 VER='1',
 VALUE='IND-120NH-30-GP',
 PACK_TYPE='DISCRET-GB2',
 PART_NUMBER='068.1202N.M001',
 LOCATION='L1C2',
 SEC='1',
 CDS_LIB='w_hdl',
 CDS_PART_NAME='IND-120NH-30-GP_DISCRET-GB2-INA',
 PRIM_FILE='C:/<user>/w_hdl/ind#2d120nh#2d30#2dgp/chips/chips.prt';

PART_NAME
 L1D1 'IND-120NH-30-GP_DISCRET-GB2-INA':;

SECTION_NUMBER 1
 '@BASEBOARD_FAB2_LIB.BASEBOARD_FAB2(SCH_1):PAGE208_I117@W_HDL.IND-120NH-30-GP(CHIPS)':
 C_PATH='@baseboard_fab2_lib.baseboard_fab2(sch_1):page208_i117@w_hdl.\ind-120nh~
-30-gp\(chips)',
 P_PATH='@baseboard_fab2_lib.baseboard_fab2(sch_1):page208_i117@w_hdl.\ind-120nh~
-30-gp\(chips)',
 PATH='I117',
 DRAWING='@BASEBOARD_FAB2_LIB.BASEBOARD_FAB2(SCH_1):PAGE208',
 TYPE='IRMS=66A@DELTA_T<40C',
 PACK_SIZE='DCR=0.17MOHM',
 RATED='ISAT=94A@25C',
 ATTRIBUTE='120NH',
 SEC_TYPE='DISCRET-GB2',
 PHYS_PAGE='208',
 XY='(-1275,1050)',
 ROT='1',
 VER='1',
 VALUE='IND-120NH-30-GP',
 PACK_TYPE='DISCRET-GB2',
 PART_NUMBER='068.1202N.M001',
 LOCATION='L1D1',
 SEC='1',
 CDS_LIB='w_hdl',
 CDS_PART_NAME='IND-120NH-30-GP_DISCRET-GB2-INA',
 PRIM_FILE='C:/<user>/w_hdl/ind#2d120nh#2d30#2dgp/chips/chips.prt';

PART_NAME
 L1D2 'IND-120NH-30-GP_DISCRET-GB2-INA':;

SECTION_NUMBER 1
 '@BASEBOARD_FAB2_LIB.BASEBOARD_FAB2(SCH_1):PAGE208_I116@W_HDL.IND-120NH-30-GP(CHIPS)':
 C_PATH='@baseboard_fab2_lib.baseboard_fab2(sch_1):page208_i116@w_hdl.\ind-120nh~
-30-gp\(chips)',
 P_PATH='@baseboard_fab2_lib.baseboard_fab2(sch_1):page208_i116@w_hdl.\ind-120nh~
-30-gp\(chips)',
 PATH='I116',
 DRAWING='@BASEBOARD_FAB2_LIB.BASEBOARD_FAB2(SCH_1):PAGE208',
 TYPE='IRMS=66A@DELTA_T<40C',
 PACK_SIZE='DCR=0.17MOHM',
 RATED='ISAT=94A@25C',
 ATTRIBUTE='120NH',
 SEC_TYPE='DISCRET-GB2',
 PHYS_PAGE='208',
 XY='(-1425,3650)',
 ROT='1',
 VER='1',
 VALUE='IND-120NH-30-GP',
 PACK_TYPE='DISCRET-GB2',
 PART_NUMBER='068.1202N.M001',
 LOCATION='L1D2',
 SEC='1',
 CDS_LIB='w_hdl',
 CDS_PART_NAME='IND-120NH-30-GP_DISCRET-GB2-INA',
 PRIM_FILE='C:/<user>/w_hdl/ind#2d120nh#2d30#2dgp/chips/chips.prt';

PART_NAME
 L1D3 'IND-120NH-30-GP_DISCRET-GB2-INA':;

SECTION_NUMBER 1
 '@BASEBOARD_FAB2_LIB.BASEBOARD_FAB2(SCH_1):PAGE207_I108@W_HDL.IND-120NH-30-GP(CHIPS)':
 C_PATH='@baseboard_fab2_lib.baseboard_fab2(sch_1):page207_i108@w_hdl.\ind-120nh~
-30-gp\(chips)',
 P_PATH='@baseboard_fab2_lib.baseboard_fab2(sch_1):page207_i108@w_hdl.\ind-120nh~
-30-gp\(chips)',
 PATH='I108',
 DRAWING='@BASEBOARD_FAB2_LIB.BASEBOARD_FAB2(SCH_1):PAGE207',
 TYPE='IRMS=66A@DELTA_T<40C',
 PACK_SIZE='DCR=0.17MOHM',
 RATED='ISAT=94A@25C',
 ATTRIBUTE='120NH',
 SEC_TYPE='DISCRET-GB2',
 PHYS_PAGE='207',
 XY='(-1425,975)',
 ROT='1',
 VER='1',
 VALUE='IND-120NH-30-GP',
 PACK_TYPE='DISCRET-GB2',
 PART_NUMBER='068.1202N.M001',
 LOCATION='L1D3',
 SEC='1',
 CDS_LIB='w_hdl',
 CDS_PART_NAME='IND-120NH-30-GP_DISCRET-GB2-INA',
 PRIM_FILE='C:/<user>/w_hdl/ind#2d120nh#2d30#2dgp/chips/chips.prt';

PART_NAME
 L1E1 'IND-120NH-30-GP_DISCRET-GB2-INA':;

SECTION_NUMBER 1
 '@BASEBOARD_FAB2_LIB.BASEBOARD_FAB2(SCH_1):PAGE207_I107@W_HDL.IND-120NH-30-GP(CHIPS)':
 C_PATH='@baseboard_fab2_lib.baseboard_fab2(sch_1):page207_i107@w_hdl.\ind-120nh~
-30-gp\(chips)',
 P_PATH='@baseboard_fab2_lib.baseboard_fab2(sch_1):page207_i107@w_hdl.\ind-120nh~
-30-gp\(chips)',
 PATH='I107',
 DRAWING='@BASEBOARD_FAB2_LIB.BASEBOARD_FAB2(SCH_1):PAGE207',
 TYPE='IRMS=66A@DELTA_T<40C',
 PACK_SIZE='DCR=0.17MOHM',
 RATED='ISAT=94A@25C',
 ATTRIBUTE='120NH',
 SEC_TYPE='DISCRET-GB2',
 PHYS_PAGE='207',
 XY='(-1475,3575)',
 ROT='1',
 VER='1',
 VALUE='IND-120NH-30-GP',
 PACK_TYPE='DISCRET-GB2',
 PART_NUMBER='068.1202N.M001',
 LOCATION='L1E1',
 SEC='1',
 CDS_LIB='w_hdl',
 CDS_PART_NAME='IND-120NH-30-GP_DISCRET-GB2-INA',
 PRIM_FILE='C:/<user>/w_hdl/ind#2d120nh#2d30#2dgp/chips/chips.prt';

PART_NAME
 L1F1 'IND-100NH-35-GP_DISCRET-G8-INDA':;

SECTION_NUMBER 1
 '@BASEBOARD_FAB2_LIB.BASEBOARD_FAB2(SCH_1):PAGE225_I253@W_HDL.IND-100NH-35-GP(CHIPS)':
 C_PATH='@baseboard_fab2_lib.baseboard_fab2(sch_1):page225_i253@w_hdl.\ind-100nh~
-35-gp\(chips)',
 P_PATH='@baseboard_fab2_lib.baseboard_fab2(sch_1):page225_i253@w_hdl.\ind-100nh~
-35-gp\(chips)',
 PATH='I253',
 DRAWING='@BASEBOARD_FAB2_LIB.BASEBOARD_FAB2(SCH_1):PAGE225',
 TYPE='IRMS=29A@DELTA_T<45C',
 PACK_SIZE='DCR=0.16MOHM',
 RATED='ISAT=16A@25C',
 ATTRIBUTE='100NH',
 SEC_TYPE='DISCRET-G8',
 PHYS_PAGE='225',
 XY='(-1750,1375)',
 ROT='1',
 VER='1',
 VALUE='IND-100NH-35-GP',
 PACK_TYPE='DISCRET-G8',
 PART_NUMBER='068.1011N.M001',
 LOCATION='L1F1',
 SEC='1',
 CDS_LIB='w_hdl',
 CDS_PART_NAME='IND-100NH-35-GP_DISCRET-G8-INDA',
 PRIM_FILE='C:/<user>/w_hdl/ind#2d100nh#2d35#2dgp/chips/chips.prt';

PART_NAME
 L1F2 'IND-120NH-30-GP_DISCRET-GB2-INA':;

SECTION_NUMBER 1
 '@BASEBOARD_FAB2_LIB.BASEBOARD_FAB2(SCH_1):PAGE224_I161@W_HDL.IND-120NH-30-GP(CHIPS)':
 C_PATH='@baseboard_fab2_lib.baseboard_fab2(sch_1):page224_i161@w_hdl.\ind-120nh~
-30-gp\(chips)',
 P_PATH='@baseboard_fab2_lib.baseboard_fab2(sch_1):page224_i161@w_hdl.\ind-120nh~
-30-gp\(chips)',
 PATH='I161',
 DRAWING='@BASEBOARD_FAB2_LIB.BASEBOARD_FAB2(SCH_1):PAGE224',
 DS_VALUE='90NH',
 NEW_TYPE='IRMS=66A@DELTA_T<40C',
 NEW_RATED='DS_ISAT=134A@25C',
 NEW_PACK_SIZE='DCR=0.17MOHM',
 TYPE='IRMS=66A@DELTA_T<40C',
 PACK_SIZE='DCR=0.17MOHM',
 RATED='ISAT=94A@25C',
 ATTRIBUTE='120NH',
 BOM_SS='NOPOP',
 BOM_DS='068.9002N.1021',
 SEC_TYPE='DISCRET-GB2',
 PHYS_PAGE='224',
 XY='(3900,-400)',
 ROT='1',
 VER='1',
 VALUE='IND-120NH-30-GP',
 PACK_TYPE='DISCRET-GB2',
 PART_NUMBER='068.1202N.M001',
 LOCATION='L1F2',
 SEC='1',
 CDS_LIB='w_hdl',
 CDS_PART_NAME='IND-120NH-30-GP_DISCRET-GB2-INA',
 PRIM_FILE='C:/<user>/w_hdl/ind#2d120nh#2d30#2dgp/chips/chips.prt';

PART_NAME
 L1G1 'IND-120NH-30-GP_DISCRET-GB2-INA':;

SECTION_NUMBER 1
 '@BASEBOARD_FAB2_LIB.BASEBOARD_FAB2(SCH_1):PAGE224_I160@W_HDL.IND-120NH-30-GP(CHIPS)':
 C_PATH='@baseboard_fab2_lib.baseboard_fab2(sch_1):page224_i160@w_hdl.\ind-120nh~
-30-gp\(chips)',
 P_PATH='@baseboard_fab2_lib.baseboard_fab2(sch_1):page224_i160@w_hdl.\ind-120nh~
-30-gp\(chips)',
 PATH='I160',
 DRAWING='@BASEBOARD_FAB2_LIB.BASEBOARD_FAB2(SCH_1):PAGE224',
 SS_ISAT='94A@25C',
 DS_VALUE='90NH',
 SS_VALUE='120NH',
 NEW_TYPE='IRMS=66A@DELTA_T<40C',
 NEW_RATED='DS_ISAT=134A@25C',
 NEW_PACK_SIZE='DCR=0.17MOHM',
 TYPE='IRMS=66A@DELTA_T<40C',
 PACK_SIZE='DCR=0.17MOHM',
 RATED='ISAT=94A@25C',
 ATTRIBUTE='120NH',
 BOM_SS='068.1202N.M001',
 BOM_DS='068.9002N.1021',
 SEC_TYPE='DISCRET-GB2',
 PHYS_PAGE='224',
 XY='(3950,1975)',
 ROT='1',
 VER='1',
 VALUE='IND-120NH-30-GP',
 PACK_TYPE='DISCRET-GB2',
 PART_NUMBER='068.1202N.M001',
 LOCATION='L1G1',
 SEC='1',
 CDS_LIB='w_hdl',
 CDS_PART_NAME='IND-120NH-30-GP_DISCRET-GB2-INA',
 PRIM_FILE='C:/<user>/w_hdl/ind#2d120nh#2d30#2dgp/chips/chips.prt';

PART_NAME
 L1M2 'CHOKE_4PIN_SMLF-90 OHM,IND,752A':;

SECTION_NUMBER 1
 '@BASEBOARD_FAB2_LIB.BASEBOARD_FAB2(SCH_1):PAGE176_I181@MSTR_DISCRETE.CHOKE_4PIN(CHIPS)':
 C_PATH='@baseboard_fab2_lib.baseboard_fab2(sch_1):page176_i181@mstr_discrete.ch~
oke_4pin(chips)',
 P_PATH='@baseboard_fab2_lib.baseboard_fab2(sch_1):page176_i181@mstr_discrete.ch~
oke_4pin(chips)',
 PATH='I181',
 DRAWING='@BASEBOARD_FAB2_LIB.BASEBOARD_FAB2(SCH_1):PAGE176',
 SEC_TYPE='SMLF',
 MATERIAL='IND',
 PHYS_PAGE='176',
 XY='(-5500,5025)',
 ROT='0',
 VER='1',
 VALUE='90 OHM',
 PACK_TYPE='SMLF',
 PART_NUMBER='752402-015',
 LOCATION='L1M2',
 SEC='1',
 CDS_LIB='mstr_discrete',
 CDS_PART_NAME='CHOKE_4PIN_SMLF-90 OHM,IND,752A',
 PRIM_FILE='./archive_libs/mstr_discrete/choke_4pin/chips/chips.prt';

PART_NAME
 L2M1 'INDUCTOR_SMT-0.022UH,IND,72189A':
 ROOM='SB_FILTER_KR_PLL';

SECTION_NUMBER 1
 '@BASEBOARD_FAB2_LIB.BASEBOARD_FAB2(SCH_1):PAGE127_I71@MSTR_DISCRETE.INDUCTOR(CHIPS)':
 C_PATH='@baseboard_fab2_lib.baseboard_fab2(sch_1):page127_i71@mstr_discrete.ind~
uctor(chips)',
 P_PATH='@baseboard_fab2_lib.baseboard_fab2(sch_1):page127_i71@mstr_discrete.ind~
uctor(chips)',
 PATH='I71',
 DRAWING='@BASEBOARD_FAB2_LIB.BASEBOARD_FAB2(SCH_1):PAGE127',
 SEC_TYPE='SMT',
 MATERIAL='IND',
 BOM_COST='SB',
 PHYS_PAGE='127',
 XY='(-1250,-3100)',
 ROT='0',
 VER='1',
 VALUE='0.022UH',
 PACK_TYPE='SMT',
 PART_NUMBER='721891-082',
 LOCATION='L2M1',
 ROOM='SB_FILTER_KR_PLL',
 SEC='1',
 CDS_LIB='mstr_discrete',
 CDS_PART_NAME='INDUCTOR_SMT-0.022UH,IND,72189A',
 PRIM_FILE='./archive_libs/mstr_discrete/inductor/chips/chips.prt';

PART_NAME
 L4A1 'INDUCTOR_SM-0.47UH,IND,E13358-A':
 ROOM='PVPP_KLM_VR',
 REUSE_ID='30';

SECTION_NUMBER 1
 '@BASEBOARD_FAB2_LIB.BASEBOARD_FAB2(SCH_1):PAGE234_I164@MSTR_DISCRETE.INDUCTOR(CHIPS)':
 C_PATH='@baseboard_fab2_lib.baseboard_fab2(sch_1):page234_i164@mstr_discrete.in~
ductor(chips)',
 P_PATH='@baseboard_fab2_lib.baseboard_fab2(sch_1):page234_i164@mstr_discrete.in~
ductor(chips)',
 PATH='I164',
 DRAWING='@BASEBOARD_FAB2_LIB.BASEBOARD_FAB2(SCH_1):PAGE234',
 TOLERANCE='1%',
 MATERIAL='IND',
 BOM_COST='PVPP_KLM_VR',
 PHYS_PAGE='234',
 REUSE_ID='30',
 XY='(-2300,3850)',
 ROT='0',
 VER='1',
 VALUE='0.47UH',
 PACK_TYPE='SM',
 PART_NUMBER='E13358-018',
 LOCATION='L4A1',
 ROOM='PVPP_KLM_VR',
 CDS_LIB='mstr_discrete',
 CDS_PART_NAME='INDUCTOR_SM-0.47UH,IND,E13358-A',
 PRIM_FILE='./archive_libs/mstr_discrete/inductor/chips/chips.prt';

PART_NAME
 L4C1 'IND-80NH-1-GP_DISCRET-GC2-IND-A':;

SECTION_NUMBER 1
 '@BASEBOARD_FAB2_LIB.BASEBOARD_FAB2(SCH_1):PAGE204_I105@W_HDL.IND-80NH-1-GP(CHIPS)':
 C_PATH='@baseboard_fab2_lib.baseboard_fab2(sch_1):page204_i105@w_hdl.\ind-80nh-~
1-gp\(chips)',
 P_PATH='@baseboard_fab2_lib.baseboard_fab2(sch_1):page204_i105@w_hdl.\ind-80nh-~
1-gp\(chips)',
 PATH='I105',
 DRAWING='@BASEBOARD_FAB2_LIB.BASEBOARD_FAB2(SCH_1):PAGE204',
 TYPE='IRMS=34A@DELTA_T<45C',
 PACK_SIZE='DCR=0.22MOHM',
 RATED='ISAT=50A@25C',
 ATTRIBUTE='80NH',
 SEC_TYPE='DISCRET-GC2',
 PHYS_PAGE='204',
 XY='(-3025,2200)',
 ROT='1',
 VER='1',
 VALUE='IND-80NH-1-GP',
 PACK_TYPE='DISCRET-GC2',
 PART_NUMBER='068.8001N.M001',
 LOCATION='L4C1',
 SEC='1',
 CDS_LIB='w_hdl',
 CDS_PART_NAME='IND-80NH-1-GP_DISCRET-GC2-IND-A',
 PRIM_FILE='C:/<user>/w_hdl/ind#2d80nh#2d1#2dgp/chips/chips.prt';

PART_NAME
 L4C2 'IND-300NH-20-GP_DISCRET-GB1-INA':;

SECTION_NUMBER 1
 '@BASEBOARD_FAB2_LIB.BASEBOARD_FAB2(SCH_1):PAGE205_I82@W_HDL.IND-300NH-20-GP(CHIPS)':
 C_PATH='@baseboard_fab2_lib.baseboard_fab2(sch_1):page205_i82@w_hdl.\ind-300nh-~
20-gp\(chips)',
 P_PATH='@baseboard_fab2_lib.baseboard_fab2(sch_1):page205_i82@w_hdl.\ind-300nh-~
20-gp\(chips)',
 PATH='I82',
 DRAWING='@BASEBOARD_FAB2_LIB.BASEBOARD_FAB2(SCH_1):PAGE205',
 TYPE='IRMS=66A@DELTA_T<40C',
 PACK_SIZE='DCR=0.17MOHM',
 RATED='ISAT=33A@25C',
 ATTRIBUTE='300NH',
 SEC_TYPE='DISCRET-GB1',
 PHYS_PAGE='205',
 XY='(-1325,3650)',
 ROT='1',
 VER='1',
 VALUE='IND-300NH-20-GP',
 PACK_TYPE='DISCRET-GB1',
 PART_NUMBER='068.3012N.M001',
 LOCATION='L4C2',
 SEC='1',
 CDS_LIB='w_hdl',
 CDS_PART_NAME='IND-300NH-20-GP_DISCRET-GB1-INA',
 PRIM_FILE='C:/<user>/w_hdl/ind#2d300nh#2d20#2dgp/chips/chips.prt';

PART_NAME
 L4C3 'IND-120NH-30-GP_DISCRET-GB2-INA':;

SECTION_NUMBER 1
 '@BASEBOARD_FAB2_LIB.BASEBOARD_FAB2(SCH_1):PAGE204_I104@W_HDL.IND-120NH-30-GP(CHIPS)':
 C_PATH='@baseboard_fab2_lib.baseboard_fab2(sch_1):page204_i104@w_hdl.\ind-120nh~
-30-gp\(chips)',
 P_PATH='@baseboard_fab2_lib.baseboard_fab2(sch_1):page204_i104@w_hdl.\ind-120nh~
-30-gp\(chips)',
 PATH='I104',
 DRAWING='@BASEBOARD_FAB2_LIB.BASEBOARD_FAB2(SCH_1):PAGE204',
 TYPE='IRMS=66A@DELTA_T<40C',
 PACK_SIZE='DCR=0.17MOHM',
 RATED='ISAT=94A@25C',
 ATTRIBUTE='120NH',
 SEC_TYPE='DISCRET-GB2',
 PHYS_PAGE='204',
 XY='(-1050,3650)',
 ROT='1',
 VER='1',
 VALUE='IND-120NH-30-GP',
 PACK_TYPE='DISCRET-GB2',
 PART_NUMBER='068.1202N.M001',
 LOCATION='L4C3',
 SEC='1',
 CDS_LIB='w_hdl',
 CDS_PART_NAME='IND-120NH-30-GP_DISCRET-GB2-INA',
 PRIM_FILE='C:/<user>/w_hdl/ind#2d120nh#2d30#2dgp/chips/chips.prt';

PART_NAME
 L4D1 'IND-120NH-30-GP_DISCRET-GB2-INA':;

SECTION_NUMBER 1
 '@BASEBOARD_FAB2_LIB.BASEBOARD_FAB2(SCH_1):PAGE203_I131@W_HDL.IND-120NH-30-GP(CHIPS)':
 C_PATH='@baseboard_fab2_lib.baseboard_fab2(sch_1):page203_i131@w_hdl.\ind-120nh~
-30-gp\(chips)',
 P_PATH='@baseboard_fab2_lib.baseboard_fab2(sch_1):page203_i131@w_hdl.\ind-120nh~
-30-gp\(chips)',
 PATH='I131',
 DRAWING='@BASEBOARD_FAB2_LIB.BASEBOARD_FAB2(SCH_1):PAGE203',
 TYPE='IRMS=66A@DELTA_T<40C',
 PACK_SIZE='DCR=0.17MOHM',
 RATED='ISAT=94A@25C',
 ATTRIBUTE='120NH',
 SEC_TYPE='DISCRET-GB2',
 PHYS_PAGE='203',
 XY='(-1075,950)',
 ROT='1',
 VER='1',
 VALUE='IND-120NH-30-GP',
 PACK_TYPE='DISCRET-GB2',
 PART_NUMBER='068.1202N.M001',
 LOCATION='L4D1',
 SEC='1',
 CDS_LIB='w_hdl',
 CDS_PART_NAME='IND-120NH-30-GP_DISCRET-GB2-INA',
 PRIM_FILE='C:/<user>/w_hdl/ind#2d120nh#2d30#2dgp/chips/chips.prt';

PART_NAME
 L4D2 'IND-120NH-30-GP_DISCRET-GB2-INA':;

SECTION_NUMBER 1
 '@BASEBOARD_FAB2_LIB.BASEBOARD_FAB2(SCH_1):PAGE203_I130@W_HDL.IND-120NH-30-GP(CHIPS)':
 C_PATH='@baseboard_fab2_lib.baseboard_fab2(sch_1):page203_i130@w_hdl.\ind-120nh~
-30-gp\(chips)',
 P_PATH='@baseboard_fab2_lib.baseboard_fab2(sch_1):page203_i130@w_hdl.\ind-120nh~
-30-gp\(chips)',
 PATH='I130',
 DRAWING='@BASEBOARD_FAB2_LIB.BASEBOARD_FAB2(SCH_1):PAGE203',
 TYPE='IRMS=66A@DELTA_T<40C',
 PACK_SIZE='DCR=0.17MOHM',
 RATED='ISAT=94A@25C',
 ATTRIBUTE='120NH',
 SEC_TYPE='DISCRET-GB2',
 PHYS_PAGE='203',
 XY='(-1175,3675)',
 ROT='1',
 VER='1',
 VALUE='IND-120NH-30-GP',
 PACK_TYPE='DISCRET-GB2',
 PART_NUMBER='068.1202N.M001',
 LOCATION='L4D2',
 SEC='1',
 CDS_LIB='w_hdl',
 CDS_PART_NAME='IND-120NH-30-GP_DISCRET-GB2-INA',
 PRIM_FILE='C:/<user>/w_hdl/ind#2d120nh#2d30#2dgp/chips/chips.prt';

PART_NAME
 L4D3 'IND-120NH-30-GP_DISCRET-GB2-INA':;

SECTION_NUMBER 1
 '@BASEBOARD_FAB2_LIB.BASEBOARD_FAB2(SCH_1):PAGE202_I110@W_HDL.IND-120NH-30-GP(CHIPS)':
 C_PATH='@baseboard_fab2_lib.baseboard_fab2(sch_1):page202_i110@w_hdl.\ind-120nh~
-30-gp\(chips)',
 P_PATH='@baseboard_fab2_lib.baseboard_fab2(sch_1):page202_i110@w_hdl.\ind-120nh~
-30-gp\(chips)',
 PATH='I110',
 DRAWING='@BASEBOARD_FAB2_LIB.BASEBOARD_FAB2(SCH_1):PAGE202',
 TYPE='IRMS=66A@DELTA_T<40C',
 PACK_SIZE='DCR=0.17MOHM',
 RATED='ISAT=94A@25C',
 ATTRIBUTE='120NH',
 SEC_TYPE='DISCRET-GB2',
 PHYS_PAGE='202',
 XY='(-1300,975)',
 ROT='1',
 VER='1',
 VALUE='IND-120NH-30-GP',
 PACK_TYPE='DISCRET-GB2',
 PART_NUMBER='068.1202N.M001',
 LOCATION='L4D3',
 SEC='1',
 CDS_LIB='w_hdl',
 CDS_PART_NAME='IND-120NH-30-GP_DISCRET-GB2-INA',
 PRIM_FILE='C:/<user>/w_hdl/ind#2d120nh#2d30#2dgp/chips/chips.prt';

PART_NAME
 L4E1 'IND-120NH-30-GP_DISCRET-GB2-INA':;

SECTION_NUMBER 1
 '@BASEBOARD_FAB2_LIB.BASEBOARD_FAB2(SCH_1):PAGE202_I109@W_HDL.IND-120NH-30-GP(CHIPS)':
 C_PATH='@baseboard_fab2_lib.baseboard_fab2(sch_1):page202_i109@w_hdl.\ind-120nh~
-30-gp\(chips)',
 P_PATH='@baseboard_fab2_lib.baseboard_fab2(sch_1):page202_i109@w_hdl.\ind-120nh~
-30-gp\(chips)',
 PATH='I109',
 DRAWING='@BASEBOARD_FAB2_LIB.BASEBOARD_FAB2(SCH_1):PAGE202',
 TYPE='IRMS=66A@DELTA_T<40C',
 PACK_SIZE='DCR=0.17MOHM',
 RATED='ISAT=94A@25C',
 ATTRIBUTE='120NH',
 SEC_TYPE='DISCRET-GB2',
 PHYS_PAGE='202',
 XY='(-1700,3525)',
 ROT='1',
 VER='1',
 VALUE='IND-120NH-30-GP',
 PACK_TYPE='DISCRET-GB2',
 PART_NUMBER='068.1202N.M001',
 LOCATION='L4E1',
 SEC='1',
 CDS_LIB='w_hdl',
 CDS_PART_NAME='IND-120NH-30-GP_DISCRET-GB2-INA',
 PRIM_FILE='C:/<user>/w_hdl/ind#2d120nh#2d30#2dgp/chips/chips.prt';

PART_NAME
 L4E2 'IND-150NH-56-GP_DISCRET-GA1-INA':;

SECTION_NUMBER 1
 '@BASEBOARD_FAB2_LIB.BASEBOARD_FAB2(SCH_1):PAGE214_I174@W_HDL.IND-150NH-56-GP(CHIPS)':
 C_PATH='@baseboard_fab2_lib.baseboard_fab2(sch_1):page214_i174@w_hdl.\ind-150nh~
-56-gp\(chips)',
 P_PATH='@baseboard_fab2_lib.baseboard_fab2(sch_1):page214_i174@w_hdl.\ind-150nh~
-56-gp\(chips)',
 PATH='I174',
 DRAWING='@BASEBOARD_FAB2_LIB.BASEBOARD_FAB2(SCH_1):PAGE214',
 TYPE='IRMS=66A@DELTA_T<40C',
 PACK_SIZE='DCR=0.17MOHM',
 RATED='ISAT=75A@25C',
 ATTRIBUTE='150NH',
 SEC_TYPE='DISCRET-GA1',
 PHYS_PAGE='214',
 XY='(3000,3650)',
 ROT='1',
 VER='1',
 VALUE='IND-150NH-56-GP',
 PACK_TYPE='DISCRET-GA1',
 PART_NUMBER='068.1512N.M001',
 LOCATION='L4E2',
 SEC='1',
 CDS_LIB='w_hdl',
 CDS_PART_NAME='IND-150NH-56-GP_DISCRET-GA1-INA',
 PRIM_FILE='C:/<user>/w_hdl/ind#2d150nh#2d56#2dgp/chips/chips.prt';

PART_NAME
 L4G1 'INDUCTOR_SM-0.47UH,IND,E13358-A':
 ROOM='PVPP_GHJ_VR',
 REUSE_ID='30';

SECTION_NUMBER 1
 '@BASEBOARD_FAB2_LIB.BASEBOARD_FAB2(SCH_1):PAGE233_I277@MSTR_DISCRETE.INDUCTOR(CHIPS)':
 C_PATH='@baseboard_fab2_lib.baseboard_fab2(sch_1):page233_i277@mstr_discrete.in~
ductor(chips)',
 P_PATH='@baseboard_fab2_lib.baseboard_fab2(sch_1):page233_i277@mstr_discrete.in~
ductor(chips)',
 PATH='I277',
 DRAWING='@BASEBOARD_FAB2_LIB.BASEBOARD_FAB2(SCH_1):PAGE233',
 TOLERANCE='1%',
 SEC_TYPE='SM',
 MATERIAL='IND',
 BOM_COST='PVPP_GHJ_VR',
 PHYS_PAGE='233',
 REUSE_ID='30',
 XY='(-2175,3700)',
 ROT='0',
 VER='1',
 VALUE='0.47UH',
 PACK_TYPE='SM',
 PART_NUMBER='E13358-018',
 LOCATION='L4G1',
 ROOM='PVPP_GHJ_VR',
 SEC='1',
 CDS_LIB='mstr_discrete',
 CDS_PART_NAME='INDUCTOR_SM-0.47UH,IND,E13358-A',
 PRIM_FILE='./archive_libs/mstr_discrete/inductor/chips/chips.prt';

PART_NAME
 L7A1 'IND-120NH-30-GP_DISCRET-GB2-INA':;

SECTION_NUMBER 1
 '@BASEBOARD_FAB2_LIB.BASEBOARD_FAB2(SCH_1):PAGE219_I157@W_HDL.IND-120NH-30-GP(CHIPS)':
 C_PATH='@baseboard_fab2_lib.baseboard_fab2(sch_1):page219_i157@w_hdl.\ind-120nh~
-30-gp\(chips)',
 P_PATH='@baseboard_fab2_lib.baseboard_fab2(sch_1):page219_i157@w_hdl.\ind-120nh~
-30-gp\(chips)',
 PATH='I157',
 DRAWING='@BASEBOARD_FAB2_LIB.BASEBOARD_FAB2(SCH_1):PAGE219',
 SS_ISAT='94A@25C',
 DS_VALUE='90NH',
 SS_VALUE='120NH',
 NEW_TYPE='IRMS=66A@DELTA_T<40C',
 NEW_RATED='DS_ISAT=134A@25C',
 NEW_PACK_SIZE='DCR=0.17MOHM',
 TYPE='IRMS=66A@DELTA_T<40C',
 PACK_SIZE='DCR=0.17MOHM',
 RATED='ISAT=94A@25C',
 ATTRIBUTE='120NH',
 BOM_SS='068.1202N.M001',
 BOM_DS='068.9002N.1021',
 SEC_TYPE='DISCRET-GB2',
 PHYS_PAGE='219',
 XY='(3850,1850)',
 ROT='1',
 VER='1',
 VALUE='IND-120NH-30-GP',
 PACK_TYPE='DISCRET-GB2',
 PART_NUMBER='068.1202N.M001',
 LOCATION='L7A1',
 SEC='1',
 CDS_LIB='w_hdl',
 CDS_PART_NAME='IND-120NH-30-GP_DISCRET-GB2-INA',
 PRIM_FILE='C:/<user>/w_hdl/ind#2d120nh#2d30#2dgp/chips/chips.prt';

PART_NAME
 L7A2 'IND-300NH-20-GP_DISCRET-GB1-INA':;

SECTION_NUMBER 1
 '@BASEBOARD_FAB2_LIB.BASEBOARD_FAB2(SCH_1):PAGE236_I178@W_HDL.IND-300NH-20-GP(CHIPS)':
 C_PATH='@baseboard_fab2_lib.baseboard_fab2(sch_1):page236_i178@w_hdl.\ind-300nh~
-20-gp\(chips)',
 P_PATH='@baseboard_fab2_lib.baseboard_fab2(sch_1):page236_i178@w_hdl.\ind-300nh~
-20-gp\(chips)',
 PATH='I178',
 DRAWING='@BASEBOARD_FAB2_LIB.BASEBOARD_FAB2(SCH_1):PAGE236',
 TYPE='IRMS=66A@DELTA_T<40C',
 PACK_SIZE='DCR=0.17MOHM',
 RATED='ISAT=33A@25C',
 ATTRIBUTE='300NH',
 SEC_TYPE='DISCRET-GB1',
 PHYS_PAGE='236',
 XY='(11375,4000)',
 ROT='1',
 VER='1',
 VALUE='IND-300NH-20-GP',
 PACK_TYPE='DISCRET-GB1',
 PART_NUMBER='068.3012N.M001',
 LOCATION='L7A2',
 SEC='1',
 CDS_LIB='w_hdl',
 CDS_PART_NAME='IND-300NH-20-GP_DISCRET-GB1-INA',
 PRIM_FILE='C:/<user>/w_hdl/ind#2d300nh#2d20#2dgp/chips/chips.prt';

PART_NAME
 L7A3 'IND-120NH-30-GP_DISCRET-GB2-INA':;

SECTION_NUMBER 1
 '@BASEBOARD_FAB2_LIB.BASEBOARD_FAB2(SCH_1):PAGE219_I158@W_HDL.IND-120NH-30-GP(CHIPS)':
 C_PATH='@baseboard_fab2_lib.baseboard_fab2(sch_1):page219_i158@w_hdl.\ind-120nh~
-30-gp\(chips)',
 P_PATH='@baseboard_fab2_lib.baseboard_fab2(sch_1):page219_i158@w_hdl.\ind-120nh~
-30-gp\(chips)',
 PATH='I158',
 DRAWING='@BASEBOARD_FAB2_LIB.BASEBOARD_FAB2(SCH_1):PAGE219',
 DS_VALUE='90NH',
 NEW_TYPE='IRMS=66A@DELTA_T<40C',
 NEW_RATED='DS_ISAT=134A@25C',
 NEW_PACK_SIZE='DCR=0.17MOHM',
 TYPE='IRMS=66A@DELTA_T<40C',
 PACK_SIZE='DCR=0.17MOHM',
 RATED='ISAT=94A@25C',
 ATTRIBUTE='120NH',
 BOM_SS='NOPOP',
 BOM_DS='068.9002N.1021',
 SEC_TYPE='DISCRET-GB2',
 PHYS_PAGE='219',
 XY='(3850,-400)',
 ROT='1',
 VER='1',
 VALUE='IND-120NH-30-GP',
 PACK_TYPE='DISCRET-GB2',
 PART_NUMBER='068.1202N.M001',
 LOCATION='L7A3',
 SEC='1',
 CDS_LIB='w_hdl',
 CDS_PART_NAME='IND-120NH-30-GP_DISCRET-GB2-INA',
 PRIM_FILE='C:/<user>/w_hdl/ind#2d120nh#2d30#2dgp/chips/chips.prt';

PART_NAME
 L7A4 'IND-300NH-20-GP_DISCRET-GB1-INA':;

SECTION_NUMBER 1
 '@BASEBOARD_FAB2_LIB.BASEBOARD_FAB2(SCH_1):PAGE236_I179@W_HDL.IND-300NH-20-GP(CHIPS)':
 C_PATH='@baseboard_fab2_lib.baseboard_fab2(sch_1):page236_i179@w_hdl.\ind-300nh~
-20-gp\(chips)',
 P_PATH='@baseboard_fab2_lib.baseboard_fab2(sch_1):page236_i179@w_hdl.\ind-300nh~
-20-gp\(chips)',
 PATH='I179',
 DRAWING='@BASEBOARD_FAB2_LIB.BASEBOARD_FAB2(SCH_1):PAGE236',
 TYPE='IRMS=66A@DELTA_T<40C',
 PACK_SIZE='DCR=0.17MOHM',
 RATED='ISAT=33A@25C',
 ATTRIBUTE='300NH',
 SEC_TYPE='DISCRET-GB1',
 PHYS_PAGE='236',
 XY='(11400,2300)',
 ROT='1',
 VER='1',
 VALUE='IND-300NH-20-GP',
 PACK_TYPE='DISCRET-GB1',
 PART_NUMBER='068.3012N.M001',
 LOCATION='L7A4',
 SEC='1',
 CDS_LIB='w_hdl',
 CDS_PART_NAME='IND-300NH-20-GP_DISCRET-GB1-INA',
 PRIM_FILE='C:/<user>/w_hdl/ind#2d300nh#2d20#2dgp/chips/chips.prt';

PART_NAME
 L7A5 'IND-100NH-35-GP_DISCRET-G8-INDA':;

SECTION_NUMBER 1
 '@BASEBOARD_FAB2_LIB.BASEBOARD_FAB2(SCH_1):PAGE220_I241@W_HDL.IND-100NH-35-GP(CHIPS)':
 C_PATH='@baseboard_fab2_lib.baseboard_fab2(sch_1):page220_i241@w_hdl.\ind-100nh~
-35-gp\(chips)',
 P_PATH='@baseboard_fab2_lib.baseboard_fab2(sch_1):page220_i241@w_hdl.\ind-100nh~
-35-gp\(chips)',
 PATH='I241',
 DRAWING='@BASEBOARD_FAB2_LIB.BASEBOARD_FAB2(SCH_1):PAGE220',
 TYPE='IRMS=29A@DELTA_T<45C',
 PACK_SIZE='DCR=0.16MOHM',
 RATED='ISAT=16A@25C',
 ATTRIBUTE='100NH',
 SEC_TYPE='DISCRET-G8',
 PHYS_PAGE='220',
 XY='(-1950,1325)',
 ROT='1',
 VER='1',
 VALUE='IND-100NH-35-GP',
 PACK_TYPE='DISCRET-G8',
 PART_NUMBER='068.1011N.M001',
 LOCATION='L7A5',
 SEC='1',
 CDS_LIB='w_hdl',
 CDS_PART_NAME='IND-100NH-35-GP_DISCRET-G8-INDA',
 PRIM_FILE='C:/<user>/w_hdl/ind#2d100nh#2d35#2dgp/chips/chips.prt';

PART_NAME
 L7B1 'INDUCTOR_SM-0.47UH,IND,E13358-A':
 ROOM='PVPP_KLM_VR',
 REUSE_ID='30';

SECTION_NUMBER 1
 '@BASEBOARD_FAB2_LIB.BASEBOARD_FAB2(SCH_1):PAGE232_I239@MSTR_DISCRETE.INDUCTOR(CHIPS)':
 C_PATH='@baseboard_fab2_lib.baseboard_fab2(sch_1):page232_i239@mstr_discrete.in~
ductor(chips)',
 P_PATH='@baseboard_fab2_lib.baseboard_fab2(sch_1):page232_i239@mstr_discrete.in~
ductor(chips)',
 PATH='I239',
 DRAWING='@BASEBOARD_FAB2_LIB.BASEBOARD_FAB2(SCH_1):PAGE232',
 TOLERANCE='1%',
 MATERIAL='IND',
 BOM_COST='PVPP_KLM_VR',
 PHYS_PAGE='232',
 REUSE_ID='30',
 XY='(-2550,3850)',
 ROT='0',
 VER='1',
 VALUE='0.47UH',
 PACK_TYPE='SM',
 PART_NUMBER='E13358-018',
 LOCATION='L7B1',
 ROOM='PVPP_KLM_VR',
 CDS_LIB='mstr_discrete',
 CDS_PART_NAME='INDUCTOR_SM-0.47UH,IND,E13358-A',
 PRIM_FILE='./archive_libs/mstr_discrete/inductor/chips/chips.prt';

PART_NAME
 L7C1 'IND-100NH-35-GP_DISCRET-G8-INDA':;

SECTION_NUMBER 1
 '@BASEBOARD_FAB2_LIB.BASEBOARD_FAB2(SCH_1):PAGE212_I142@W_HDL.IND-100NH-35-GP(CHIPS)':
 C_PATH='@baseboard_fab2_lib.baseboard_fab2(sch_1):page212_i142@w_hdl.\ind-100nh~
-35-gp\(chips)',
 P_PATH='@baseboard_fab2_lib.baseboard_fab2(sch_1):page212_i142@w_hdl.\ind-100nh~
-35-gp\(chips)',
 PATH='I142',
 DRAWING='@BASEBOARD_FAB2_LIB.BASEBOARD_FAB2(SCH_1):PAGE212',
 TYPE='IRMS=29A@DELTA_T<45C',
 PACK_SIZE='DCR=0.16MOHM',
 RATED='ISAT=16A@25C',
 ATTRIBUTE='100NH',
 SEC_TYPE='DISCRET-G8',
 PHYS_PAGE='212',
 XY='(225,2475)',
 ROT='1',
 VER='1',
 VALUE='IND-100NH-35-GP',
 PACK_TYPE='DISCRET-G8',
 PART_NUMBER='068.1011N.M001',
 LOCATION='L7C1',
 SEC='1',
 CDS_LIB='w_hdl',
 CDS_PART_NAME='IND-100NH-35-GP_DISCRET-G8-INDA',
 PRIM_FILE='C:/<user>/w_hdl/ind#2d100nh#2d35#2dgp/chips/chips.prt';

PART_NAME
 L7C2 'IND-150NH-56-GP_DISCRET-GA1-INA':;

SECTION_NUMBER 1
 '@BASEBOARD_FAB2_LIB.BASEBOARD_FAB2(SCH_1):PAGE212_I141@W_HDL.IND-150NH-56-GP(CHIPS)':
 C_PATH='@baseboard_fab2_lib.baseboard_fab2(sch_1):page212_i141@w_hdl.\ind-150nh~
-56-gp\(chips)',
 P_PATH='@baseboard_fab2_lib.baseboard_fab2(sch_1):page212_i141@w_hdl.\ind-150nh~
-56-gp\(chips)',
 PATH='I141',
 DRAWING='@BASEBOARD_FAB2_LIB.BASEBOARD_FAB2(SCH_1):PAGE212',
 TYPE='IRMS=66A@DELTA_T<40C',
 PACK_SIZE='DCR=0.17MOHM',
 RATED='ISAT=75A@25C',
 ATTRIBUTE='150NH',
 SEC_TYPE='DISCRET-GA1',
 PHYS_PAGE='212',
 XY='(3075,3675)',
 ROT='1',
 VER='1',
 VALUE='IND-150NH-56-GP',
 PACK_TYPE='DISCRET-GA1',
 PART_NUMBER='068.1512N.M001',
 LOCATION='L7C2',
 SEC='1',
 CDS_LIB='w_hdl',
 CDS_PART_NAME='IND-150NH-56-GP_DISCRET-GA1-INA',
 PRIM_FILE='C:/<user>/w_hdl/ind#2d150nh#2d56#2dgp/chips/chips.prt';

PART_NAME
 L7F1 'INDUCTOR_SM-0.47UH,IND,E13358-A':
 ROOM='PVPP_KLM_VR',
 REUSE_ID='30';

SECTION_NUMBER 1
 '@BASEBOARD_FAB2_LIB.BASEBOARD_FAB2(SCH_1):PAGE231_I178@MSTR_DISCRETE.INDUCTOR(CHIPS)':
 C_PATH='@baseboard_fab2_lib.baseboard_fab2(sch_1):page231_i178@mstr_discrete.in~
ductor(chips)',
 P_PATH='@baseboard_fab2_lib.baseboard_fab2(sch_1):page231_i178@mstr_discrete.in~
ductor(chips)',
 PATH='I178',
 DRAWING='@BASEBOARD_FAB2_LIB.BASEBOARD_FAB2(SCH_1):PAGE231',
 TOLERANCE='1%',
 MATERIAL='IND',
 BOM_COST='PVPP_KLM_VR',
 PHYS_PAGE='231',
 REUSE_ID='30',
 XY='(-1950,4100)',
 ROT='0',
 VER='1',
 VALUE='0.47UH',
 PACK_TYPE='SM',
 PART_NUMBER='E13358-018',
 LOCATION='L7F1',
 ROOM='PVPP_KLM_VR',
 CDS_LIB='mstr_discrete',
 CDS_PART_NAME='INDUCTOR_SM-0.47UH,IND,E13358-A',
 PRIM_FILE='./archive_libs/mstr_discrete/inductor/chips/chips.prt';

PART_NAME
 L7F2 'IND-100NH-35-GP_DISCRET-G8-INDA':;

SECTION_NUMBER 1
 '@BASEBOARD_FAB2_LIB.BASEBOARD_FAB2(SCH_1):PAGE217_I261@W_HDL.IND-100NH-35-GP(CHIPS)':
 C_PATH='@baseboard_fab2_lib.baseboard_fab2(sch_1):page217_i261@w_hdl.\ind-100nh~
-35-gp\(chips)',
 P_PATH='@baseboard_fab2_lib.baseboard_fab2(sch_1):page217_i261@w_hdl.\ind-100nh~
-35-gp\(chips)',
 PATH='I261',
 DRAWING='@BASEBOARD_FAB2_LIB.BASEBOARD_FAB2(SCH_1):PAGE217',
 TYPE='IRMS=29A@DELTA_T<45C',
 PACK_SIZE='DCR=0.16MOHM',
 RATED='ISAT=16A@25C',
 ATTRIBUTE='100NH',
 SEC_TYPE='DISCRET-G8',
 PHYS_PAGE='217',
 XY='(-200,925)',
 ROT='1',
 VER='1',
 VALUE='IND-100NH-35-GP',
 PACK_TYPE='DISCRET-G8',
 PART_NUMBER='068.1011N.M001',
 LOCATION='L7F2',
 SEC='1',
 CDS_LIB='w_hdl',
 CDS_PART_NAME='IND-100NH-35-GP_DISCRET-G8-INDA',
 PRIM_FILE='C:/<user>/w_hdl/ind#2d100nh#2d35#2dgp/chips/chips.prt';

PART_NAME
 L7G1 'IND-120NH-30-GP_DISCRET-GB2-INA':;

SECTION_NUMBER 1
 '@BASEBOARD_FAB2_LIB.BASEBOARD_FAB2(SCH_1):PAGE216_I153@W_HDL.IND-120NH-30-GP(CHIPS)':
 C_PATH='@baseboard_fab2_lib.baseboard_fab2(sch_1):page216_i153@w_hdl.\ind-120nh~
-30-gp\(chips)',
 P_PATH='@baseboard_fab2_lib.baseboard_fab2(sch_1):page216_i153@w_hdl.\ind-120nh~
-30-gp\(chips)',
 PATH='I153',
 DRAWING='@BASEBOARD_FAB2_LIB.BASEBOARD_FAB2(SCH_1):PAGE216',
 SS_ISAT='94A@25C',
 DS_VALUE='90NH',
 SS_VALUE='120NH',
 NEW_TYPE='IRMS=66A@DELTA_T<40C',
 NEW_RATED='DS_ISAT=134A@25C',
 NEW_PACK_SIZE='DCR=0.17MOHM',
 TYPE='IRMS=66A@DELTA_T<40C',
 PACK_SIZE='DCR=0.17MOHM',
 RATED='ISAT=94A@25C',
 ATTRIBUTE='120NH',
 BOM_SS='068.1202N.M001',
 BOM_DS='068.9002N.1021',
 SEC_TYPE='DISCRET-GB2',
 PHYS_PAGE='216',
 XY='(3900,2025)',
 ROT='1',
 VER='1',
 VALUE='IND-120NH-30-GP',
 PACK_TYPE='DISCRET-GB2',
 PART_NUMBER='068.1202N.M001',
 LOCATION='L7G1',
 SEC='1',
 CDS_LIB='w_hdl',
 CDS_PART_NAME='IND-120NH-30-GP_DISCRET-GB2-INA',
 PRIM_FILE='C:/<user>/w_hdl/ind#2d120nh#2d30#2dgp/chips/chips.prt';

PART_NAME
 L7G2 'IND-120NH-30-GP_DISCRET-GB2-INA':;

SECTION_NUMBER 1
 '@BASEBOARD_FAB2_LIB.BASEBOARD_FAB2(SCH_1):PAGE216_I155@W_HDL.IND-120NH-30-GP(CHIPS)':
 C_PATH='@baseboard_fab2_lib.baseboard_fab2(sch_1):page216_i155@w_hdl.\ind-120nh~
-30-gp\(chips)',
 P_PATH='@baseboard_fab2_lib.baseboard_fab2(sch_1):page216_i155@w_hdl.\ind-120nh~
-30-gp\(chips)',
 PATH='I155',
 DRAWING='@BASEBOARD_FAB2_LIB.BASEBOARD_FAB2(SCH_1):PAGE216',
 DS_VALUE='90NH',
 NEW_TYPE='IRMS=66A@DELTA_T<40C',
 NEW_RATED='DS_ISAT=134A@25C',
 NEW_PACK_SIZE='DCR=0.17MOHM',
 TYPE='IRMS=66A@DELTA_T<40C',
 PACK_SIZE='DCR=0.17MOHM',
 RATED='ISAT=94A@25C',
 ATTRIBUTE='120NH',
 BOM_SS='NOPOP',
 BOM_DS='068.9002N.1021',
 SEC_TYPE='DISCRET-GB2',
 PHYS_PAGE='216',
 XY='(3950,-350)',
 ROT='1',
 VER='1',
 VALUE='IND-120NH-30-GP',
 PACK_TYPE='DISCRET-GB2',
 PART_NUMBER='068.1202N.M001',
 LOCATION='L7G2',
 SEC='1',
 CDS_LIB='w_hdl',
 CDS_PART_NAME='IND-120NH-30-GP_DISCRET-GB2-INA',
 PRIM_FILE='C:/<user>/w_hdl/ind#2d120nh#2d30#2dgp/chips/chips.prt';

PART_NAME
 L8E1 'INDUCTOR_SM-2.2UH,IND,E98761-0A':;

SECTION_NUMBER 1
 '@BASEBOARD_FAB2_LIB.BASEBOARD_FAB2(SCH_1):PAGE241_I90@MSTR_DISCRETE.INDUCTOR(CHIPS)':
 C_PATH='@baseboard_fab2_lib.baseboard_fab2(sch_1):page241_i90@mstr_discrete.ind~
uctor(chips)',
 P_PATH='@baseboard_fab2_lib.baseboard_fab2(sch_1):page241_i90@mstr_discrete.ind~
uctor(chips)',
 PATH='I90',
 DRAWING='@BASEBOARD_FAB2_LIB.BASEBOARD_FAB2(SCH_1):PAGE241',
 MATERIAL='IND',
 PHYS_PAGE='241',
 XY='(2150,4050)',
 ROT='0',
 VER='1',
 VALUE='2.2UH',
 PACK_TYPE='SM',
 PART_NUMBER='E98761-003',
 LOCATION='L8E1',
 CDS_LIB='mstr_discrete',
 CDS_PART_NAME='INDUCTOR_SM-2.2UH,IND,E98761-0A',
 PRIM_FILE='./archive_libs/mstr_discrete/inductor/chips/chips.prt';

PART_NAME
 L8F1 'IND-1UH-361-GP_DISCRET-GC1-INDA':;

SECTION_NUMBER 1
 '@BASEBOARD_FAB2_LIB.BASEBOARD_FAB2(SCH_1):PAGE240_I188@W_HDL.IND-1UH-361-GP(CHIPS)':
 C_PATH='@baseboard_fab2_lib.baseboard_fab2(sch_1):page240_i188@w_hdl.\ind-1uh-3~
61-gp\(chips)',
 P_PATH='@baseboard_fab2_lib.baseboard_fab2(sch_1):page240_i188@w_hdl.\ind-1uh-3~
61-gp\(chips)',
 PATH='I188',
 DRAWING='@BASEBOARD_FAB2_LIB.BASEBOARD_FAB2(SCH_1):PAGE240',
 PACK_SIZE='DCR=4.6MOHM',
 RATED='ISAT=24A@25C',
 ATTRIBUTE='1.0UH',
 SEC_TYPE='DISCRET-GC1',
 PHYS_PAGE='240',
 XY='(10500,4050)',
 ROT='1',
 VER='1',
 VALUE='IND-1UH-361-GP',
 PACK_TYPE='DISCRET-GC1',
 PART_NUMBER='068.1R010.1781',
 LOCATION='L8F1',
 SEC='1',
 CDS_LIB='w_hdl',
 CDS_PART_NAME='IND-1UH-361-GP_DISCRET-GC1-INDA',
 PRIM_FILE='C:/<user>/w_hdl/ind#2d1uh#2d361#2dgp/chips/chips.prt';

PART_NAME
 L25W1 'IND-68NH-15-GP_DISCRET-GC1-INDA':
 GROUP='AST2500';

SECTION_NUMBER 1
 '@BASEBOARD_FAB2_LIB.BASEBOARD_FAB2(SCH_1):PAGE255_I76@W_HDL.IND-68NH-15-GP(CHIPS)':
 C_PATH='@baseboard_fab2_lib.baseboard_fab2(sch_1):page255_i76@w_hdl.\ind-68nh-1~
5-gp\(chips)',
 P_PATH='@baseboard_fab2_lib.baseboard_fab2(sch_1):page252_i76@w_hdl.\ind-68nh-1~
5-gp\(chips)',
 PATH='I76',
 DRAWING='@BASEBOARD_FAB2_LIB.BASEBOARD_FAB2(SCH_1):PAGE255',
 PACK_SIZE='DCR=800MOHM',
 RATED='300MA',
 ATTRIBUTE='68NH',
 SEC_TYPE='DISCRET-GC1',
 PHYS_PAGE='252',
 XY='(-3650,3600)',
 ROT='1',
 VER='1',
 VALUE='IND-68NH-15-GP',
 PACK_TYPE='DISCRET-GC1',
 PART_NUMBER='68.6803N.10D',
 LOCATION='L25W1',
 GROUP='AST2500',
 SEC='1',
 CDS_LIB='w_hdl',
 CDS_PART_NAME='IND-68NH-15-GP_DISCRET-GC1-INDA',
 PRIM_FILE='C:/<user>/w_hdl/ind#2d68nh#2d15#2dgp/chips/chips.prt';

PART_NAME
 L25W2 'IND-68NH-15-GP_DISCRET-GC1-INDA':
 GROUP='AST2500';

SECTION_NUMBER 1
 '@BASEBOARD_FAB2_LIB.BASEBOARD_FAB2(SCH_1):PAGE255_I77@W_HDL.IND-68NH-15-GP(CHIPS)':
 C_PATH='@baseboard_fab2_lib.baseboard_fab2(sch_1):page255_i77@w_hdl.\ind-68nh-1~
5-gp\(chips)',
 P_PATH='@baseboard_fab2_lib.baseboard_fab2(sch_1):page252_i77@w_hdl.\ind-68nh-1~
5-gp\(chips)',
 PATH='I77',
 DRAWING='@BASEBOARD_FAB2_LIB.BASEBOARD_FAB2(SCH_1):PAGE255',
 PACK_SIZE='DCR=800MOHM',
 RATED='300MA',
 ATTRIBUTE='68NH',
 SEC_TYPE='DISCRET-GC1',
 PHYS_PAGE='252',
 XY='(-3650,3750)',
 ROT='1',
 VER='1',
 VALUE='IND-68NH-15-GP',
 PACK_TYPE='DISCRET-GC1',
 PART_NUMBER='68.6803N.10D',
 LOCATION='L25W2',
 GROUP='AST2500',
 SEC='1',
 CDS_LIB='w_hdl',
 CDS_PART_NAME='IND-68NH-15-GP_DISCRET-GC1-INDA',
 PRIM_FILE='C:/<user>/w_hdl/ind#2d68nh#2d15#2dgp/chips/chips.prt';

PART_NAME
 L25W3 'IND-68NH-15-GP_DISCRET-GC1-INDA':
 GROUP='AST2500';

SECTION_NUMBER 1
 '@BASEBOARD_FAB2_LIB.BASEBOARD_FAB2(SCH_1):PAGE255_I78@W_HDL.IND-68NH-15-GP(CHIPS)':
 C_PATH='@baseboard_fab2_lib.baseboard_fab2(sch_1):page255_i78@w_hdl.\ind-68nh-1~
5-gp\(chips)',
 P_PATH='@baseboard_fab2_lib.baseboard_fab2(sch_1):page252_i78@w_hdl.\ind-68nh-1~
5-gp\(chips)',
 PATH='I78',
 DRAWING='@BASEBOARD_FAB2_LIB.BASEBOARD_FAB2(SCH_1):PAGE255',
 PACK_SIZE='DCR=800MOHM',
 RATED='300MA',
 ATTRIBUTE='68NH',
 SEC_TYPE='DISCRET-GC1',
 PHYS_PAGE='252',
 XY='(-3600,3900)',
 ROT='1',
 VER='1',
 VALUE='IND-68NH-15-GP',
 PACK_TYPE='DISCRET-GC1',
 PART_NUMBER='68.6803N.10D',
 LOCATION='L25W3',
 GROUP='AST2500',
 SEC='1',
 CDS_LIB='w_hdl',
 CDS_PART_NAME='IND-68NH-15-GP_DISCRET-GC1-INDA',
 PRIM_FILE='C:/<user>/w_hdl/ind#2d68nh#2d15#2dgp/chips/chips.prt';

PART_NAME
 L30W1 'CHOKE_4PIN_SM_B-67 OHM,EMPTY,7A':;

SECTION_NUMBER 1
 '@BASEBOARD_FAB2_LIB.BASEBOARD_FAB2(SCH_1):PAGE253_I16@MSTR_DISCRETE.CHOKE_4PIN(CHIPS)':
 C_PATH='@baseboard_fab2_lib.baseboard_fab2(sch_1):page253_i16@mstr_discrete.cho~
ke_4pin(chips)',
 P_PATH='@baseboard_fab2_lib.baseboard_fab2(sch_1):page253_i16@mstr_discrete.cho~
ke_4pin(chips)',
 PATH='I16',
 DRAWING='@BASEBOARD_FAB2_LIB.BASEBOARD_FAB2(SCH_1):PAGE253',
 SEC_TYPE='SM_B',
 MATERIAL='EMPTY',
 PHYS_PAGE='253',
 XY='(-5300,3400)',
 ROT='0',
 VER='2',
 VALUE='67 OHM',
 PACK_TYPE='SM_B',
 PART_NUMBER='752402-028',
 LOCATION='L30W1',
 SEC='1',
 CDS_LIB='mstr_discrete',
 CDS_PART_NAME='CHOKE_4PIN_SM_B-67 OHM,EMPTY,7A',
 PRIM_FILE='./archive_libs/mstr_discrete/choke_4pin/chips/chips.prt';

PART_NAME
 L30W2 'CHOKE_4PIN_SM_B-67 OHM,EMPTY,7A':;

SECTION_NUMBER 1
 '@BASEBOARD_FAB2_LIB.BASEBOARD_FAB2(SCH_1):PAGE253_I11@MSTR_DISCRETE.CHOKE_4PIN(CHIPS)':
 C_PATH='@baseboard_fab2_lib.baseboard_fab2(sch_1):page253_i11@mstr_discrete.cho~
ke_4pin(chips)',
 P_PATH='@baseboard_fab2_lib.baseboard_fab2(sch_1):page253_i11@mstr_discrete.cho~
ke_4pin(chips)',
 PATH='I11',
 DRAWING='@BASEBOARD_FAB2_LIB.BASEBOARD_FAB2(SCH_1):PAGE253',
 SEC_TYPE='SM_B',
 MATERIAL='EMPTY',
 PHYS_PAGE='253',
 XY='(-5300,2150)',
 ROT='0',
 VER='2',
 VALUE='67 OHM',
 PACK_TYPE='SM_B',
 PART_NUMBER='752402-028',
 LOCATION='L30W2',
 SEC='1',
 CDS_LIB='mstr_discrete',
 CDS_PART_NAME='CHOKE_4PIN_SM_B-67 OHM,EMPTY,7A',
 PRIM_FILE='./archive_libs/mstr_discrete/choke_4pin/chips/chips.prt';

PART_NAME
 Q1B1 'MOSFET_N_LCC3-BSZ019N03LS,NFETA':;

SECTION_NUMBER 1
 '@BASEBOARD_FAB2_LIB.BASEBOARD_FAB2(SCH_1):PAGE198_I86@MSTR_DISCRETE.MOSFET_N(CHIPS)':
 C_PATH='@baseboard_fab2_lib.baseboard_fab2(sch_1):page198_i86@mstr_discrete.mos~
fet_n(chips)',
 P_PATH='@baseboard_fab2_lib.baseboard_fab2(sch_1):page198_i86@mstr_discrete.mos~
fet_n(chips)',
 PATH='I86',
 DRAWING='@BASEBOARD_FAB2_LIB.BASEBOARD_FAB2(SCH_1):PAGE198',
 SEC_TYPE='LCC3',
 MATERIAL='NFET',
 PHYS_PAGE='198',
 XY='(-1375,1850)',
 ROT='2',
 VER='3',
 VALUE='BSZ019N03LS',
 PACK_TYPE='LCC3',
 PART_NUMBER='G26762-001',
 LOCATION='Q1B1',
 SEC='1',
 CDS_LIB='mstr_discrete',
 CDS_PART_NAME='MOSFET_N_LCC3-BSZ019N03LS,NFETA',
 PRIM_FILE='./archive_libs/mstr_discrete/mosfet_n/chips/chips.prt';

PART_NAME
 Q1D1 'FET_N_DUAL_SMLF-2N7002DW,FET,DA':
 ROOM='HOT_SWAP';

SECTION_NUMBER 1
 '@BASEBOARD_FAB2_LIB.BASEBOARD_FAB2(SCH_1):PAGE199_I86@MSTR_DISCRETE.FET_N_DUAL(CHIPS)':
 C_PATH='@baseboard_fab2_lib.baseboard_fab2(sch_1):page199_i86@mstr_discrete.fet~
_n_dual(chips)',
 P_PATH='@baseboard_fab2_lib.baseboard_fab2(sch_1):page199_i86@mstr_discrete.fet~
_n_dual(chips)',
 PATH='I86',
 DRAWING='@BASEBOARD_FAB2_LIB.BASEBOARD_FAB2(SCH_1):PAGE199',
 SIZE='1',
 SEC_TYPE='SMLF',
 MATERIAL='FET',
 PHYS_PAGE='199',
 XY='(-5875,275)',
 ROT='0',
 VER='5',
 VALUE='2N7002DW',
 PACK_TYPE='SMLF',
 PART_NUMBER='D24280-001',
 LOCATION='Q1D1',
 ROOM='HOT_SWAP',
 SEC='1',
 CDS_LIB='mstr_discrete',
 CDS_PART_NAME='FET_N_DUAL_SMLF-2N7002DW,FET,DA',
 PRIM_FILE='./archive_libs/mstr_discrete/fet_n_dual/chips/chips.prt';

SECTION_NUMBER 2
 '@BASEBOARD_FAB2_LIB.BASEBOARD_FAB2(SCH_1):PAGE199_I82@MSTR_DISCRETE.FET_N_DUAL(CHIPS)':
 C_PATH='@baseboard_fab2_lib.baseboard_fab2(sch_1):page199_i82@mstr_discrete.fet~
_n_dual(chips)',
 P_PATH='@baseboard_fab2_lib.baseboard_fab2(sch_1):page199_i82@mstr_discrete.fet~
_n_dual(chips)',
 PATH='I82',
 DRAWING='@BASEBOARD_FAB2_LIB.BASEBOARD_FAB2(SCH_1):PAGE199',
 SIZE='1',
 SEC_TYPE='SMLF',
 MATERIAL='FET',
 PHYS_PAGE='199',
 XY='(-6600,400)',
 ROT='0',
 VER='5',
 VALUE='2N7002DW',
 PACK_TYPE='SMLF',
 PART_NUMBER='D24280-001',
 LOCATION='Q1D1',
 ROOM='HOT_SWAP',
 SEC='2',
 CDS_LIB='mstr_discrete',
 CDS_PART_NAME='FET_N_DUAL_SMLF-2N7002DW,FET,DA',
 PRIM_FILE='./archive_libs/mstr_discrete/fet_n_dual/chips/chips.prt';

PART_NAME
 Q1D2 'FET_N_SOT23LF-2N7002,FET,C7925A':
 ROOM='HOT_SWAP';

SECTION_NUMBER 1
 '@BASEBOARD_FAB2_LIB.BASEBOARD_FAB2(SCH_1):PAGE200_I203@MSTR_DISCRETE.FET_N(CHIPS)':
 C_PATH='@baseboard_fab2_lib.baseboard_fab2(sch_1):page200_i203@mstr_discrete.fe~
t_n(chips)',
 P_PATH='@baseboard_fab2_lib.baseboard_fab2(sch_1):page200_i203@mstr_discrete.fe~
t_n(chips)',
 PATH='I203',
 DRAWING='@BASEBOARD_FAB2_LIB.BASEBOARD_FAB2(SCH_1):PAGE200',
 SEC_TYPE='SOT23LF',
 MATERIAL='FET',
 PHYS_PAGE='200',
 XY='(-3500,1300)',
 ROT='0',
 VER='8',
 VALUE='2N7002',
 PACK_TYPE='SOT23LF',
 PART_NUMBER='C79254-001',
 LOCATION='Q1D2',
 ROOM='HOT_SWAP',
 SEC='1',
 CDS_LIB='mstr_discrete',
 CDS_PART_NAME='FET_N_SOT23LF-2N7002,FET,C7925A',
 PRIM_FILE='./archive_libs/mstr_discrete/fet_n/chips/chips.prt';

PART_NAME
 Q1D3 'NPN_SM-MMBT3904,IC,C52245-001':
 ROOM='HOT_SWAP';

SECTION_NUMBER 1
 '@BASEBOARD_FAB2_LIB.BASEBOARD_FAB2(SCH_1):PAGE199_I58@MSTR_DISCRETE.NPN(CHIPS)':
 C_PATH='@baseboard_fab2_lib.baseboard_fab2(sch_1):page199_i58@mstr_discrete.npn~
(chips)',
 P_PATH='@baseboard_fab2_lib.baseboard_fab2(sch_1):page199_i58@mstr_discrete.npn~
(chips)',
 PATH='I58',
 DRAWING='@BASEBOARD_FAB2_LIB.BASEBOARD_FAB2(SCH_1):PAGE199',
 SEC_TYPE='SM',
 MATERIAL='IC',
 PHYS_PAGE='199',
 XY='(-525,1700)',
 ROT='0',
 VER='1',
 VALUE='MMBT3904',
 PACK_TYPE='SM',
 PART_NUMBER='C52245-001',
 LOCATION='Q1D3',
 ROOM='HOT_SWAP',
 SEC='1',
 CDS_LIB='mstr_discrete',
 CDS_PART_NAME='NPN_SM-MMBT3904,IC,C52245-001',
 PRIM_FILE='./archive_libs/mstr_discrete/npn/chips/chips.prt';

PART_NAME
 Q1E1 '2SB2907A-B0-00001-GP_DISCRET-GA':;

SECTION_NUMBER 1
 '@BASEBOARD_FAB2_LIB.BASEBOARD_FAB2(SCH_1):PAGE167_I94@W_HDL.2SB2907A-B0-00001-GP(CHIPS)':
 C_PATH='@baseboard_fab2_lib.baseboard_fab2(sch_1):page167_i94@w_hdl.\2sb2907a-b~
0-00001-gp\(chips)',
 P_PATH='@baseboard_fab2_lib.baseboard_fab2(sch_1):page167_i94@w_hdl.\2sb2907a-b~
0-00001-gp\(chips)',
 PATH='I94',
 DRAWING='@BASEBOARD_FAB2_LIB.BASEBOARD_FAB2(SCH_1):PAGE167',
 SEC_TYPE='DISCRET-GB1',
 PHYS_PAGE='167',
 XY='(-5700,3150)',
 ROT='4',
 VER='1',
 VALUE='2SB2907A-B0-00001-GP',
 PACK_TYPE='DISCRET-GB1',
 PART_NUMBER='006.02907.001A',
 LOCATION='Q1E1',
 SEC='1',
 CDS_LIB='w_hdl',
 CDS_PART_NAME='2SB2907A-B0-00001-GP_DISCRET-GA',
 PRIM_FILE='C:/<user>/w_hdl/2sb2907a#2db0#2d00001#2dgp/chips/chips.prt';

PART_NAME
 Q1F1 'NPN_SM-MMBT3904,IC,C52245-001':
 ROOM='PROC_SIDEBAND';

SECTION_NUMBER 1
 '@BASEBOARD_FAB2_LIB.BASEBOARD_FAB2(SCH_1):PAGE89_I53@MSTR_DISCRETE.NPN(CHIPS)':
 C_PATH='@baseboard_fab2_lib.baseboard_fab2(sch_1):page89_i53@mstr_discrete.npn(~
chips)',
 P_PATH='@baseboard_fab2_lib.baseboard_fab2(sch_1):page89_i53@mstr_discrete.npn(~
chips)',
 PATH='I53',
 DRAWING='@BASEBOARD_FAB2_LIB.BASEBOARD_FAB2(SCH_1):PAGE89',
 SEC_TYPE='SM',
 MATERIAL='IC',
 BOM_COST='PROC_SIDEBAND',
 PHYS_PAGE='89',
 XY='(-500,2725)',
 ROT='0',
 VER='1',
 VALUE='MMBT3904',
 PACK_TYPE='SM',
 PART_NUMBER='C52245-001',
 LOCATION='Q1F1',
 ROOM='PROC_SIDEBAND',
 SEC='1',
 CDS_LIB='mstr_discrete',
 CDS_PART_NAME='NPN_SM-MMBT3904,IC,C52245-001',
 PRIM_FILE='./archive_libs/mstr_discrete/npn/chips/chips.prt';

PART_NAME
 Q1L2 'FET_N_DUAL_SMLF-NTJD4001N,FET,A':
 ROOM='BMC';

SECTION_NUMBER 1
 '@BASEBOARD_FAB2_LIB.BASEBOARD_FAB2(SCH_1):PAGE155_I188@MSTR_DISCRETE.FET_N_DUAL(CHIPS)':
 C_PATH='@baseboard_fab2_lib.baseboard_fab2(sch_1):page155_i188@mstr_discrete.fe~
t_n_dual(chips)',
 P_PATH='@baseboard_fab2_lib.baseboard_fab2(sch_1):page155_i188@mstr_discrete.fe~
t_n_dual(chips)',
 PATH='I188',
 DRAWING='@BASEBOARD_FAB2_LIB.BASEBOARD_FAB2(SCH_1):PAGE155',
 SIZE='1',
 SEC_TYPE='SMLF',
 MATERIAL='FET',
 BOM_COST='BMC_DEBUG_HEADER',
 PHYS_PAGE='155',
 XY='(-4950,2625)',
 ROT='1',
 VER='5',
 VALUE='NTJD4001N',
 PACK_TYPE='SMLF',
 PART_NUMBER='E40049-001',
 LOCATION='Q1L2',
 ROOM='BMC',
 SEC='1',
 CDS_LIB='mstr_discrete',
 CDS_PART_NAME='FET_N_DUAL_SMLF-NTJD4001N,FET,A',
 PRIM_FILE='./archive_libs/mstr_discrete/fet_n_dual/chips/chips.prt';

SECTION_NUMBER 2
 '@BASEBOARD_FAB2_LIB.BASEBOARD_FAB2(SCH_1):PAGE155_I187@MSTR_DISCRETE.FET_N_DUAL(CHIPS)':
 C_PATH='@baseboard_fab2_lib.baseboard_fab2(sch_1):page155_i187@mstr_discrete.fe~
t_n_dual(chips)',
 P_PATH='@baseboard_fab2_lib.baseboard_fab2(sch_1):page155_i187@mstr_discrete.fe~
t_n_dual(chips)',
 PATH='I187',
 DRAWING='@BASEBOARD_FAB2_LIB.BASEBOARD_FAB2(SCH_1):PAGE155',
 SIZE='1',
 SEC_TYPE='SMLF',
 MATERIAL='FET',
 BOM_COST='BMC_DEBUG_HEADER',
 PHYS_PAGE='155',
 XY='(-5950,2100)',
 ROT='0',
 VER='5',
 VALUE='NTJD4001N',
 PACK_TYPE='SMLF',
 PART_NUMBER='E40049-001',
 LOCATION='Q1L2',
 ROOM='BMC',
 SEC='2',
 CDS_LIB='mstr_discrete',
 CDS_PART_NAME='FET_N_DUAL_SMLF-NTJD4001N,FET,A',
 PRIM_FILE='./archive_libs/mstr_discrete/fet_n_dual/chips/chips.prt';

PART_NAME
 Q1L3 'NPN_SM-MMBT3904,IC,C52245-001':
 ROOM='UART_MUX';

SECTION_NUMBER 1
 '@BASEBOARD_FAB2_LIB.BASEBOARD_FAB2(SCH_1):PAGE168_I8@MSTR_DISCRETE.NPN(CHIPS)':
 C_PATH='@baseboard_fab2_lib.baseboard_fab2(sch_1):page168_i8@mstr_discrete.npn(~
chips)',
 P_PATH='@baseboard_fab2_lib.baseboard_fab2(sch_1):page168_i8@mstr_discrete.npn(~
chips)',
 PATH='I8',
 DRAWING='@BASEBOARD_FAB2_LIB.BASEBOARD_FAB2(SCH_1):PAGE168',
 SEC_TYPE='SM',
 MATERIAL='IC',
 BOM_COST='DEBUG',
 PHYS_PAGE='168',
 XY='(-3450,2750)',
 ROT='0',
 VER='1',
 VALUE='MMBT3904',
 PACK_TYPE='SM',
 PART_NUMBER='C52245-001',
 LOCATION='Q1L3',
 ROOM='UART_MUX',
 SEC='1',
 CDS_LIB='mstr_discrete',
 CDS_PART_NAME='NPN_SM-MMBT3904,IC,C52245-001',
 PRIM_FILE='./archive_libs/mstr_discrete/npn/chips/chips.prt';

PART_NAME
 Q1L4 'FET_N_DUAL_SMLF-2N7002DW,FET,DA':
 ROOM='UART_MUX';

SECTION_NUMBER 1
 '@BASEBOARD_FAB2_LIB.BASEBOARD_FAB2(SCH_1):PAGE168_I19@MSTR_DISCRETE.FET_N_DUAL(CHIPS)':
 C_PATH='@baseboard_fab2_lib.baseboard_fab2(sch_1):page168_i19@mstr_discrete.fet~
_n_dual(chips)',
 P_PATH='@baseboard_fab2_lib.baseboard_fab2(sch_1):page168_i19@mstr_discrete.fet~
_n_dual(chips)',
 PATH='I19',
 DRAWING='@BASEBOARD_FAB2_LIB.BASEBOARD_FAB2(SCH_1):PAGE168',
 SIZE='1',
 SEC_TYPE='SMLF',
 MATERIAL='FET',
 BOM_COST='DEBUG',
 PHYS_PAGE='168',
 XY='(-2425,3000)',
 ROT='0',
 VER='5',
 VALUE='2N7002DW',
 PACK_TYPE='SMLF',
 PART_NUMBER='D24280-001',
 LOCATION='Q1L4',
 ROOM='UART_MUX',
 SEC='1',
 CDS_LIB='mstr_discrete',
 CDS_PART_NAME='FET_N_DUAL_SMLF-2N7002DW,FET,DA',
 PRIM_FILE='./archive_libs/mstr_discrete/fet_n_dual/chips/chips.prt';

SECTION_NUMBER 2
 '@BASEBOARD_FAB2_LIB.BASEBOARD_FAB2(SCH_1):PAGE168_I18@MSTR_DISCRETE.FET_N_DUAL(CHIPS)':
 C_PATH='@baseboard_fab2_lib.baseboard_fab2(sch_1):page168_i18@mstr_discrete.fet~
_n_dual(chips)',
 P_PATH='@baseboard_fab2_lib.baseboard_fab2(sch_1):page168_i18@mstr_discrete.fet~
_n_dual(chips)',
 PATH='I18',
 DRAWING='@BASEBOARD_FAB2_LIB.BASEBOARD_FAB2(SCH_1):PAGE168',
 SIZE='1',
 SEC_TYPE='SMLF',
 MATERIAL='FET',
 BOM_COST='DEBUG',
 PHYS_PAGE='168',
 XY='(-1525,4425)',
 ROT='0',
 VER='5',
 VALUE='2N7002DW',
 PACK_TYPE='SMLF',
 PART_NUMBER='D24280-001',
 LOCATION='Q1L4',
 ROOM='UART_MUX',
 SEC='2',
 CDS_LIB='mstr_discrete',
 CDS_PART_NAME='FET_N_DUAL_SMLF-2N7002DW,FET,DA',
 PRIM_FILE='./archive_libs/mstr_discrete/fet_n_dual/chips/chips.prt';

PART_NAME
 Q1P2 'FET_N_SOT23LF-2N7002,FET,C7925A':
 ROOM='HOT_SWAP';

SECTION_NUMBER 1
 '@BASEBOARD_FAB2_LIB.BASEBOARD_FAB2(SCH_1):PAGE196_I129@MSTR_DISCRETE.FET_N(CHIPS)':
 C_PATH='@baseboard_fab2_lib.baseboard_fab2(sch_1):page196_i129@mstr_discrete.fe~
t_n(chips)',
 P_PATH='@baseboard_fab2_lib.baseboard_fab2(sch_1):page196_i129@mstr_discrete.fe~
t_n(chips)',
 PATH='I129',
 DRAWING='@BASEBOARD_FAB2_LIB.BASEBOARD_FAB2(SCH_1):PAGE196',
 MATERIAL='FET',
 PHYS_PAGE='196',
 XY='(750,1750)',
 ROT='0',
 VER='8',
 VALUE='2N7002',
 PACK_TYPE='SOT23LF',
 PART_NUMBER='C79254-001',
 LOCATION='Q1P2',
 ROOM='HOT_SWAP',
 CDS_LIB='mstr_discrete',
 CDS_PART_NAME='FET_N_SOT23LF-2N7002,FET,C7925A',
 PRIM_FILE='./archive_libs/mstr_discrete/fet_n/chips/chips.prt';

PART_NAME
 Q1W1 'FET_N_SOT23LF-2N7002,FET,C7925A':
 ROOM='HOT_SWAP';

SECTION_NUMBER 1
 '@BASEBOARD_FAB2_LIB.BASEBOARD_FAB2(SCH_1):PAGE250_I29@MSTR_DISCRETE.FET_N(CHIPS)':
 C_PATH='@baseboard_fab2_lib.baseboard_fab2(sch_1):page250_i29@mstr_discrete.fet~
_n(chips)',
 P_PATH='@baseboard_fab2_lib.baseboard_fab2(sch_1):page250_i29@mstr_discrete.fet~
_n(chips)',
 PATH='I29',
 DRAWING='@BASEBOARD_FAB2_LIB.BASEBOARD_FAB2(SCH_1):PAGE250',
 SEC_TYPE='SOT23LF',
 MATERIAL='FET',
 PHYS_PAGE='250',
 XY='(-7350,5375)',
 ROT='0',
 VER='8',
 VALUE='2N7002',
 PACK_TYPE='SOT23LF',
 PART_NUMBER='C79254-001',
 LOCATION='Q1W1',
 ROOM='HOT_SWAP',
 SEC='1',
 CDS_LIB='mstr_discrete',
 CDS_PART_NAME='FET_N_SOT23LF-2N7002,FET,C7925A',
 PRIM_FILE='./archive_libs/mstr_discrete/fet_n/chips/chips.prt';

PART_NAME
 Q1W2 'FET_N_DUAL_SMLF-2N7002DW,FET,DA':
 ROOM='UART_MUX';

SECTION_NUMBER 1
 '@BASEBOARD_FAB2_LIB.BASEBOARD_FAB2(SCH_1):PAGE250_I24@MSTR_DISCRETE.FET_N_DUAL(CHIPS)':
 C_PATH='@baseboard_fab2_lib.baseboard_fab2(sch_1):page250_i24@mstr_discrete.fet~
_n_dual(chips)',
 P_PATH='@baseboard_fab2_lib.baseboard_fab2(sch_1):page250_i24@mstr_discrete.fet~
_n_dual(chips)',
 PATH='I24',
 DRAWING='@BASEBOARD_FAB2_LIB.BASEBOARD_FAB2(SCH_1):PAGE250',
 SIZE='1',
 SEC_TYPE='SMLF',
 MATERIAL='FET',
 BOM_COST='DEBUG',
 PHYS_PAGE='250',
 XY='(-7350,4250)',
 ROT='0',
 VER='5',
 VALUE='2N7002DW',
 PACK_TYPE='SMLF',
 PART_NUMBER='D24280-001',
 LOCATION='Q1W2',
 ROOM='UART_MUX',
 SEC='1',
 CDS_LIB='mstr_discrete',
 CDS_PART_NAME='FET_N_DUAL_SMLF-2N7002DW,FET,DA',
 PRIM_FILE='./archive_libs/mstr_discrete/fet_n_dual/chips/chips.prt';

SECTION_NUMBER 2
 '@BASEBOARD_FAB2_LIB.BASEBOARD_FAB2(SCH_1):PAGE250_I12@MSTR_DISCRETE.FET_N_DUAL(CHIPS)':
 C_PATH='@baseboard_fab2_lib.baseboard_fab2(sch_1):page250_i12@mstr_discrete.fet~
_n_dual(chips)',
 P_PATH='@baseboard_fab2_lib.baseboard_fab2(sch_1):page250_i12@mstr_discrete.fet~
_n_dual(chips)',
 PATH='I12',
 DRAWING='@BASEBOARD_FAB2_LIB.BASEBOARD_FAB2(SCH_1):PAGE250',
 SIZE='1',
 SEC_TYPE='SMLF',
 MATERIAL='FET',
 BOM_COST='DEBUG',
 PHYS_PAGE='250',
 XY='(-6525,4125)',
 ROT='0',
 VER='5',
 VALUE='2N7002DW',
 PACK_TYPE='SMLF',
 PART_NUMBER='D24280-001',
 LOCATION='Q1W2',
 ROOM='UART_MUX',
 SEC='2',
 CDS_LIB='mstr_discrete',
 CDS_PART_NAME='FET_N_DUAL_SMLF-2N7002DW,FET,DA',
 PRIM_FILE='./archive_libs/mstr_discrete/fet_n_dual/chips/chips.prt';

PART_NAME
 Q1W4 'FET_N_DUAL_SMLF-2N7002DW,FET,DA':
 ROOM='UART_MUX';

SECTION_NUMBER 1
 '@BASEBOARD_FAB2_LIB.BASEBOARD_FAB2(SCH_1):PAGE250_I3@MSTR_DISCRETE.FET_N_DUAL(CHIPS)':
 C_PATH='@baseboard_fab2_lib.baseboard_fab2(sch_1):page250_i3@mstr_discrete.fet_~
n_dual(chips)',
 P_PATH='@baseboard_fab2_lib.baseboard_fab2(sch_1):page250_i3@mstr_discrete.fet_~
n_dual(chips)',
 PATH='I3',
 DRAWING='@BASEBOARD_FAB2_LIB.BASEBOARD_FAB2(SCH_1):PAGE250',
 SIZE='1',
 SEC_TYPE='SMLF',
 MATERIAL='FET',
 BOM_COST='DEBUG',
 PHYS_PAGE='250',
 XY='(-7700,2450)',
 ROT='0',
 VER='5',
 VALUE='2N7002DW',
 PACK_TYPE='SMLF',
 PART_NUMBER='D24280-001',
 LOCATION='Q1W4',
 ROOM='UART_MUX',
 SEC='1',
 CDS_LIB='mstr_discrete',
 CDS_PART_NAME='FET_N_DUAL_SMLF-2N7002DW,FET,DA',
 PRIM_FILE='./archive_libs/mstr_discrete/fet_n_dual/chips/chips.prt';

SECTION_NUMBER 2
 '@BASEBOARD_FAB2_LIB.BASEBOARD_FAB2(SCH_1):PAGE250_I8@MSTR_DISCRETE.FET_N_DUAL(CHIPS)':
 C_PATH='@baseboard_fab2_lib.baseboard_fab2(sch_1):page250_i8@mstr_discrete.fet_~
n_dual(chips)',
 P_PATH='@baseboard_fab2_lib.baseboard_fab2(sch_1):page250_i8@mstr_discrete.fet_~
n_dual(chips)',
 PATH='I8',
 DRAWING='@BASEBOARD_FAB2_LIB.BASEBOARD_FAB2(SCH_1):PAGE250',
 SIZE='1',
 SEC_TYPE='SMLF',
 MATERIAL='FET',
 BOM_COST='DEBUG',
 PHYS_PAGE='250',
 XY='(-5925,2800)',
 ROT='0',
 VER='5',
 VALUE='2N7002DW',
 PACK_TYPE='SMLF',
 PART_NUMBER='D24280-001',
 LOCATION='Q1W4',
 ROOM='UART_MUX',
 SEC='2',
 CDS_LIB='mstr_discrete',
 CDS_PART_NAME='FET_N_DUAL_SMLF-2N7002DW,FET,DA',
 PRIM_FILE='./archive_libs/mstr_discrete/fet_n_dual/chips/chips.prt';

PART_NAME
 Q1W5 'FET_N_SOT23LF-2N7002,FET,C7925A':
 ROOM='HOT_SWAP';

SECTION_NUMBER 1
 '@BASEBOARD_FAB2_LIB.BASEBOARD_FAB2(SCH_1):PAGE199_I130@MSTR_DISCRETE.FET_N(CHIPS)':
 C_PATH='@baseboard_fab2_lib.baseboard_fab2(sch_1):page199_i130@mstr_discrete.fe~
t_n(chips)',
 P_PATH='@baseboard_fab2_lib.baseboard_fab2(sch_1):page199_i130@mstr_discrete.fe~
t_n(chips)',
 PATH='I130',
 DRAWING='@BASEBOARD_FAB2_LIB.BASEBOARD_FAB2(SCH_1):PAGE199',
 SEC_TYPE='SOT23LF',
 MATERIAL='FET',
 PHYS_PAGE='199',
 XY='(-3350,200)',
 ROT='0',
 VER='8',
 VALUE='2N7002',
 PACK_TYPE='SOT23LF',
 PART_NUMBER='C79254-001',
 LOCATION='Q1W5',
 ROOM='HOT_SWAP',
 SEC='1',
 CDS_LIB='mstr_discrete',
 CDS_PART_NAME='FET_N_SOT23LF-2N7002,FET,C7925A',
 PRIM_FILE='./archive_libs/mstr_discrete/fet_n/chips/chips.prt';

PART_NAME
 Q1W6 'NPN_SM-MMBT3904,IC,C52245-001':
 ROOM='PROC_SIDEBAND';

SECTION_NUMBER 1
 '@BASEBOARD_FAB2_LIB.BASEBOARD_FAB2(SCH_1):PAGE89_I55@MSTR_DISCRETE.NPN(CHIPS)':
 C_PATH='@baseboard_fab2_lib.baseboard_fab2(sch_1):page89_i55@mstr_discrete.npn(~
chips)',
 P_PATH='@baseboard_fab2_lib.baseboard_fab2(sch_1):page89_i55@mstr_discrete.npn(~
chips)',
 PATH='I55',
 DRAWING='@BASEBOARD_FAB2_LIB.BASEBOARD_FAB2(SCH_1):PAGE89',
 SEC_TYPE='SM',
 MATERIAL='IC',
 BOM_COST='PROC_SIDEBAND',
 PHYS_PAGE='89',
 XY='(-500,1550)',
 ROT='0',
 VER='1',
 VALUE='MMBT3904',
 PACK_TYPE='SM',
 PART_NUMBER='C52245-001',
 LOCATION='Q1W6',
 ROOM='PROC_SIDEBAND',
 SEC='1',
 CDS_LIB='mstr_discrete',
 CDS_PART_NAME='NPN_SM-MMBT3904,IC,C52245-001',
 PRIM_FILE='./archive_libs/mstr_discrete/npn/chips/chips.prt';

PART_NAME
 Q2P1 'FET_N_SOT23LF-2N7002,FET,C7925A':
 ROOM='PROC_SIDEBAND';

SECTION_NUMBER 1
 '@BASEBOARD_FAB2_LIB.BASEBOARD_FAB2(SCH_1):PAGE170_I58@MSTR_DISCRETE.FET_N(CHIPS)':
 C_PATH='@baseboard_fab2_lib.baseboard_fab2(sch_1):page170_i58@mstr_discrete.fet~
_n(chips)',
 P_PATH='@baseboard_fab2_lib.baseboard_fab2(sch_1):page170_i58@mstr_discrete.fet~
_n(chips)',
 PATH='I58',
 DRAWING='@BASEBOARD_FAB2_LIB.BASEBOARD_FAB2(SCH_1):PAGE170',
 SEC_TYPE='SOT23LF',
 MATERIAL='FET',
 BOM_COST='PROC_SIDEBAND',
 PHYS_PAGE='170',
 XY='(-4150,4225)',
 ROT='0',
 VER='8',
 VALUE='2N7002',
 PACK_TYPE='SOT23LF',
 PART_NUMBER='C79254-001',
 LOCATION='Q2P1',
 ROOM='PROC_SIDEBAND',
 SEC='1',
 CDS_LIB='mstr_discrete',
 CDS_PART_NAME='FET_N_SOT23LF-2N7002,FET,C7925A',
 PRIM_FILE='./archive_libs/mstr_discrete/fet_n/chips/chips.prt';

PART_NAME
 Q2T1 'NPN_SM-MMBT3904,IC,C52245-001':
 ROOM='PROC_SIDEBAND';

SECTION_NUMBER 1
 '@BASEBOARD_FAB2_LIB.BASEBOARD_FAB2(SCH_1):PAGE157_I330@MSTR_DISCRETE.NPN(CHIPS)':
 C_PATH='@baseboard_fab2_lib.baseboard_fab2(sch_1):page157_i330@mstr_discrete.np~
n(chips)',
 P_PATH='@baseboard_fab2_lib.baseboard_fab2(sch_1):page157_i330@mstr_discrete.np~
n(chips)',
 PATH='I330',
 DRAWING='@BASEBOARD_FAB2_LIB.BASEBOARD_FAB2(SCH_1):PAGE157',
 SEC_TYPE='SM',
 MATERIAL='IC',
 BOM_COST='PROC_SIDEBAND',
 PHYS_PAGE='157',
 XY='(-6200,775)',
 ROT='0',
 VER='1',
 VALUE='MMBT3904',
 PACK_TYPE='SM',
 PART_NUMBER='C52245-001',
 LOCATION='Q2T1',
 ROOM='PROC_SIDEBAND',
 SEC='1',
 CDS_LIB='mstr_discrete',
 CDS_PART_NAME='NPN_SM-MMBT3904,IC,C52245-001',
 PRIM_FILE='./archive_libs/mstr_discrete/npn/chips/chips.prt';

PART_NAME
 Q2T2 'FET_N_SOT23LF-2N7002,FET,C7925A':
 ROOM='PROC_SIDEBAND';

SECTION_NUMBER 1
 '@BASEBOARD_FAB2_LIB.BASEBOARD_FAB2(SCH_1):PAGE157_I340@MSTR_DISCRETE.FET_N(CHIPS)':
 C_PATH='@baseboard_fab2_lib.baseboard_fab2(sch_1):page157_i340@mstr_discrete.fe~
t_n(chips)',
 P_PATH='@baseboard_fab2_lib.baseboard_fab2(sch_1):page157_i340@mstr_discrete.fe~
t_n(chips)',
 PATH='I340',
 DRAWING='@BASEBOARD_FAB2_LIB.BASEBOARD_FAB2(SCH_1):PAGE157',
 SEC_TYPE='SOT23LF',
 MATERIAL='FET',
 BOM_COST='PROC_SIDEBAND',
 PHYS_PAGE='157',
 XY='(-5500,1100)',
 ROT='0',
 VER='8',
 VALUE='2N7002',
 PACK_TYPE='SOT23LF',
 PART_NUMBER='C79254-001',
 LOCATION='Q2T2',
 ROOM='PROC_SIDEBAND',
 SEC='1',
 CDS_LIB='mstr_discrete',
 CDS_PART_NAME='FET_N_SOT23LF-2N7002,FET,C7925A',
 PRIM_FILE='./archive_libs/mstr_discrete/fet_n/chips/chips.prt';

PART_NAME
 Q2U1 'FET_N_DUAL_SMLF-NTJD4001N,FET,A':
 ROOM='PROC_SIDEBAND';

SECTION_NUMBER 1
 '@BASEBOARD_FAB2_LIB.BASEBOARD_FAB2(SCH_1):PAGE95_I28@MSTR_DISCRETE.FET_N_DUAL(CHIPS)':
 C_PATH='@baseboard_fab2_lib.baseboard_fab2(sch_1):page95_i28@mstr_discrete.fet_~
n_dual(chips)',
 P_PATH='@baseboard_fab2_lib.baseboard_fab2(sch_1):page95_i28@mstr_discrete.fet_~
n_dual(chips)',
 PATH='I28',
 DRAWING='@BASEBOARD_FAB2_LIB.BASEBOARD_FAB2(SCH_1):PAGE95',
 SIZE='1',
 SEC_TYPE='SMLF',
 MATERIAL='FET',
 BOM_COST='PROC_SIDEBAND',
 PHYS_PAGE='95',
 XY='(-3100,2625)',
 ROT='0',
 VER='5',
 VALUE='NTJD4001N',
 PACK_TYPE='SMLF',
 PART_NUMBER='E40049-001',
 LOCATION='Q2U1',
 ROOM='PROC_SIDEBAND',
 SEC='1',
 CDS_LIB='mstr_discrete',
 CDS_PART_NAME='FET_N_DUAL_SMLF-NTJD4001N,FET,A',
 PRIM_FILE='./archive_libs/mstr_discrete/fet_n_dual/chips/chips.prt';

SECTION_NUMBER 2
 '@BASEBOARD_FAB2_LIB.BASEBOARD_FAB2(SCH_1):PAGE95_I113@MSTR_DISCRETE.FET_N_DUAL(CHIPS)':
 C_PATH='@baseboard_fab2_lib.baseboard_fab2(sch_1):page95_i113@mstr_discrete.fet~
_n_dual(chips)',
 P_PATH='@baseboard_fab2_lib.baseboard_fab2(sch_1):page95_i113@mstr_discrete.fet~
_n_dual(chips)',
 PATH='I113',
 DRAWING='@BASEBOARD_FAB2_LIB.BASEBOARD_FAB2(SCH_1):PAGE95',
 SIZE='1',
 SEC_TYPE='SMLF',
 MATERIAL='FET',
 BOM_COST='PROC_SIDEBAND',
 PHYS_PAGE='95',
 XY='(-3100,1950)',
 ROT='0',
 VER='5',
 VALUE='NTJD4001N',
 PACK_TYPE='SMLF',
 PART_NUMBER='E40049-001',
 LOCATION='Q2U1',
 ROOM='PROC_SIDEBAND',
 SEC='2',
 CDS_LIB='mstr_discrete',
 CDS_PART_NAME='FET_N_DUAL_SMLF-NTJD4001N,FET,A',
 PRIM_FILE='./archive_libs/mstr_discrete/fet_n_dual/chips/chips.prt';

PART_NAME
 Q3U1 'FET_N_DUAL_SMLF-NTJD4001N,FET,A':
 ROOM='PROC_SIDEBAND';

SECTION_NUMBER 1
 '@BASEBOARD_FAB2_LIB.BASEBOARD_FAB2(SCH_1):PAGE94_I49@MSTR_DISCRETE.FET_N_DUAL(CHIPS)':
 C_PATH='@baseboard_fab2_lib.baseboard_fab2(sch_1):page94_i49@mstr_discrete.fet_~
n_dual(chips)',
 P_PATH='@baseboard_fab2_lib.baseboard_fab2(sch_1):page94_i49@mstr_discrete.fet_~
n_dual(chips)',
 PATH='I49',
 DRAWING='@BASEBOARD_FAB2_LIB.BASEBOARD_FAB2(SCH_1):PAGE94',
 SIZE='1',
 SEC_TYPE='SMLF',
 MATERIAL='FET',
 PHYS_PAGE='94',
 XY='(-2150,1925)',
 ROT='0',
 VER='5',
 VALUE='NTJD4001N',
 PACK_TYPE='SMLF',
 PART_NUMBER='E40049-001',
 LOCATION='Q3U1',
 ROOM='PROC_SIDEBAND',
 SEC='1',
 CDS_LIB='mstr_discrete',
 CDS_PART_NAME='FET_N_DUAL_SMLF-NTJD4001N,FET,A',
 PRIM_FILE='./archive_libs/mstr_discrete/fet_n_dual/chips/chips.prt';

SECTION_NUMBER 2
 '@BASEBOARD_FAB2_LIB.BASEBOARD_FAB2(SCH_1):PAGE94_I89@MSTR_DISCRETE.FET_N_DUAL(CHIPS)':
 C_PATH='@baseboard_fab2_lib.baseboard_fab2(sch_1):page94_i89@mstr_discrete.fet_~
n_dual(chips)',
 P_PATH='@baseboard_fab2_lib.baseboard_fab2(sch_1):page94_i89@mstr_discrete.fet_~
n_dual(chips)',
 PATH='I89',
 DRAWING='@BASEBOARD_FAB2_LIB.BASEBOARD_FAB2(SCH_1):PAGE94',
 SIZE='1',
 SEC_TYPE='SMLF',
 MATERIAL='FET',
 PHYS_PAGE='94',
 XY='(-1425,2050)',
 ROT='0',
 VER='5',
 VALUE='NTJD4001N',
 PACK_TYPE='SMLF',
 PART_NUMBER='E40049-001',
 LOCATION='Q3U1',
 ROOM='PROC_SIDEBAND',
 SEC='2',
 CDS_LIB='mstr_discrete',
 CDS_PART_NAME='FET_N_DUAL_SMLF-NTJD4001N,FET,A',
 PRIM_FILE='./archive_libs/mstr_discrete/fet_n_dual/chips/chips.prt';

PART_NAME
 Q4B1 'FET_N_DUAL_SMLF-NTJD4001N,FET,A':
 ROOM='PROC_SIDEBAND';

SECTION_NUMBER 1
 '@BASEBOARD_FAB2_LIB.BASEBOARD_FAB2(SCH_1):PAGE94_I84@MSTR_DISCRETE.FET_N_DUAL(CHIPS)':
 C_PATH='@baseboard_fab2_lib.baseboard_fab2(sch_1):page94_i84@mstr_discrete.fet_~
n_dual(chips)',
 P_PATH='@baseboard_fab2_lib.baseboard_fab2(sch_1):page94_i84@mstr_discrete.fet_~
n_dual(chips)',
 PATH='I84',
 DRAWING='@BASEBOARD_FAB2_LIB.BASEBOARD_FAB2(SCH_1):PAGE94',
 SIZE='1',
 SEC_TYPE='SMLF',
 MATERIAL='FET',
 PHYS_PAGE='94',
 XY='(1175,875)',
 ROT='0',
 VER='5',
 VALUE='NTJD4001N',
 PACK_TYPE='SMLF',
 PART_NUMBER='E40049-001',
 LOCATION='Q4B1',
 ROOM='PROC_SIDEBAND',
 SEC='1',
 CDS_LIB='mstr_discrete',
 CDS_PART_NAME='FET_N_DUAL_SMLF-NTJD4001N,FET,A',
 PRIM_FILE='./archive_libs/mstr_discrete/fet_n_dual/chips/chips.prt';

SECTION_NUMBER 2
 '@BASEBOARD_FAB2_LIB.BASEBOARD_FAB2(SCH_1):PAGE94_I77@MSTR_DISCRETE.FET_N_DUAL(CHIPS)':
 C_PATH='@baseboard_fab2_lib.baseboard_fab2(sch_1):page94_i77@mstr_discrete.fet_~
n_dual(chips)',
 P_PATH='@baseboard_fab2_lib.baseboard_fab2(sch_1):page94_i77@mstr_discrete.fet_~
n_dual(chips)',
 PATH='I77',
 DRAWING='@BASEBOARD_FAB2_LIB.BASEBOARD_FAB2(SCH_1):PAGE94',
 SIZE='1',
 SEC_TYPE='SMLF',
 MATERIAL='FET',
 PHYS_PAGE='94',
 XY='(1900,1000)',
 ROT='0',
 VER='5',
 VALUE='NTJD4001N',
 PACK_TYPE='SMLF',
 PART_NUMBER='E40049-001',
 LOCATION='Q4B1',
 ROOM='PROC_SIDEBAND',
 SEC='2',
 CDS_LIB='mstr_discrete',
 CDS_PART_NAME='FET_N_DUAL_SMLF-NTJD4001N,FET,A',
 PRIM_FILE='./archive_libs/mstr_discrete/fet_n_dual/chips/chips.prt';

PART_NAME
 Q4B2 'FET_N_DUAL_SMLF-NTJD4001N,FET,A':
 ROOM='PROC_SIDEBAND';

SECTION_NUMBER 1
 '@BASEBOARD_FAB2_LIB.BASEBOARD_FAB2(SCH_1):PAGE95_I32@MSTR_DISCRETE.FET_N_DUAL(CHIPS)':
 C_PATH='@baseboard_fab2_lib.baseboard_fab2(sch_1):page95_i32@mstr_discrete.fet_~
n_dual(chips)',
 P_PATH='@baseboard_fab2_lib.baseboard_fab2(sch_1):page95_i32@mstr_discrete.fet_~
n_dual(chips)',
 PATH='I32',
 DRAWING='@BASEBOARD_FAB2_LIB.BASEBOARD_FAB2(SCH_1):PAGE95',
 SIZE='1',
 SEC_TYPE='SMLF',
 MATERIAL='FET',
 BOM_COST='PROC_SIDEBAND',
 PHYS_PAGE='95',
 XY='(-3100,1300)',
 ROT='0',
 VER='5',
 VALUE='NTJD4001N',
 PACK_TYPE='SMLF',
 PART_NUMBER='E40049-001',
 LOCATION='Q4B2',
 ROOM='PROC_SIDEBAND',
 SEC='1',
 CDS_LIB='mstr_discrete',
 CDS_PART_NAME='FET_N_DUAL_SMLF-NTJD4001N,FET,A',
 PRIM_FILE='./archive_libs/mstr_discrete/fet_n_dual/chips/chips.prt';

SECTION_NUMBER 2
 '@BASEBOARD_FAB2_LIB.BASEBOARD_FAB2(SCH_1):PAGE95_I33@MSTR_DISCRETE.FET_N_DUAL(CHIPS)':
 C_PATH='@baseboard_fab2_lib.baseboard_fab2(sch_1):page95_i33@mstr_discrete.fet_~
n_dual(chips)',
 P_PATH='@baseboard_fab2_lib.baseboard_fab2(sch_1):page95_i33@mstr_discrete.fet_~
n_dual(chips)',
 PATH='I33',
 DRAWING='@BASEBOARD_FAB2_LIB.BASEBOARD_FAB2(SCH_1):PAGE95',
 SIZE='1',
 SEC_TYPE='SMLF',
 MATERIAL='FET',
 BOM_COST='PROC_SIDEBAND',
 PHYS_PAGE='95',
 XY='(-3100,700)',
 ROT='0',
 VER='5',
 VALUE='NTJD4001N',
 PACK_TYPE='SMLF',
 PART_NUMBER='E40049-001',
 LOCATION='Q4B2',
 ROOM='PROC_SIDEBAND',
 SEC='2',
 CDS_LIB='mstr_discrete',
 CDS_PART_NAME='FET_N_DUAL_SMLF-NTJD4001N,FET,A',
 PRIM_FILE='./archive_libs/mstr_discrete/fet_n_dual/chips/chips.prt';

PART_NAME
 Q4U1 'FET_N_DUAL_SMLF-NTJD4001N,FET,A':
 ROOM='PROC_SIDEBAND';

SECTION_NUMBER 1
 '@BASEBOARD_FAB2_LIB.BASEBOARD_FAB2(SCH_1):PAGE94_I98@MSTR_DISCRETE.FET_N_DUAL(CHIPS)':
 C_PATH='@baseboard_fab2_lib.baseboard_fab2(sch_1):page94_i98@mstr_discrete.fet_~
n_dual(chips)',
 P_PATH='@baseboard_fab2_lib.baseboard_fab2(sch_1):page94_i98@mstr_discrete.fet_~
n_dual(chips)',
 PATH='I98',
 DRAWING='@BASEBOARD_FAB2_LIB.BASEBOARD_FAB2(SCH_1):PAGE94',
 SIZE='1',
 SEC_TYPE='SMLF',
 MATERIAL='FET',
 BOM_COST='PROC_SIDEBAND',
 PHYS_PAGE='94',
 XY='(175,3525)',
 ROT='0',
 VER='5',
 VALUE='NTJD4001N',
 PACK_TYPE='SMLF',
 PART_NUMBER='E40049-001',
 LOCATION='Q4U1',
 ROOM='PROC_SIDEBAND',
 SEC='1',
 CDS_LIB='mstr_discrete',
 CDS_PART_NAME='FET_N_DUAL_SMLF-NTJD4001N,FET,A',
 PRIM_FILE='./archive_libs/mstr_discrete/fet_n_dual/chips/chips.prt';

SECTION_NUMBER 2
 '@BASEBOARD_FAB2_LIB.BASEBOARD_FAB2(SCH_1):PAGE94_I102@MSTR_DISCRETE.FET_N_DUAL(CHIPS)':
 C_PATH='@baseboard_fab2_lib.baseboard_fab2(sch_1):page94_i102@mstr_discrete.fet~
_n_dual(chips)',
 P_PATH='@baseboard_fab2_lib.baseboard_fab2(sch_1):page94_i102@mstr_discrete.fet~
_n_dual(chips)',
 PATH='I102',
 DRAWING='@BASEBOARD_FAB2_LIB.BASEBOARD_FAB2(SCH_1):PAGE94',
 SIZE='1',
 SEC_TYPE='SMLF',
 MATERIAL='FET',
 BOM_COST='PROC_SIDEBAND',
 PHYS_PAGE='94',
 XY='(1400,3950)',
 ROT='0',
 VER='5',
 VALUE='NTJD4001N',
 PACK_TYPE='SMLF',
 PART_NUMBER='E40049-001',
 LOCATION='Q4U1',
 ROOM='PROC_SIDEBAND',
 SEC='2',
 CDS_LIB='mstr_discrete',
 CDS_PART_NAME='FET_N_DUAL_SMLF-NTJD4001N,FET,A',
 PRIM_FILE='./archive_libs/mstr_discrete/fet_n_dual/chips/chips.prt';

PART_NAME
 Q4W1 'FET_N_DUAL_SMLF-2N7002DW,FET,DA':
 ROOM='UART_MUX';

SECTION_NUMBER 1
 '@BASEBOARD_FAB2_LIB.BASEBOARD_FAB2(SCH_1):PAGE102_I102@MSTR_DISCRETE.FET_N_DUAL(CHIPS)':
 C_PATH='@baseboard_fab2_lib.baseboard_fab2(sch_1):page102_i102@mstr_discrete.fe~
t_n_dual(chips)',
 P_PATH='@baseboard_fab2_lib.baseboard_fab2(sch_1):page102_i102@mstr_discrete.fe~
t_n_dual(chips)',
 PATH='I102',
 DRAWING='@BASEBOARD_FAB2_LIB.BASEBOARD_FAB2(SCH_1):PAGE102',
 SIZE='1',
 SEC_TYPE='SMLF',
 MATERIAL='FET',
 BOM_COST='DEBUG',
 PHYS_PAGE='102',
 XY='(2350,4500)',
 ROT='3',
 VER='5',
 VALUE='2N7002DW',
 PACK_TYPE='SMLF',
 PART_NUMBER='D24280-001',
 LOCATION='Q4W1',
 ROOM='UART_MUX',
 SEC='1',
 CDS_LIB='mstr_discrete',
 CDS_PART_NAME='FET_N_DUAL_SMLF-2N7002DW,FET,DA',
 PRIM_FILE='./archive_libs/mstr_discrete/fet_n_dual/chips/chips.prt';

SECTION_NUMBER 2
 '@BASEBOARD_FAB2_LIB.BASEBOARD_FAB2(SCH_1):PAGE102_I101@MSTR_DISCRETE.FET_N_DUAL(CHIPS)':
 C_PATH='@baseboard_fab2_lib.baseboard_fab2(sch_1):page102_i101@mstr_discrete.fe~
t_n_dual(chips)',
 P_PATH='@baseboard_fab2_lib.baseboard_fab2(sch_1):page102_i101@mstr_discrete.fe~
t_n_dual(chips)',
 PATH='I101',
 DRAWING='@BASEBOARD_FAB2_LIB.BASEBOARD_FAB2(SCH_1):PAGE102',
 SIZE='1',
 SEC_TYPE='SMLF',
 MATERIAL='FET',
 BOM_COST='DEBUG',
 PHYS_PAGE='102',
 XY='(2000,4100)',
 ROT='3',
 VER='5',
 VALUE='2N7002DW',
 PACK_TYPE='SMLF',
 PART_NUMBER='D24280-001',
 LOCATION='Q4W1',
 ROOM='UART_MUX',
 SEC='2',
 CDS_LIB='mstr_discrete',
 CDS_PART_NAME='FET_N_DUAL_SMLF-2N7002DW,FET,DA',
 PRIM_FILE='./archive_libs/mstr_discrete/fet_n_dual/chips/chips.prt';

PART_NAME
 Q4W2 'FET_N_SOT23LF-2N7002,FET,C7925A':
 ROOM='HOT_SWAP';

SECTION_NUMBER 1
 '@BASEBOARD_FAB2_LIB.BASEBOARD_FAB2(SCH_1):PAGE102_I112@MSTR_DISCRETE.FET_N(CHIPS)':
 C_PATH='@baseboard_fab2_lib.baseboard_fab2(sch_1):page102_i112@mstr_discrete.fe~
t_n(chips)',
 P_PATH='@baseboard_fab2_lib.baseboard_fab2(sch_1):page102_i112@mstr_discrete.fe~
t_n(chips)',
 PATH='I112',
 DRAWING='@BASEBOARD_FAB2_LIB.BASEBOARD_FAB2(SCH_1):PAGE102',
 SEC_TYPE='SOT23LF',
 MATERIAL='FET',
 PHYS_PAGE='102',
 XY='(-950,1950)',
 ROT='0',
 VER='8',
 VALUE='2N7002',
 PACK_TYPE='SOT23LF',
 PART_NUMBER='C79254-001',
 LOCATION='Q4W2',
 ROOM='HOT_SWAP',
 SEC='1',
 CDS_LIB='mstr_discrete',
 CDS_PART_NAME='FET_N_SOT23LF-2N7002,FET,C7925A',
 PRIM_FILE='./archive_libs/mstr_discrete/fet_n/chips/chips.prt';

PART_NAME
 Q6W1 'FET_N_SOT23LF-2N7002,FET,C7925A':
 ROOM='HOT_SWAP';

SECTION_NUMBER 1
 '@BASEBOARD_FAB2_LIB.BASEBOARD_FAB2(SCH_1):PAGE200_I225@MSTR_DISCRETE.FET_N(CHIPS)':
 C_PATH='@baseboard_fab2_lib.baseboard_fab2(sch_1):page200_i225@mstr_discrete.fe~
t_n(chips)',
 P_PATH='@baseboard_fab2_lib.baseboard_fab2(sch_1):page200_i225@mstr_discrete.fe~
t_n(chips)',
 PATH='I225',
 DRAWING='@BASEBOARD_FAB2_LIB.BASEBOARD_FAB2(SCH_1):PAGE200',
 MATERIAL='FET',
 PHYS_PAGE='200',
 XY='(-1500,1675)',
 ROT='0',
 VER='8',
 VALUE='2N7002',
 PACK_TYPE='SOT23LF',
 PART_NUMBER='C79254-001',
 LOCATION='Q6W1',
 ROOM='HOT_SWAP',
 CDS_LIB='mstr_discrete',
 CDS_PART_NAME='FET_N_SOT23LF-2N7002,FET,C7925A',
 PRIM_FILE='./archive_libs/mstr_discrete/fet_n/chips/chips.prt';

PART_NAME
 Q6W2 'NPN_SM-MMBT3904,IC,C52245-001':
 ROOM='UART_MUX';

SECTION_NUMBER 1
 '@BASEBOARD_FAB2_LIB.BASEBOARD_FAB2(SCH_1):PAGE168_I47@MSTR_DISCRETE.NPN(CHIPS)':
 C_PATH='@baseboard_fab2_lib.baseboard_fab2(sch_1):page168_i47@mstr_discrete.npn~
(chips)',
 P_PATH='@baseboard_fab2_lib.baseboard_fab2(sch_1):page168_i47@mstr_discrete.npn~
(chips)',
 PATH='I47',
 DRAWING='@BASEBOARD_FAB2_LIB.BASEBOARD_FAB2(SCH_1):PAGE168',
 SEC_TYPE='SM',
 MATERIAL='IC',
 BOM_COST='DEBUG',
 PHYS_PAGE='168',
 XY='(-4000,1450)',
 ROT='0',
 VER='1',
 VALUE='MMBT3904',
 PACK_TYPE='SM',
 PART_NUMBER='C52245-001',
 LOCATION='Q6W2',
 ROOM='UART_MUX',
 SEC='1',
 CDS_LIB='mstr_discrete',
 CDS_PART_NAME='NPN_SM-MMBT3904,IC,C52245-001',
 PRIM_FILE='./archive_libs/mstr_discrete/npn/chips/chips.prt';

PART_NAME
 Q6W4 'FET_N_SOT23LF-2N7002,FET,C7925A':
 ROOM='HOT_SWAP';

SECTION_NUMBER 1
 '@BASEBOARD_FAB2_LIB.BASEBOARD_FAB2(SCH_1):PAGE168_I43@MSTR_DISCRETE.FET_N(CHIPS)':
 C_PATH='@baseboard_fab2_lib.baseboard_fab2(sch_1):page168_i43@mstr_discrete.fet~
_n(chips)',
 P_PATH='@baseboard_fab2_lib.baseboard_fab2(sch_1):page168_i43@mstr_discrete.fet~
_n(chips)',
 PATH='I43',
 DRAWING='@BASEBOARD_FAB2_LIB.BASEBOARD_FAB2(SCH_1):PAGE168',
 SEC_TYPE='SOT23LF',
 MATERIAL='FET',
 PHYS_PAGE='168',
 XY='(-1450,2650)',
 ROT='0',
 VER='8',
 VALUE='2N7002',
 PACK_TYPE='SOT23LF',
 PART_NUMBER='C79254-001',
 LOCATION='Q6W4',
 ROOM='HOT_SWAP',
 SEC='1',
 CDS_LIB='mstr_discrete',
 CDS_PART_NAME='FET_N_SOT23LF-2N7002,FET,C7925A',
 PRIM_FILE='./archive_libs/mstr_discrete/fet_n/chips/chips.prt';

PART_NAME
 Q7D1 'FET_N_SOT23LF-2N7002,FET,C7925A':
 ROOM='HOT_SWAP';

SECTION_NUMBER 1
 '@BASEBOARD_FAB2_LIB.BASEBOARD_FAB2(SCH_1):PAGE134_I14@MSTR_DISCRETE.FET_N(CHIPS)':
 C_PATH='@baseboard_fab2_lib.baseboard_fab2(sch_1):page134_i14@mstr_discrete.fet~
_n(chips)',
 P_PATH='@baseboard_fab2_lib.baseboard_fab2(sch_1):page134_i14@mstr_discrete.fet~
_n(chips)',
 PATH='I14',
 DRAWING='@BASEBOARD_FAB2_LIB.BASEBOARD_FAB2(SCH_1):PAGE134',
 MATERIAL='FET',
 PHYS_PAGE='134',
 XY='(-2875,4400)',
 ROT='0',
 VER='8',
 VALUE='2N7002',
 PACK_TYPE='SOT23LF',
 PART_NUMBER='C79254-001',
 LOCATION='Q7D1',
 ROOM='HOT_SWAP',
 CDS_LIB='mstr_discrete',
 CDS_PART_NAME='FET_N_SOT23LF-2N7002,FET,C7925A',
 PRIM_FILE='./archive_libs/mstr_discrete/fet_n/chips/chips.prt';

PART_NAME
 Q7E1 'FET_N_DUAL_SMLF-NTJD4001N,FET,A':
 ROOM='PROC_SIDEBAND';

SECTION_NUMBER 1
 '@BASEBOARD_FAB2_LIB.BASEBOARD_FAB2(SCH_1):PAGE94_I60@MSTR_DISCRETE.FET_N_DUAL(CHIPS)':
 C_PATH='@baseboard_fab2_lib.baseboard_fab2(sch_1):page94_i60@mstr_discrete.fet_~
n_dual(chips)',
 P_PATH='@baseboard_fab2_lib.baseboard_fab2(sch_1):page94_i60@mstr_discrete.fet_~
n_dual(chips)',
 PATH='I60',
 DRAWING='@BASEBOARD_FAB2_LIB.BASEBOARD_FAB2(SCH_1):PAGE94',
 SIZE='1',
 SEC_TYPE='SMLF',
 MATERIAL='FET',
 PHYS_PAGE='94',
 XY='(-2150,825)',
 ROT='0',
 VER='5',
 VALUE='NTJD4001N',
 PACK_TYPE='SMLF',
 PART_NUMBER='E40049-001',
 LOCATION='Q7E1',
 ROOM='PROC_SIDEBAND',
 SEC='1',
 CDS_LIB='mstr_discrete',
 CDS_PART_NAME='FET_N_DUAL_SMLF-NTJD4001N,FET,A',
 PRIM_FILE='./archive_libs/mstr_discrete/fet_n_dual/chips/chips.prt';

SECTION_NUMBER 2
 '@BASEBOARD_FAB2_LIB.BASEBOARD_FAB2(SCH_1):PAGE94_I64@MSTR_DISCRETE.FET_N_DUAL(CHIPS)':
 C_PATH='@baseboard_fab2_lib.baseboard_fab2(sch_1):page94_i64@mstr_discrete.fet_~
n_dual(chips)',
 P_PATH='@baseboard_fab2_lib.baseboard_fab2(sch_1):page94_i64@mstr_discrete.fet_~
n_dual(chips)',
 PATH='I64',
 DRAWING='@BASEBOARD_FAB2_LIB.BASEBOARD_FAB2(SCH_1):PAGE94',
 SIZE='1',
 SEC_TYPE='SMLF',
 MATERIAL='FET',
 PHYS_PAGE='94',
 XY='(-1425,950)',
 ROT='0',
 VER='5',
 VALUE='NTJD4001N',
 PACK_TYPE='SMLF',
 PART_NUMBER='E40049-001',
 LOCATION='Q7E1',
 ROOM='PROC_SIDEBAND',
 SEC='2',
 CDS_LIB='mstr_discrete',
 CDS_PART_NAME='FET_N_DUAL_SMLF-NTJD4001N,FET,A',
 PRIM_FILE='./archive_libs/mstr_discrete/fet_n_dual/chips/chips.prt';

PART_NAME
 Q7E2 'FET_N_DUAL_SMLF-NTJD4001N,FET,A':
 ROOM='PROC_SIDEBAND';

SECTION_NUMBER 1
 '@BASEBOARD_FAB2_LIB.BASEBOARD_FAB2(SCH_1):PAGE94_I69@MSTR_DISCRETE.FET_N_DUAL(CHIPS)':
 C_PATH='@baseboard_fab2_lib.baseboard_fab2(sch_1):page94_i69@mstr_discrete.fet_~
n_dual(chips)',
 P_PATH='@baseboard_fab2_lib.baseboard_fab2(sch_1):page94_i69@mstr_discrete.fet_~
n_dual(chips)',
 PATH='I69',
 DRAWING='@BASEBOARD_FAB2_LIB.BASEBOARD_FAB2(SCH_1):PAGE94',
 SIZE='1',
 SEC_TYPE='SMLF',
 MATERIAL='FET',
 PHYS_PAGE='94',
 XY='(1175,1975)',
 ROT='0',
 VER='5',
 VALUE='NTJD4001N',
 PACK_TYPE='SMLF',
 PART_NUMBER='E40049-001',
 LOCATION='Q7E2',
 ROOM='PROC_SIDEBAND',
 SEC='1',
 CDS_LIB='mstr_discrete',
 CDS_PART_NAME='FET_N_DUAL_SMLF-NTJD4001N,FET,A',
 PRIM_FILE='./archive_libs/mstr_discrete/fet_n_dual/chips/chips.prt';

SECTION_NUMBER 2
 '@BASEBOARD_FAB2_LIB.BASEBOARD_FAB2(SCH_1):PAGE94_I75@MSTR_DISCRETE.FET_N_DUAL(CHIPS)':
 C_PATH='@baseboard_fab2_lib.baseboard_fab2(sch_1):page94_i75@mstr_discrete.fet_~
n_dual(chips)',
 P_PATH='@baseboard_fab2_lib.baseboard_fab2(sch_1):page94_i75@mstr_discrete.fet_~
n_dual(chips)',
 PATH='I75',
 DRAWING='@BASEBOARD_FAB2_LIB.BASEBOARD_FAB2(SCH_1):PAGE94',
 SIZE='1',
 SEC_TYPE='SMLF',
 MATERIAL='FET',
 PHYS_PAGE='94',
 XY='(1900,2100)',
 ROT='0',
 VER='5',
 VALUE='NTJD4001N',
 PACK_TYPE='SMLF',
 PART_NUMBER='E40049-001',
 LOCATION='Q7E2',
 ROOM='PROC_SIDEBAND',
 SEC='2',
 CDS_LIB='mstr_discrete',
 CDS_PART_NAME='FET_N_DUAL_SMLF-NTJD4001N,FET,A',
 PRIM_FILE='./archive_libs/mstr_discrete/fet_n_dual/chips/chips.prt';

PART_NAME
 Q7E3 'FET_N_DUAL_SMLF-NTJD4001N,FET,A':
 ROOM='PROC_SIDEBAND';

SECTION_NUMBER 1
 '@BASEBOARD_FAB2_LIB.BASEBOARD_FAB2(SCH_1):PAGE95_I52@MSTR_DISCRETE.FET_N_DUAL(CHIPS)':
 C_PATH='@baseboard_fab2_lib.baseboard_fab2(sch_1):page95_i52@mstr_discrete.fet_~
n_dual(chips)',
 P_PATH='@baseboard_fab2_lib.baseboard_fab2(sch_1):page95_i52@mstr_discrete.fet_~
n_dual(chips)',
 PATH='I52',
 DRAWING='@BASEBOARD_FAB2_LIB.BASEBOARD_FAB2(SCH_1):PAGE95',
 SIZE='1',
 SEC_TYPE='SMLF',
 MATERIAL='FET',
 BOM_COST='PROC_SIDEBAND',
 PHYS_PAGE='95',
 XY='(-3100,3950)',
 ROT='0',
 VER='5',
 VALUE='NTJD4001N',
 PACK_TYPE='SMLF',
 PART_NUMBER='E40049-001',
 LOCATION='Q7E3',
 ROOM='PROC_SIDEBAND',
 SEC='1',
 CDS_LIB='mstr_discrete',
 CDS_PART_NAME='FET_N_DUAL_SMLF-NTJD4001N,FET,A',
 PRIM_FILE='./archive_libs/mstr_discrete/fet_n_dual/chips/chips.prt';

SECTION_NUMBER 2
 '@BASEBOARD_FAB2_LIB.BASEBOARD_FAB2(SCH_1):PAGE95_I51@MSTR_DISCRETE.FET_N_DUAL(CHIPS)':
 C_PATH='@baseboard_fab2_lib.baseboard_fab2(sch_1):page95_i51@mstr_discrete.fet_~
n_dual(chips)',
 P_PATH='@baseboard_fab2_lib.baseboard_fab2(sch_1):page95_i51@mstr_discrete.fet_~
n_dual(chips)',
 PATH='I51',
 DRAWING='@BASEBOARD_FAB2_LIB.BASEBOARD_FAB2(SCH_1):PAGE95',
 SIZE='1',
 SEC_TYPE='SMLF',
 MATERIAL='FET',
 BOM_COST='PROC_SIDEBAND',
 PHYS_PAGE='95',
 XY='(-3100,3275)',
 ROT='0',
 VER='5',
 VALUE='NTJD4001N',
 PACK_TYPE='SMLF',
 PART_NUMBER='E40049-001',
 LOCATION='Q7E3',
 ROOM='PROC_SIDEBAND',
 SEC='2',
 CDS_LIB='mstr_discrete',
 CDS_PART_NAME='FET_N_DUAL_SMLF-NTJD4001N,FET,A',
 PRIM_FILE='./archive_libs/mstr_discrete/fet_n_dual/chips/chips.prt';

PART_NAME
 Q7E4 'FET_N_SOT23LF-2N7002,FET,C7925A':
 ROOM='HOT_SWAP';

SECTION_NUMBER 1
 '@BASEBOARD_FAB2_LIB.BASEBOARD_FAB2(SCH_1):PAGE95_I122@MSTR_DISCRETE.FET_N(CHIPS)':
 C_PATH='@baseboard_fab2_lib.baseboard_fab2(sch_1):page95_i122@mstr_discrete.fet~
_n(chips)',
 P_PATH='@baseboard_fab2_lib.baseboard_fab2(sch_1):page95_i122@mstr_discrete.fet~
_n(chips)',
 PATH='I122',
 DRAWING='@BASEBOARD_FAB2_LIB.BASEBOARD_FAB2(SCH_1):PAGE95',
 MATERIAL='FET',
 PHYS_PAGE='95',
 XY='(2150,1350)',
 ROT='0',
 VER='8',
 VALUE='2N7002',
 PACK_TYPE='SOT23LF',
 PART_NUMBER='C79254-001',
 LOCATION='Q7E4',
 ROOM='HOT_SWAP',
 CDS_LIB='mstr_discrete',
 CDS_PART_NAME='FET_N_SOT23LF-2N7002,FET,C7925A',
 PRIM_FILE='./archive_libs/mstr_discrete/fet_n/chips/chips.prt';

PART_NAME
 Q7E5 'FET_N_DUAL_SMLF-NTJD4001N,FET,A':
 ROOM='HOT_EVENTS';

SECTION_NUMBER 1
 '@BASEBOARD_FAB2_LIB.BASEBOARD_FAB2(SCH_1):PAGE95_I111@MSTR_DISCRETE.FET_N_DUAL(CHIPS)':
 C_PATH='@baseboard_fab2_lib.baseboard_fab2(sch_1):page95_i111@mstr_discrete.fet~
_n_dual(chips)',
 P_PATH='@baseboard_fab2_lib.baseboard_fab2(sch_1):page95_i111@mstr_discrete.fet~
_n_dual(chips)',
 PATH='I111',
 DRAWING='@BASEBOARD_FAB2_LIB.BASEBOARD_FAB2(SCH_1):PAGE95',
 SIZE='1',
 SEC_TYPE='SMLF',
 MATERIAL='FET',
 BOM_COST='PROC_SIDEBAND',
 PHYS_PAGE='95',
 XY='(2475,4325)',
 ROT='0',
 VER='5',
 VALUE='NTJD4001N',
 PACK_TYPE='SMLF',
 PART_NUMBER='E40049-001',
 LOCATION='Q7E5',
 ROOM='HOT_EVENTS',
 SEC='1',
 CDS_LIB='mstr_discrete',
 CDS_PART_NAME='FET_N_DUAL_SMLF-NTJD4001N,FET,A',
 PRIM_FILE='./archive_libs/mstr_discrete/fet_n_dual/chips/chips.prt';

SECTION_NUMBER 2
 '@BASEBOARD_FAB2_LIB.BASEBOARD_FAB2(SCH_1):PAGE95_I59@MSTR_DISCRETE.FET_N_DUAL(CHIPS)':
 C_PATH='@baseboard_fab2_lib.baseboard_fab2(sch_1):page95_i59@mstr_discrete.fet_~
n_dual(chips)',
 P_PATH='@baseboard_fab2_lib.baseboard_fab2(sch_1):page95_i59@mstr_discrete.fet_~
n_dual(chips)',
 PATH='I59',
 DRAWING='@BASEBOARD_FAB2_LIB.BASEBOARD_FAB2(SCH_1):PAGE95',
 SIZE='1',
 SEC_TYPE='SMLF',
 MATERIAL='FET',
 BOM_COST='PROC_SIDEBAND',
 PHYS_PAGE='95',
 XY='(3050,4725)',
 ROT='0',
 VER='5',
 VALUE='NTJD4001N',
 PACK_TYPE='SMLF',
 PART_NUMBER='E40049-001',
 LOCATION='Q7E5',
 ROOM='HOT_EVENTS',
 SEC='2',
 CDS_LIB='mstr_discrete',
 CDS_PART_NAME='FET_N_DUAL_SMLF-NTJD4001N,FET,A',
 PRIM_FILE='./archive_libs/mstr_discrete/fet_n_dual/chips/chips.prt';

PART_NAME
 Q7E6 'FET_N_DUAL_SMLF-NTJD4001N,FET,A':
 ROOM='HOT_EVENTS';

SECTION_NUMBER 1
 '@BASEBOARD_FAB2_LIB.BASEBOARD_FAB2(SCH_1):PAGE95_I112@MSTR_DISCRETE.FET_N_DUAL(CHIPS)':
 C_PATH='@baseboard_fab2_lib.baseboard_fab2(sch_1):page95_i112@mstr_discrete.fet~
_n_dual(chips)',
 P_PATH='@baseboard_fab2_lib.baseboard_fab2(sch_1):page95_i112@mstr_discrete.fet~
_n_dual(chips)',
 PATH='I112',
 DRAWING='@BASEBOARD_FAB2_LIB.BASEBOARD_FAB2(SCH_1):PAGE95',
 SIZE='1',
 SEC_TYPE='SMLF',
 MATERIAL='FET',
 BOM_COST='PROC_SIDEBAND',
 PHYS_PAGE='95',
 XY='(2550,2875)',
 ROT='0',
 VER='5',
 VALUE='NTJD4001N',
 PACK_TYPE='SMLF',
 PART_NUMBER='E40049-001',
 LOCATION='Q7E6',
 ROOM='HOT_EVENTS',
 SEC='1',
 CDS_LIB='mstr_discrete',
 CDS_PART_NAME='FET_N_DUAL_SMLF-NTJD4001N,FET,A',
 PRIM_FILE='./archive_libs/mstr_discrete/fet_n_dual/chips/chips.prt';

SECTION_NUMBER 2
 '@BASEBOARD_FAB2_LIB.BASEBOARD_FAB2(SCH_1):PAGE95_I69@MSTR_DISCRETE.FET_N_DUAL(CHIPS)':
 C_PATH='@baseboard_fab2_lib.baseboard_fab2(sch_1):page95_i69@mstr_discrete.fet_~
n_dual(chips)',
 P_PATH='@baseboard_fab2_lib.baseboard_fab2(sch_1):page95_i69@mstr_discrete.fet_~
n_dual(chips)',
 PATH='I69',
 DRAWING='@BASEBOARD_FAB2_LIB.BASEBOARD_FAB2(SCH_1):PAGE95',
 SIZE='1',
 SEC_TYPE='SMLF',
 MATERIAL='FET',
 BOM_COST='PROC_SIDEBAND',
 PHYS_PAGE='95',
 XY='(3225,3250)',
 ROT='0',
 VER='5',
 VALUE='NTJD4001N',
 PACK_TYPE='SMLF',
 PART_NUMBER='E40049-001',
 LOCATION='Q7E6',
 ROOM='HOT_EVENTS',
 SEC='2',
 CDS_LIB='mstr_discrete',
 CDS_PART_NAME='FET_N_DUAL_SMLF-NTJD4001N,FET,A',
 PRIM_FILE='./archive_libs/mstr_discrete/fet_n_dual/chips/chips.prt';

PART_NAME
 Q7E7 'MOSFET_N_LCC3-BSZ019N03LS,NFETA':;

SECTION_NUMBER 1
 '@BASEBOARD_FAB2_LIB.BASEBOARD_FAB2(SCH_1):PAGE198_I88@MSTR_DISCRETE.MOSFET_N(CHIPS)':
 C_PATH='@baseboard_fab2_lib.baseboard_fab2(sch_1):page198_i88@mstr_discrete.mos~
fet_n(chips)',
 P_PATH='@baseboard_fab2_lib.baseboard_fab2(sch_1):page198_i88@mstr_discrete.mos~
fet_n(chips)',
 PATH='I88',
 DRAWING='@BASEBOARD_FAB2_LIB.BASEBOARD_FAB2(SCH_1):PAGE198',
 SEC_TYPE='LCC3',
 MATERIAL='NFET',
 PHYS_PAGE='198',
 XY='(-5325,1850)',
 ROT='2',
 VER='3',
 VALUE='BSZ019N03LS',
 PACK_TYPE='LCC3',
 PART_NUMBER='G26762-001',
 LOCATION='Q7E7',
 SEC='1',
 CDS_LIB='mstr_discrete',
 CDS_PART_NAME='MOSFET_N_LCC3-BSZ019N03LS,NFETA',
 PRIM_FILE='./archive_libs/mstr_discrete/mosfet_n/chips/chips.prt';

PART_NAME
 Q7E8 'FET_N_SOT23LF-2N7002,FET,C7925A':
 ROOM='HOT_SWAP';

SECTION_NUMBER 1
 '@BASEBOARD_FAB2_LIB.BASEBOARD_FAB2(SCH_1):PAGE95_I123@MSTR_DISCRETE.FET_N(CHIPS)':
 C_PATH='@baseboard_fab2_lib.baseboard_fab2(sch_1):page95_i123@mstr_discrete.fet~
_n(chips)',
 P_PATH='@baseboard_fab2_lib.baseboard_fab2(sch_1):page95_i123@mstr_discrete.fet~
_n(chips)',
 PATH='I123',
 DRAWING='@BASEBOARD_FAB2_LIB.BASEBOARD_FAB2(SCH_1):PAGE95',
 MATERIAL='FET',
 PHYS_PAGE='95',
 XY='(-3100,4550)',
 ROT='0',
 VER='8',
 VALUE='2N7002',
 PACK_TYPE='SOT23LF',
 PART_NUMBER='C79254-001',
 LOCATION='Q7E8',
 ROOM='HOT_SWAP',
 CDS_LIB='mstr_discrete',
 CDS_PART_NAME='FET_N_SOT23LF-2N7002,FET,C7925A',
 PRIM_FILE='./archive_libs/mstr_discrete/fet_n/chips/chips.prt';

PART_NAME
 Q8B1 'MOSFET_N_LCC3-BSZ019N03LS,NFETA':;

SECTION_NUMBER 1
 '@BASEBOARD_FAB2_LIB.BASEBOARD_FAB2(SCH_1):PAGE198_I87@MSTR_DISCRETE.MOSFET_N(CHIPS)':
 C_PATH='@baseboard_fab2_lib.baseboard_fab2(sch_1):page198_i87@mstr_discrete.mos~
fet_n(chips)',
 P_PATH='@baseboard_fab2_lib.baseboard_fab2(sch_1):page198_i87@mstr_discrete.mos~
fet_n(chips)',
 PATH='I87',
 DRAWING='@BASEBOARD_FAB2_LIB.BASEBOARD_FAB2(SCH_1):PAGE198',
 SEC_TYPE='LCC3',
 MATERIAL='NFET',
 PHYS_PAGE='198',
 XY='(-1600,3850)',
 ROT='2',
 VER='3',
 VALUE='BSZ019N03LS',
 PACK_TYPE='LCC3',
 PART_NUMBER='G26762-001',
 LOCATION='Q8B1',
 SEC='1',
 CDS_LIB='mstr_discrete',
 CDS_PART_NAME='MOSFET_N_LCC3-BSZ019N03LS,NFETA',
 PRIM_FILE='./archive_libs/mstr_discrete/mosfet_n/chips/chips.prt';

PART_NAME
 Q8D1 'NPN_DUAL_SSOPLF-MBT3904,XSTR,CA':
 ROOM='NV_DIMM';

SECTION_NUMBER 1
 '@BASEBOARD_FAB2_LIB.BASEBOARD_FAB2(SCH_1):PAGE89_I35@MSTR_DISCRETE.NPN_DUAL(CHIPS)':
 C_PATH='@baseboard_fab2_lib.baseboard_fab2(sch_1):page89_i35@mstr_discrete.npn_~
dual(chips)',
 P_PATH='@baseboard_fab2_lib.baseboard_fab2(sch_1):page89_i35@mstr_discrete.npn_~
dual(chips)',
 PATH='I35',
 DRAWING='@BASEBOARD_FAB2_LIB.BASEBOARD_FAB2(SCH_1):PAGE89',
 SIZE='1',
 SEC_TYPE='SSOPLF',
 MATERIAL='XSTR',
 BOM_COST='MEM_NV',
 PHYS_PAGE='89',
 XY='(1700,3700)',
 ROT='0',
 VER='1',
 VALUE='MBT3904',
 PACK_TYPE='SSOPLF',
 PART_NUMBER='C52264-001',
 LOCATION='Q8D1',
 ROOM='NV_DIMM',
 SEC='1',
 CDS_LIB='mstr_discrete',
 CDS_PART_NAME='NPN_DUAL_SSOPLF-MBT3904,XSTR,CA',
 PRIM_FILE='./archive_libs/mstr_discrete/npn_dual/chips/chips.prt';

SECTION_NUMBER 2
 '@BASEBOARD_FAB2_LIB.BASEBOARD_FAB2(SCH_1):PAGE89_I46@MSTR_DISCRETE.NPN_DUAL(CHIPS)':
 C_PATH='@baseboard_fab2_lib.baseboard_fab2(sch_1):page89_i46@mstr_discrete.npn_~
dual(chips)',
 P_PATH='@baseboard_fab2_lib.baseboard_fab2(sch_1):page89_i46@mstr_discrete.npn_~
dual(chips)',
 PATH='I46',
 DRAWING='@BASEBOARD_FAB2_LIB.BASEBOARD_FAB2(SCH_1):PAGE89',
 SIZE='1',
 SEC_TYPE='SSOPLF',
 MATERIAL='XSTR',
 BOM_COST='MEM_NV',
 PHYS_PAGE='89',
 XY='(2400,4175)',
 ROT='0',
 VER='1',
 VALUE='MBT3904',
 PACK_TYPE='SSOPLF',
 PART_NUMBER='C52264-001',
 LOCATION='Q8D1',
 ROOM='NV_DIMM',
 SEC='2',
 CDS_LIB='mstr_discrete',
 CDS_PART_NAME='NPN_DUAL_SSOPLF-MBT3904,XSTR,CA',
 PRIM_FILE='./archive_libs/mstr_discrete/npn_dual/chips/chips.prt';

PART_NAME
 Q8D2 'FET_N_SOT23LF-2N7002,FET,C7925A':
 ROOM='HOT_SWAP';

SECTION_NUMBER 1
 '@BASEBOARD_FAB2_LIB.BASEBOARD_FAB2(SCH_1):PAGE134_I15@MSTR_DISCRETE.FET_N(CHIPS)':
 C_PATH='@baseboard_fab2_lib.baseboard_fab2(sch_1):page134_i15@mstr_discrete.fet~
_n(chips)',
 P_PATH='@baseboard_fab2_lib.baseboard_fab2(sch_1):page134_i15@mstr_discrete.fet~
_n(chips)',
 PATH='I15',
 DRAWING='@BASEBOARD_FAB2_LIB.BASEBOARD_FAB2(SCH_1):PAGE134',
 MATERIAL='FET',
 PHYS_PAGE='134',
 XY='(700,4375)',
 ROT='0',
 VER='8',
 VALUE='2N7002',
 PACK_TYPE='SOT23LF',
 PART_NUMBER='C79254-001',
 LOCATION='Q8D2',
 ROOM='HOT_SWAP',
 CDS_LIB='mstr_discrete',
 CDS_PART_NAME='FET_N_SOT23LF-2N7002,FET,C7925A',
 PRIM_FILE='./archive_libs/mstr_discrete/fet_n/chips/chips.prt';

PART_NAME
 Q8E1 'FET_N_SOT23LF-2N7002,FET,C7925A':
 ROOM='SB';

SECTION_NUMBER 1
 '@BASEBOARD_FAB2_LIB.BASEBOARD_FAB2(SCH_1):PAGE136_I134@MSTR_DISCRETE.FET_N(CHIPS)':
 C_PATH='@baseboard_fab2_lib.baseboard_fab2(sch_1):page136_i134@mstr_discrete.fe~
t_n(chips)',
 P_PATH='@baseboard_fab2_lib.baseboard_fab2(sch_1):page136_i134@mstr_discrete.fe~
t_n(chips)',
 PATH='I134',
 DRAWING='@BASEBOARD_FAB2_LIB.BASEBOARD_FAB2(SCH_1):PAGE136',
 SEC_TYPE='SOT23LF',
 MATERIAL='FET',
 PHYS_PAGE='136',
 XY='(-550,1375)',
 ROT='0',
 VER='8',
 VALUE='2N7002',
 PACK_TYPE='SOT23LF',
 PART_NUMBER='C79254-001',
 LOCATION='Q8E1',
 ROOM='SB',
 SEC='1',
 CDS_LIB='mstr_discrete',
 CDS_PART_NAME='FET_N_SOT23LF-2N7002,FET,C7925A',
 PRIM_FILE='./archive_libs/mstr_discrete/fet_n/chips/chips.prt';

PART_NAME
 Q8E2 'FET_N_SOT23LF-2N7002,FET,C7925A':;

SECTION_NUMBER 1
 '@BASEBOARD_FAB2_LIB.BASEBOARD_FAB2(SCH_1):PAGE126_I13@MSTR_DISCRETE.FET_N(CHIPS)':
 C_PATH='@baseboard_fab2_lib.baseboard_fab2(sch_1):page126_i13@mstr_discrete.fet~
_n(chips)',
 P_PATH='@baseboard_fab2_lib.baseboard_fab2(sch_1):page126_i13@mstr_discrete.fet~
_n(chips)',
 PATH='I13',
 DRAWING='@BASEBOARD_FAB2_LIB.BASEBOARD_FAB2(SCH_1):PAGE126',
 SEC_TYPE='SOT23LF',
 MATERIAL='FET',
 PHYS_PAGE='126',
 XY='(-3625,3925)',
 ROT='0',
 VER='8',
 VALUE='2N7002',
 PACK_TYPE='SOT23LF',
 PART_NUMBER='C79254-001',
 LOCATION='Q8E2',
 SEC='1',
 CDS_LIB='mstr_discrete',
 CDS_PART_NAME='FET_N_SOT23LF-2N7002,FET,C7925A',
 PRIM_FILE='./archive_libs/mstr_discrete/fet_n/chips/chips.prt';

PART_NAME
 Q8F1 'FET_N_SOT23LF-2N7002,FET,C7925A':
 GROUP='NI_BIOS_ROM2',
 ROOM='SB_BMC_SPI_MUX';

SECTION_NUMBER 1
 '@BASEBOARD_FAB2_LIB.BASEBOARD_FAB2(SCH_1):PAGE154_I126@MSTR_DISCRETE.FET_N(CHIPS)':
 C_PATH='@baseboard_fab2_lib.baseboard_fab2(sch_1):page154_i126@mstr_discrete.fe~
t_n(chips)',
 P_PATH='@baseboard_fab2_lib.baseboard_fab2(sch_1):page154_i126@mstr_discrete.fe~
t_n(chips)',
 PATH='I126',
 DRAWING='@BASEBOARD_FAB2_LIB.BASEBOARD_FAB2(SCH_1):PAGE154',
 SEC_TYPE='SOT23LF',
 MATERIAL='FET',
 BOM_COST='MIO_BIOS_MEM',
 PHYS_PAGE='154',
 XY='(-3100,1575)',
 ROT='0',
 VER='8',
 VALUE='2N7002',
 PACK_TYPE='SOT23LF',
 PART_NUMBER='C79254-001',
 LOCATION='Q8F1',
 ROOM='SB_BMC_SPI_MUX',
 GROUP='NI_BIOS_ROM2',
 SEC='1',
 CDS_LIB='mstr_discrete',
 CDS_PART_NAME='FET_N_SOT23LF-2N7002,FET,C7925A',
 PRIM_FILE='./archive_libs/mstr_discrete/fet_n/chips/chips.prt';

PART_NAME
 Q8F2 'FET_N_SOT23LF-2N7002,FET,C7925A':
 ROOM='PROC_SIDEBAND';

SECTION_NUMBER 1
 '@BASEBOARD_FAB2_LIB.BASEBOARD_FAB2(SCH_1):PAGE170_I67@MSTR_DISCRETE.FET_N(CHIPS)':
 C_PATH='@baseboard_fab2_lib.baseboard_fab2(sch_1):page170_i67@mstr_discrete.fet~
_n(chips)',
 P_PATH='@baseboard_fab2_lib.baseboard_fab2(sch_1):page170_i67@mstr_discrete.fet~
_n(chips)',
 PATH='I67',
 DRAWING='@BASEBOARD_FAB2_LIB.BASEBOARD_FAB2(SCH_1):PAGE170',
 SEC_TYPE='SOT23LF',
 MATERIAL='FET',
 BOM_COST='PROC_SIDEBAND',
 PHYS_PAGE='170',
 XY='(-2950,1900)',
 ROT='0',
 VER='8',
 VALUE='2N7002',
 PACK_TYPE='SOT23LF',
 PART_NUMBER='C79254-001',
 LOCATION='Q8F2',
 ROOM='PROC_SIDEBAND',
 SEC='1',
 CDS_LIB='mstr_discrete',
 CDS_PART_NAME='FET_N_SOT23LF-2N7002,FET,C7925A',
 PRIM_FILE='./archive_libs/mstr_discrete/fet_n/chips/chips.prt';

PART_NAME
 Q8G1 'MOSFET_N_LCC3-BSZ019N03LS,NFETA':;

SECTION_NUMBER 1
 '@BASEBOARD_FAB2_LIB.BASEBOARD_FAB2(SCH_1):PAGE198_I85@MSTR_DISCRETE.MOSFET_N(CHIPS)':
 C_PATH='@baseboard_fab2_lib.baseboard_fab2(sch_1):page198_i85@mstr_discrete.mos~
fet_n(chips)',
 P_PATH='@baseboard_fab2_lib.baseboard_fab2(sch_1):page198_i85@mstr_discrete.mos~
fet_n(chips)',
 PATH='I85',
 DRAWING='@BASEBOARD_FAB2_LIB.BASEBOARD_FAB2(SCH_1):PAGE198',
 SEC_TYPE='LCC3',
 MATERIAL='NFET',
 PHYS_PAGE='198',
 XY='(-5650,3900)',
 ROT='2',
 VER='3',
 VALUE='BSZ019N03LS',
 PACK_TYPE='LCC3',
 PART_NUMBER='G26762-001',
 LOCATION='Q8G1',
 SEC='1',
 CDS_LIB='mstr_discrete',
 CDS_PART_NAME='MOSFET_N_LCC3-BSZ019N03LS,NFETA',
 PRIM_FILE='./archive_libs/mstr_discrete/mosfet_n/chips/chips.prt';

PART_NAME
 Q8W1 'NPN_DUAL_SSOPLF-MBT3904,XSTR,CA':
 ROOM='NV_DIMM';

SECTION_NUMBER 1
 '@BASEBOARD_FAB2_LIB.BASEBOARD_FAB2(SCH_1):PAGE89_I52@MSTR_DISCRETE.NPN_DUAL(CHIPS)':
 C_PATH='@baseboard_fab2_lib.baseboard_fab2(sch_1):page89_i52@mstr_discrete.npn_~
dual(chips)',
 P_PATH='@baseboard_fab2_lib.baseboard_fab2(sch_1):page89_i52@mstr_discrete.npn_~
dual(chips)',
 PATH='I52',
 DRAWING='@BASEBOARD_FAB2_LIB.BASEBOARD_FAB2(SCH_1):PAGE89',
 SIZE='1',
 SEC_TYPE='SSOPLF',
 MATERIAL='XSTR',
 BOM_COST='MEM_NV',
 PHYS_PAGE='89',
 XY='(2150,2500)',
 ROT='0',
 VER='1',
 VALUE='MBT3904',
 PACK_TYPE='SSOPLF',
 PART_NUMBER='C52264-001',
 LOCATION='Q8W1',
 ROOM='NV_DIMM',
 SEC='1',
 CDS_LIB='mstr_discrete',
 CDS_PART_NAME='NPN_DUAL_SSOPLF-MBT3904,XSTR,CA',
 PRIM_FILE='./archive_libs/mstr_discrete/npn_dual/chips/chips.prt';

SECTION_NUMBER 2
 '@BASEBOARD_FAB2_LIB.BASEBOARD_FAB2(SCH_1):PAGE89_I51@MSTR_DISCRETE.NPN_DUAL(CHIPS)':
 C_PATH='@baseboard_fab2_lib.baseboard_fab2(sch_1):page89_i51@mstr_discrete.npn_~
dual(chips)',
 P_PATH='@baseboard_fab2_lib.baseboard_fab2(sch_1):page89_i51@mstr_discrete.npn_~
dual(chips)',
 PATH='I51',
 DRAWING='@BASEBOARD_FAB2_LIB.BASEBOARD_FAB2(SCH_1):PAGE89',
 SIZE='1',
 SEC_TYPE='SSOPLF',
 MATERIAL='XSTR',
 BOM_COST='MEM_NV',
 PHYS_PAGE='89',
 XY='(2900,2975)',
 ROT='0',
 VER='1',
 VALUE='MBT3904',
 PACK_TYPE='SSOPLF',
 PART_NUMBER='C52264-001',
 LOCATION='Q8W1',
 ROOM='NV_DIMM',
 SEC='2',
 CDS_LIB='mstr_discrete',
 CDS_PART_NAME='NPN_DUAL_SSOPLF-MBT3904,XSTR,CA',
 PRIM_FILE='./archive_libs/mstr_discrete/npn_dual/chips/chips.prt';

PART_NAME
 Q9A1 'NPN_DUAL_SSOPLF-MBT3904,EMPTY,A':
 ROOM='DEBUG';

SECTION_NUMBER 1
 '@BASEBOARD_FAB2_LIB.BASEBOARD_FAB2(SCH_1):PAGE111_I94@MSTR_DISCRETE.NPN_DUAL(CHIPS)':
 C_PATH='@baseboard_fab2_lib.baseboard_fab2(sch_1):page111_i94@mstr_discrete.npn~
_dual(chips)',
 P_PATH='@baseboard_fab2_lib.baseboard_fab2(sch_1):page111_i94@mstr_discrete.npn~
_dual(chips)',
 PATH='I94',
 DRAWING='@BASEBOARD_FAB2_LIB.BASEBOARD_FAB2(SCH_1):PAGE111',
 SIZE='1',
 SEC_TYPE='SSOPLF',
 MATERIAL='EMPTY',
 PHYS_PAGE='111',
 XY='(-1150,2275)',
 ROT='0',
 VER='1',
 VALUE='MBT3904',
 PACK_TYPE='SSOPLF',
 PART_NUMBER='C52264-001',
 LOCATION='Q9A1',
 ROOM='DEBUG',
 SEC='1',
 CDS_LIB='mstr_discrete',
 CDS_PART_NAME='NPN_DUAL_SSOPLF-MBT3904,EMPTY,A',
 PRIM_FILE='./archive_libs/mstr_discrete/npn_dual/chips/chips.prt';

SECTION_NUMBER 2
 '@BASEBOARD_FAB2_LIB.BASEBOARD_FAB2(SCH_1):PAGE111_I93@MSTR_DISCRETE.NPN_DUAL(CHIPS)':
 C_PATH='@baseboard_fab2_lib.baseboard_fab2(sch_1):page111_i93@mstr_discrete.npn~
_dual(chips)',
 P_PATH='@baseboard_fab2_lib.baseboard_fab2(sch_1):page111_i93@mstr_discrete.npn~
_dual(chips)',
 PATH='I93',
 DRAWING='@BASEBOARD_FAB2_LIB.BASEBOARD_FAB2(SCH_1):PAGE111',
 SIZE='1',
 SEC_TYPE='SSOPLF',
 MATERIAL='EMPTY',
 PHYS_PAGE='111',
 XY='(-2150,2325)',
 ROT='0',
 VER='2',
 VALUE='MBT3904',
 PACK_TYPE='SSOPLF',
 PART_NUMBER='C52264-001',
 LOCATION='Q9A1',
 ROOM='DEBUG',
 SEC='2',
 CDS_LIB='mstr_discrete',
 CDS_PART_NAME='NPN_DUAL_SSOPLF-MBT3904,EMPTY,A',
 PRIM_FILE='./archive_libs/mstr_discrete/npn_dual/chips/chips.prt';

PART_NAME
 Q9A2 'FET_N_DUAL_SMLF-NTJD4001N,FET,A':
 ROOM='SB';

SECTION_NUMBER 1
 '@BASEBOARD_FAB2_LIB.BASEBOARD_FAB2(SCH_1):PAGE119_I175@MSTR_DISCRETE.FET_N_DUAL(CHIPS)':
 C_PATH='@baseboard_fab2_lib.baseboard_fab2(sch_1):page119_i175@mstr_discrete.fe~
t_n_dual(chips)',
 P_PATH='@baseboard_fab2_lib.baseboard_fab2(sch_1):page119_i175@mstr_discrete.fe~
t_n_dual(chips)',
 PATH='I175',
 DRAWING='@BASEBOARD_FAB2_LIB.BASEBOARD_FAB2(SCH_1):PAGE119',
 SIZE='1',
 SEC_TYPE='SMLF',
 MATERIAL='FET',
 BOM_COST='SB',
 PHYS_PAGE='119',
 XY='(-4725,725)',
 ROT='0',
 VER='5',
 VALUE='NTJD4001N',
 PACK_TYPE='SMLF',
 PART_NUMBER='E40049-001',
 LOCATION='Q9A2',
 ROOM='SB',
 SEC='1',
 CDS_LIB='mstr_discrete',
 CDS_PART_NAME='FET_N_DUAL_SMLF-NTJD4001N,FET,A',
 PRIM_FILE='./archive_libs/mstr_discrete/fet_n_dual/chips/chips.prt';

SECTION_NUMBER 2
 '@BASEBOARD_FAB2_LIB.BASEBOARD_FAB2(SCH_1):PAGE119_I180@MSTR_DISCRETE.FET_N_DUAL(CHIPS)':
 C_PATH='@baseboard_fab2_lib.baseboard_fab2(sch_1):page119_i180@mstr_discrete.fe~
t_n_dual(chips)',
 P_PATH='@baseboard_fab2_lib.baseboard_fab2(sch_1):page119_i180@mstr_discrete.fe~
t_n_dual(chips)',
 PATH='I180',
 DRAWING='@BASEBOARD_FAB2_LIB.BASEBOARD_FAB2(SCH_1):PAGE119',
 SIZE='1',
 SEC_TYPE='SMLF',
 MATERIAL='FET',
 BOM_COST='SB',
 PHYS_PAGE='119',
 XY='(-3950,1200)',
 ROT='0',
 VER='5',
 VALUE='NTJD4001N',
 PACK_TYPE='SMLF',
 PART_NUMBER='E40049-001',
 LOCATION='Q9A2',
 ROOM='SB',
 SEC='2',
 CDS_LIB='mstr_discrete',
 CDS_PART_NAME='FET_N_DUAL_SMLF-NTJD4001N,FET,A',
 PRIM_FILE='./archive_libs/mstr_discrete/fet_n_dual/chips/chips.prt';

PART_NAME
 Q9A3 'FET_N_SOT23LF-2N7002,FET,C7925A':
 ROOM='MIO_CHASSIS';

SECTION_NUMBER 1
 '@BASEBOARD_FAB2_LIB.BASEBOARD_FAB2(SCH_1):PAGE175_I49@MSTR_DISCRETE.FET_N(CHIPS)':
 C_PATH='@baseboard_fab2_lib.baseboard_fab2(sch_1):page175_i49@mstr_discrete.fet~
_n(chips)',
 P_PATH='@baseboard_fab2_lib.baseboard_fab2(sch_1):page175_i49@mstr_discrete.fet~
_n(chips)',
 PATH='I49',
 DRAWING='@BASEBOARD_FAB2_LIB.BASEBOARD_FAB2(SCH_1):PAGE175',
 SEC_TYPE='SOT23LF',
 MATERIAL='FET',
 BOM_COST='MIO_CHASSIS',
 PHYS_PAGE='175',
 XY='(-5025,1175)',
 ROT='0',
 VER='8',
 VALUE='2N7002',
 PACK_TYPE='SOT23LF',
 PART_NUMBER='C79254-001',
 LOCATION='Q9A3',
 ROOM='MIO_CHASSIS',
 SEC='1',
 CDS_LIB='mstr_discrete',
 CDS_PART_NAME='FET_N_SOT23LF-2N7002,FET,C7925A',
 PRIM_FILE='./archive_libs/mstr_discrete/fet_n/chips/chips.prt';

PART_NAME
 Q9B1 '2SB2907A-B0-00001-GP_DISCRET-GA':;

SECTION_NUMBER 1
 '@BASEBOARD_FAB2_LIB.BASEBOARD_FAB2(SCH_1):PAGE167_I93@W_HDL.2SB2907A-B0-00001-GP(CHIPS)':
 C_PATH='@baseboard_fab2_lib.baseboard_fab2(sch_1):page167_i93@w_hdl.\2sb2907a-b~
0-00001-gp\(chips)',
 P_PATH='@baseboard_fab2_lib.baseboard_fab2(sch_1):page167_i93@w_hdl.\2sb2907a-b~
0-00001-gp\(chips)',
 PATH='I93',
 DRAWING='@BASEBOARD_FAB2_LIB.BASEBOARD_FAB2(SCH_1):PAGE167',
 SEC_TYPE='DISCRET-GB1',
 PHYS_PAGE='167',
 XY='(-5925,4600)',
 ROT='4',
 VER='1',
 VALUE='2SB2907A-B0-00001-GP',
 PACK_TYPE='DISCRET-GB1',
 PART_NUMBER='006.02907.001A',
 LOCATION='Q9B1',
 SEC='1',
 CDS_LIB='w_hdl',
 CDS_PART_NAME='2SB2907A-B0-00001-GP_DISCRET-GA',
 PRIM_FILE='C:/<user>/w_hdl/2sb2907a#2db0#2d00001#2dgp/chips/chips.prt';

PART_NAME
 Q9E1 'FET_N_DUAL_SMLF-NTJD4001N,FET,A':
 ROOM='BMC';

SECTION_NUMBER 1
 '@BASEBOARD_FAB2_LIB.BASEBOARD_FAB2(SCH_1):PAGE151_I198@MSTR_DISCRETE.FET_N_DUAL(CHIPS)':
 C_PATH='@baseboard_fab2_lib.baseboard_fab2(sch_1):page151_i198@mstr_discrete.fe~
t_n_dual(chips)',
 P_PATH='@baseboard_fab2_lib.baseboard_fab2(sch_1):page151_i198@mstr_discrete.fe~
t_n_dual(chips)',
 PATH='I198',
 DRAWING='@BASEBOARD_FAB2_LIB.BASEBOARD_FAB2(SCH_1):PAGE151',
 SIZE='1',
 SEC_TYPE='SMLF',
 MATERIAL='FET',
 BOM_COST='SM_CONTROLLER',
 PHYS_PAGE='151',
 XY='(-1700,-800)',
 ROT='0',
 VER='5',
 VALUE='NTJD4001N',
 PACK_TYPE='SMLF',
 PART_NUMBER='E40049-001',
 LOCATION='Q9E1',
 ROOM='BMC',
 SEC='1',
 CDS_LIB='mstr_discrete',
 CDS_PART_NAME='FET_N_DUAL_SMLF-NTJD4001N,FET,A',
 PRIM_FILE='./archive_libs/mstr_discrete/fet_n_dual/chips/chips.prt';

SECTION_NUMBER 2
 '@BASEBOARD_FAB2_LIB.BASEBOARD_FAB2(SCH_1):PAGE151_I145@MSTR_DISCRETE.FET_N_DUAL(CHIPS)':
 C_PATH='@baseboard_fab2_lib.baseboard_fab2(sch_1):page151_i145@mstr_discrete.fe~
t_n_dual(chips)',
 P_PATH='@baseboard_fab2_lib.baseboard_fab2(sch_1):page151_i145@mstr_discrete.fe~
t_n_dual(chips)',
 PATH='I145',
 DRAWING='@BASEBOARD_FAB2_LIB.BASEBOARD_FAB2(SCH_1):PAGE151',
 SIZE='1',
 SEC_TYPE='SMLF',
 MATERIAL='FET',
 BOM_COST='SM_CONTROLLER',
 PHYS_PAGE='151',
 XY='(-1100,-375)',
 ROT='0',
 VER='5',
 VALUE='NTJD4001N',
 PACK_TYPE='SMLF',
 PART_NUMBER='E40049-001',
 LOCATION='Q9E1',
 ROOM='BMC',
 SEC='2',
 CDS_LIB='mstr_discrete',
 CDS_PART_NAME='FET_N_DUAL_SMLF-NTJD4001N,FET,A',
 PRIM_FILE='./archive_libs/mstr_discrete/fet_n_dual/chips/chips.prt';

PART_NAME
 Q9F1 'FET_N_DUAL_SMLF-NTJD4001N,FET,A':
 ROOM='BMC';

SECTION_NUMBER 1
 '@BASEBOARD_FAB2_LIB.BASEBOARD_FAB2(SCH_1):PAGE177_I80@MSTR_DISCRETE.FET_N_DUAL(CHIPS)':
 C_PATH='@baseboard_fab2_lib.baseboard_fab2(sch_1):page177_i80@mstr_discrete.fet~
_n_dual(chips)',
 P_PATH='@baseboard_fab2_lib.baseboard_fab2(sch_1):page177_i80@mstr_discrete.fet~
_n_dual(chips)',
 PATH='I80',
 DRAWING='@BASEBOARD_FAB2_LIB.BASEBOARD_FAB2(SCH_1):PAGE177',
 SIZE='1',
 SEC_TYPE='SMLF',
 MATERIAL='FET',
 BOM_COST='SM_CONTROLLER',
 PHYS_PAGE='177',
 XY='(-8125,7675)',
 ROT='0',
 VER='5',
 VALUE='NTJD4001N',
 PACK_TYPE='SMLF',
 PART_NUMBER='E40049-001',
 LOCATION='Q9F1',
 ROOM='BMC',
 SEC='1',
 CDS_LIB='mstr_discrete',
 CDS_PART_NAME='FET_N_DUAL_SMLF-NTJD4001N,FET,A',
 PRIM_FILE='./archive_libs/mstr_discrete/fet_n_dual/chips/chips.prt';

SECTION_NUMBER 2
 '@BASEBOARD_FAB2_LIB.BASEBOARD_FAB2(SCH_1):PAGE177_I79@MSTR_DISCRETE.FET_N_DUAL(CHIPS)':
 C_PATH='@baseboard_fab2_lib.baseboard_fab2(sch_1):page177_i79@mstr_discrete.fet~
_n_dual(chips)',
 P_PATH='@baseboard_fab2_lib.baseboard_fab2(sch_1):page177_i79@mstr_discrete.fet~
_n_dual(chips)',
 PATH='I79',
 DRAWING='@BASEBOARD_FAB2_LIB.BASEBOARD_FAB2(SCH_1):PAGE177',
 SIZE='1',
 SEC_TYPE='SMLF',
 MATERIAL='FET',
 BOM_COST='SM_CONTROLLER',
 PHYS_PAGE='177',
 XY='(-7200,8050)',
 ROT='0',
 VER='5',
 VALUE='NTJD4001N',
 PACK_TYPE='SMLF',
 PART_NUMBER='E40049-001',
 LOCATION='Q9F1',
 ROOM='BMC',
 SEC='2',
 CDS_LIB='mstr_discrete',
 CDS_PART_NAME='FET_N_DUAL_SMLF-NTJD4001N,FET,A',
 PRIM_FILE='./archive_libs/mstr_discrete/fet_n_dual/chips/chips.prt';

PART_NAME
 Q9G1 'FET_N_DUAL_SMLF-NTJD4001N,FET,A':
 ROOM='BMC_VOLT_MONITOR';

SECTION_NUMBER 1
 '@BASEBOARD_FAB2_LIB.BASEBOARD_FAB2(SCH_1):PAGE169_I162@MSTR_DISCRETE.FET_N_DUAL(CHIPS)':
 C_PATH='@baseboard_fab2_lib.baseboard_fab2(sch_1):page169_i162@mstr_discrete.fe~
t_n_dual(chips)',
 P_PATH='@baseboard_fab2_lib.baseboard_fab2(sch_1):page169_i162@mstr_discrete.fe~
t_n_dual(chips)',
 PATH='I162',
 DRAWING='@BASEBOARD_FAB2_LIB.BASEBOARD_FAB2(SCH_1):PAGE169',
 SIZE='1',
 SEC_TYPE='SMLF',
 MATERIAL='FET',
 BOM_COST='SM_HM',
 PHYS_PAGE='169',
 XY='(-875,2900)',
 ROT='0',
 VER='5',
 VALUE='NTJD4001N',
 PACK_TYPE='SMLF',
 PART_NUMBER='E40049-001',
 LOCATION='Q9G1',
 ROOM='BMC_VOLT_MONITOR',
 SEC='1',
 CDS_LIB='mstr_discrete',
 CDS_PART_NAME='FET_N_DUAL_SMLF-NTJD4001N,FET,A',
 PRIM_FILE='./archive_libs/mstr_discrete/fet_n_dual/chips/chips.prt';

SECTION_NUMBER 2
 '@BASEBOARD_FAB2_LIB.BASEBOARD_FAB2(SCH_1):PAGE169_I157@MSTR_DISCRETE.FET_N_DUAL(CHIPS)':
 C_PATH='@baseboard_fab2_lib.baseboard_fab2(sch_1):page169_i157@mstr_discrete.fe~
t_n_dual(chips)',
 P_PATH='@baseboard_fab2_lib.baseboard_fab2(sch_1):page169_i157@mstr_discrete.fe~
t_n_dual(chips)',
 PATH='I157',
 DRAWING='@BASEBOARD_FAB2_LIB.BASEBOARD_FAB2(SCH_1):PAGE169',
 SIZE='1',
 SEC_TYPE='SMLF',
 MATERIAL='FET',
 BOM_COST='SM_HM',
 PHYS_PAGE='169',
 XY='(200,3225)',
 ROT='0',
 VER='5',
 VALUE='NTJD4001N',
 PACK_TYPE='SMLF',
 PART_NUMBER='E40049-001',
 LOCATION='Q9G1',
 ROOM='BMC_VOLT_MONITOR',
 SEC='2',
 CDS_LIB='mstr_discrete',
 CDS_PART_NAME='FET_N_DUAL_SMLF-NTJD4001N,FET,A',
 PRIM_FILE='./archive_libs/mstr_discrete/fet_n_dual/chips/chips.prt';

PART_NAME
 Q9P1 'FET_N_DUAL_SMLF-2N7002DW,FET,DA':
 ROOM='HOT_SWAP';

SECTION_NUMBER 1
 '@BASEBOARD_FAB2_LIB.BASEBOARD_FAB2(SCH_1):PAGE200_I196@MSTR_DISCRETE.FET_N_DUAL(CHIPS)':
 C_PATH='@baseboard_fab2_lib.baseboard_fab2(sch_1):page200_i196@mstr_discrete.fe~
t_n_dual(chips)',
 P_PATH='@baseboard_fab2_lib.baseboard_fab2(sch_1):page200_i196@mstr_discrete.fe~
t_n_dual(chips)',
 PATH='I196',
 DRAWING='@BASEBOARD_FAB2_LIB.BASEBOARD_FAB2(SCH_1):PAGE200',
 SIZE='1',
 SEC_TYPE='SMLF',
 MATERIAL='FET',
 PHYS_PAGE='200',
 XY='(-2000,3325)',
 ROT='0',
 VER='5',
 VALUE='2N7002DW',
 PACK_TYPE='SMLF',
 PART_NUMBER='D24280-001',
 LOCATION='Q9P1',
 ROOM='HOT_SWAP',
 SEC='1',
 CDS_LIB='mstr_discrete',
 CDS_PART_NAME='FET_N_DUAL_SMLF-2N7002DW,FET,DA',
 PRIM_FILE='./archive_libs/mstr_discrete/fet_n_dual/chips/chips.prt';

SECTION_NUMBER 2
 '@BASEBOARD_FAB2_LIB.BASEBOARD_FAB2(SCH_1):PAGE200_I199@MSTR_DISCRETE.FET_N_DUAL(CHIPS)':
 C_PATH='@baseboard_fab2_lib.baseboard_fab2(sch_1):page200_i199@mstr_discrete.fe~
t_n_dual(chips)',
 P_PATH='@baseboard_fab2_lib.baseboard_fab2(sch_1):page200_i199@mstr_discrete.fe~
t_n_dual(chips)',
 PATH='I199',
 DRAWING='@BASEBOARD_FAB2_LIB.BASEBOARD_FAB2(SCH_1):PAGE200',
 SIZE='1',
 SEC_TYPE='SMLF',
 MATERIAL='FET',
 PHYS_PAGE='200',
 XY='(550,-100)',
 ROT='0',
 VER='5',
 VALUE='2N7002DW',
 PACK_TYPE='SMLF',
 PART_NUMBER='D24280-001',
 LOCATION='Q9P1',
 ROOM='HOT_SWAP',
 SEC='2',
 CDS_LIB='mstr_discrete',
 CDS_PART_NAME='FET_N_DUAL_SMLF-2N7002DW,FET,DA',
 PRIM_FILE='./archive_libs/mstr_discrete/fet_n_dual/chips/chips.prt';

PART_NAME
 Q9T1 'NPN_SM-MMBT3904,IC,C52245-001':
 ROOM='SB';

SECTION_NUMBER 1
 '@BASEBOARD_FAB2_LIB.BASEBOARD_FAB2(SCH_1):PAGE181_I42@MSTR_DISCRETE.NPN(CHIPS)':
 C_PATH='@baseboard_fab2_lib.baseboard_fab2(sch_1):page181_i42@mstr_discrete.npn~
(chips)',
 P_PATH='@baseboard_fab2_lib.baseboard_fab2(sch_1):page181_i42@mstr_discrete.npn~
(chips)',
 PATH='I42',
 DRAWING='@BASEBOARD_FAB2_LIB.BASEBOARD_FAB2(SCH_1):PAGE181',
 SEC_TYPE='SM',
 MATERIAL='IC',
 PHYS_PAGE='181',
 XY='(650,1550)',
 ROT='0',
 VER='1',
 VALUE='MMBT3904',
 PACK_TYPE='SM',
 PART_NUMBER='C52245-001',
 LOCATION='Q9T1',
 ROOM='SB',
 SEC='1',
 CDS_LIB='mstr_discrete',
 CDS_PART_NAME='NPN_SM-MMBT3904,IC,C52245-001',
 PRIM_FILE='./archive_libs/mstr_discrete/npn/chips/chips.prt';

PART_NAME
 Q9W1 'FET_N_SOT23LF-2N7002,FET,C7925A':
 ROOM='HOT_SWAP';

SECTION_NUMBER 1
 '@BASEBOARD_FAB2_LIB.BASEBOARD_FAB2(SCH_1):PAGE249_I30@MSTR_DISCRETE.FET_N(CHIPS)':
 C_PATH='@baseboard_fab2_lib.baseboard_fab2(sch_1):page249_i30@mstr_discrete.fet~
_n(chips)',
 P_PATH='@baseboard_fab2_lib.baseboard_fab2(sch_1):page249_i30@mstr_discrete.fet~
_n(chips)',
 PATH='I30',
 DRAWING='@BASEBOARD_FAB2_LIB.BASEBOARD_FAB2(SCH_1):PAGE249',
 SEC_TYPE='SOT23LF',
 MATERIAL='FET',
 PHYS_PAGE='249',
 XY='(-4850,2250)',
 ROT='0',
 VER='8',
 VALUE='2N7002',
 PACK_TYPE='SOT23LF',
 PART_NUMBER='C79254-001',
 LOCATION='Q9W1',
 ROOM='HOT_SWAP',
 SEC='1',
 CDS_LIB='mstr_discrete',
 CDS_PART_NAME='FET_N_SOT23LF-2N7002,FET,C7925A',
 PRIM_FILE='./archive_libs/mstr_discrete/fet_n/chips/chips.prt';

PART_NAME
 Q9W2 'NPN_SM-MMBT3904,IC,C52245-001':
 ROOM='SB';

SECTION_NUMBER 1
 '@BASEBOARD_FAB2_LIB.BASEBOARD_FAB2(SCH_1):PAGE249_I29@MSTR_DISCRETE.NPN(CHIPS)':
 C_PATH='@baseboard_fab2_lib.baseboard_fab2(sch_1):page249_i29@mstr_discrete.npn~
(chips)',
 P_PATH='@baseboard_fab2_lib.baseboard_fab2(sch_1):page249_i29@mstr_discrete.npn~
(chips)',
 PATH='I29',
 DRAWING='@BASEBOARD_FAB2_LIB.BASEBOARD_FAB2(SCH_1):PAGE249',
 SEC_TYPE='SM',
 MATERIAL='IC',
 PHYS_PAGE='249',
 XY='(-3250,3850)',
 ROT='0',
 VER='1',
 VALUE='MMBT3904',
 PACK_TYPE='SM',
 PART_NUMBER='C52245-001',
 LOCATION='Q9W2',
 ROOM='SB',
 SEC='1',
 CDS_LIB='mstr_discrete',
 CDS_PART_NAME='NPN_SM-MMBT3904,IC,C52245-001',
 PRIM_FILE='./archive_libs/mstr_discrete/npn/chips/chips.prt';

PART_NAME
 Q9W3 'NPN_SM-MMBT3904,IC,C52245-001':
 ROOM='SB';

SECTION_NUMBER 1
 '@BASEBOARD_FAB2_LIB.BASEBOARD_FAB2(SCH_1):PAGE249_I49@MSTR_DISCRETE.NPN(CHIPS)':
 C_PATH='@baseboard_fab2_lib.baseboard_fab2(sch_1):page249_i49@mstr_discrete.npn~
(chips)',
 P_PATH='@baseboard_fab2_lib.baseboard_fab2(sch_1):page249_i49@mstr_discrete.npn~
(chips)',
 PATH='I49',
 DRAWING='@BASEBOARD_FAB2_LIB.BASEBOARD_FAB2(SCH_1):PAGE249',
 SEC_TYPE='SM',
 MATERIAL='IC',
 PHYS_PAGE='249',
 XY='(-2350,4100)',
 ROT='0',
 VER='1',
 VALUE='MMBT3904',
 PACK_TYPE='SM',
 PART_NUMBER='C52245-001',
 LOCATION='Q9W3',
 ROOM='SB',
 SEC='1',
 CDS_LIB='mstr_discrete',
 CDS_PART_NAME='NPN_SM-MMBT3904,IC,C52245-001',
 PRIM_FILE='./archive_libs/mstr_discrete/npn/chips/chips.prt';

PART_NAME
 Q9W4 'LMV331IDCKRG4-GP_DISCRET-G-LMVA':;

SECTION_NUMBER 1
 '@BASEBOARD_FAB2_LIB.BASEBOARD_FAB2(SCH_1):PAGE249_I15@W_HDL.LMV331IDCKRG4-GP(CHIPS)':
 C_PATH='@baseboard_fab2_lib.baseboard_fab2(sch_1):page249_i15@w_hdl.\lmv331idck~
rg4-gp\(chips)',
 P_PATH='@baseboard_fab2_lib.baseboard_fab2(sch_1):page249_i15@w_hdl.\lmv331idck~
rg4-gp\(chips)',
 PATH='I15',
 DRAWING='@BASEBOARD_FAB2_LIB.BASEBOARD_FAB2(SCH_1):PAGE249',
 PHYS_PAGE='249',
 XY='(-2300,2550)',
 ROT='0',
 VER='1',
 VALUE='LMV331IDCKRG4-GP',
 PACK_TYPE='DISCRET-G',
 PART_NUMBER='74.00331.A2F',
 LOCATION='Q9W4',
 CDS_LIB='w_hdl',
 CDS_PART_NAME='LMV331IDCKRG4-GP_DISCRET-G-LMVA',
 PRIM_FILE='C:/<user>/w_hdl/lmv331idckrg4#2dgp/chips/chips.prt';

PART_NAME
 Q12W1 'BSL308C-H6327-GP_DISCRET-GB1-BA':;

SECTION_NUMBER 1
 '@BASEBOARD_FAB2_LIB.BASEBOARD_FAB2(SCH_1):PAGE197_I43@W_HDL.BSL308C-H6327-GP(CHIPS)':
 C_PATH='@baseboard_fab2_lib.baseboard_fab2(sch_1):page197_i43@w_hdl.\bsl308c-h6~
327-gp\(chips)',
 P_PATH='@baseboard_fab2_lib.baseboard_fab2(sch_1):page197_i43@w_hdl.\bsl308c-h6~
327-gp\(chips)',
 PATH='I43',
 DRAWING='@BASEBOARD_FAB2_LIB.BASEBOARD_FAB2(SCH_1):PAGE197',
 SEC_TYPE='DISCRET-GB1',
 PHYS_PAGE='197',
 XY='(-3250,4100)',
 ROT='0',
 VER='1',
 VALUE='BSL308C-H6327-GP',
 PACK_TYPE='DISCRET-GB1',
 PART_NUMBER='075.00308.007C',
 LOCATION='Q12W1',
 SEC='1',
 CDS_LIB='w_hdl',
 CDS_PART_NAME='BSL308C-H6327-GP_DISCRET-GB1-BA',
 PRIM_FILE='C:/<user>/w_hdl/bsl308c#2dh6327#2dgp/chips/chips.prt';

PART_NAME
 Q12W2 'BSL308C-H6327-GP_DISCRET-GB1-BA':;

SECTION_NUMBER 1
 '@BASEBOARD_FAB2_LIB.BASEBOARD_FAB2(SCH_1):PAGE197_I19@W_HDL.BSL308C-H6327-GP(CHIPS)':
 C_PATH='@baseboard_fab2_lib.baseboard_fab2(sch_1):page197_i19@w_hdl.\bsl308c-h6~
327-gp\(chips)',
 P_PATH='@baseboard_fab2_lib.baseboard_fab2(sch_1):page197_i19@w_hdl.\bsl308c-h6~
327-gp\(chips)',
 PATH='I19',
 DRAWING='@BASEBOARD_FAB2_LIB.BASEBOARD_FAB2(SCH_1):PAGE197',
 SEC_TYPE='DISCRET-GB1',
 PHYS_PAGE='197',
 XY='(-3250,2000)',
 ROT='0',
 VER='1',
 VALUE='BSL308C-H6327-GP',
 PACK_TYPE='DISCRET-GB1',
 PART_NUMBER='075.00308.007C',
 LOCATION='Q12W2',
 SEC='1',
 CDS_LIB='w_hdl',
 CDS_PART_NAME='BSL308C-H6327-GP_DISCRET-GB1-BA',
 PRIM_FILE='C:/<user>/w_hdl/bsl308c#2dh6327#2dgp/chips/chips.prt';

PART_NAME
 Q12W3 'BSL308C-H6327-GP_DISCRET-GB1-BA':;

SECTION_NUMBER 1
 '@BASEBOARD_FAB2_LIB.BASEBOARD_FAB2(SCH_1):PAGE197_I91@W_HDL.BSL308C-H6327-GP(CHIPS)':
 C_PATH='@baseboard_fab2_lib.baseboard_fab2(sch_1):page197_i91@w_hdl.\bsl308c-h6~
327-gp\(chips)',
 P_PATH='@baseboard_fab2_lib.baseboard_fab2(sch_1):page197_i91@w_hdl.\bsl308c-h6~
327-gp\(chips)',
 PATH='I91',
 DRAWING='@BASEBOARD_FAB2_LIB.BASEBOARD_FAB2(SCH_1):PAGE197',
 SEC_TYPE='DISCRET-GB1',
 PHYS_PAGE='197',
 XY='(-700,4100)',
 ROT='0',
 VER='1',
 VALUE='BSL308C-H6327-GP',
 PACK_TYPE='DISCRET-GB1',
 PART_NUMBER='075.00308.007C',
 LOCATION='Q12W3',
 SEC='1',
 CDS_LIB='w_hdl',
 CDS_PART_NAME='BSL308C-H6327-GP_DISCRET-GB1-BA',
 PRIM_FILE='C:/<user>/w_hdl/bsl308c#2dh6327#2dgp/chips/chips.prt';

PART_NAME
 Q12W4 'BSL308C-H6327-GP_DISCRET-GB1-BA':;

SECTION_NUMBER 1
 '@BASEBOARD_FAB2_LIB.BASEBOARD_FAB2(SCH_1):PAGE197_I35@W_HDL.BSL308C-H6327-GP(CHIPS)':
 C_PATH='@baseboard_fab2_lib.baseboard_fab2(sch_1):page197_i35@w_hdl.\bsl308c-h6~
327-gp\(chips)',
 P_PATH='@baseboard_fab2_lib.baseboard_fab2(sch_1):page197_i35@w_hdl.\bsl308c-h6~
327-gp\(chips)',
 PATH='I35',
 DRAWING='@BASEBOARD_FAB2_LIB.BASEBOARD_FAB2(SCH_1):PAGE197',
 SEC_TYPE='DISCRET-GB1',
 PHYS_PAGE='197',
 XY='(-700,2000)',
 ROT='0',
 VER='1',
 VALUE='BSL308C-H6327-GP',
 PACK_TYPE='DISCRET-GB1',
 PART_NUMBER='075.00308.007C',
 LOCATION='Q12W4',
 SEC='1',
 CDS_LIB='w_hdl',
 CDS_PART_NAME='BSL308C-H6327-GP_DISCRET-GB1-BA',
 PRIM_FILE='C:/<user>/w_hdl/bsl308c#2dh6327#2dgp/chips/chips.prt';

PART_NAME
 Q25W4 'FET_N_DUAL_SMLF-2N7002DW,FET,DA':
 GROUP='AST2500',
 ROOM='UART_MUX';

SECTION_NUMBER 1
 '@BASEBOARD_FAB2_LIB.BASEBOARD_FAB2(SCH_1):PAGE255_I95@MSTR_DISCRETE.FET_N_DUAL(CHIPS)':
 C_PATH='@baseboard_fab2_lib.baseboard_fab2(sch_1):page255_i95@mstr_discrete.fet~
_n_dual(chips)',
 P_PATH='@baseboard_fab2_lib.baseboard_fab2(sch_1):page252_i95@mstr_discrete.fet~
_n_dual(chips)',
 PATH='I95',
 DRAWING='@BASEBOARD_FAB2_LIB.BASEBOARD_FAB2(SCH_1):PAGE255',
 SIZE='1',
 SEC_TYPE='SMLF',
 MATERIAL='FET',
 BOM_COST='DEBUG',
 PHYS_PAGE='252',
 XY='(-8100,4750)',
 ROT='5',
 VER='5',
 VALUE='2N7002DW',
 PACK_TYPE='SMLF',
 PART_NUMBER='D24280-001',
 LOCATION='Q25W4',
 ROOM='UART_MUX',
 GROUP='AST2500',
 SEC='1',
 CDS_LIB='mstr_discrete',
 CDS_PART_NAME='FET_N_DUAL_SMLF-2N7002DW,FET,DA',
 PRIM_FILE='./archive_libs/mstr_discrete/fet_n_dual/chips/chips.prt';

SECTION_NUMBER 2
 '@BASEBOARD_FAB2_LIB.BASEBOARD_FAB2(SCH_1):PAGE255_I96@MSTR_DISCRETE.FET_N_DUAL(CHIPS)':
 C_PATH='@baseboard_fab2_lib.baseboard_fab2(sch_1):page255_i96@mstr_discrete.fet~
_n_dual(chips)',
 P_PATH='@baseboard_fab2_lib.baseboard_fab2(sch_1):page252_i96@mstr_discrete.fet~
_n_dual(chips)',
 PATH='I96',
 DRAWING='@BASEBOARD_FAB2_LIB.BASEBOARD_FAB2(SCH_1):PAGE255',
 SIZE='1',
 SEC_TYPE='SMLF',
 MATERIAL='FET',
 BOM_COST='DEBUG',
 PHYS_PAGE='252',
 XY='(-8100,3500)',
 ROT='5',
 VER='5',
 VALUE='2N7002DW',
 PACK_TYPE='SMLF',
 PART_NUMBER='D24280-001',
 LOCATION='Q25W4',
 ROOM='UART_MUX',
 GROUP='AST2500',
 SEC='2',
 CDS_LIB='mstr_discrete',
 CDS_PART_NAME='FET_N_DUAL_SMLF-2N7002DW,FET,DA',
 PRIM_FILE='./archive_libs/mstr_discrete/fet_n_dual/chips/chips.prt';

PART_NAME
 Q25W5 'FET_N_SOT23LF-2N7002,FET,C7925A':
 ROOM='HOT_SWAP';

SECTION_NUMBER 1
 '@BASEBOARD_FAB2_LIB.BASEBOARD_FAB2(SCH_1):PAGE268_I51@MSTR_DISCRETE.FET_N(CHIPS)':
 C_PATH='@baseboard_fab2_lib.baseboard_fab2(sch_1):page268_i51@mstr_discrete.fet~
_n(chips)',
 P_PATH='@baseboard_fab2_lib.baseboard_fab2(sch_1):page255_i51@mstr_discrete.fet~
_n(chips)',
 PATH='I51',
 DRAWING='@BASEBOARD_FAB2_LIB.BASEBOARD_FAB2(SCH_1):PAGE268',
 SEC_TYPE='SOT23LF',
 MATERIAL='FET',
 PHYS_PAGE='255',
 XY='(-3250,3050)',
 ROT='0',
 VER='8',
 VALUE='2N7002',
 PACK_TYPE='SOT23LF',
 PART_NUMBER='C79254-001',
 LOCATION='Q25W5',
 ROOM='HOT_SWAP',
 SEC='1',
 CDS_LIB='mstr_discrete',
 CDS_PART_NAME='FET_N_SOT23LF-2N7002,FET,C7925A',
 PRIM_FILE='./archive_libs/mstr_discrete/fet_n/chips/chips.prt';

PART_NAME
 R1A1 'RES_0603-120.0,1%,1/10W,CHIP,GA':
 ROOM='VDDQ_KLM_PWR_VR';

SECTION_NUMBER 1
 '@BASEBOARD_FAB2_LIB.BASEBOARD_FAB2(SCH_1):PAGE228_I58@MSTR_DISCRETE.RES(CHIPS)':
 C_PATH='@baseboard_fab2_lib.baseboard_fab2(sch_1):page228_i58@mstr_discrete.res~
(chips)',
 P_PATH='@baseboard_fab2_lib.baseboard_fab2(sch_1):page228_i58@mstr_discrete.res~
(chips)',
 PATH='I58',
 DRAWING='@BASEBOARD_FAB2_LIB.BASEBOARD_FAB2(SCH_1):PAGE228',
 WATTAGE='1/10W',
 TOLERANCE='1%',
 MATERIAL='CHIP',
 BOM_COST='MEM_VRD_PVPP_AB',
 PHYS_PAGE='228',
 XY='(4100,-500)',
 ROT='0',
 VER='2',
 VALUE='120.0',
 PACK_TYPE='0603',
 PART_NUMBER='G22026-003',
 LOCATION='R1A1',
 ROOM='VDDQ_KLM_PWR_VR',
 CDS_LIB='mstr_discrete',
 CDS_PART_NAME='RES_0603-120.0,1%,1/10W,CHIP,GA',
 PRIM_FILE='./archive_libs/mstr_discrete/res/chips/chips.prt';

PART_NAME
 R1A2 'RES_0402-68.1K,1%,1/16W,EMPTY,A':;

SECTION_NUMBER 1
 '@BASEBOARD_FAB2_LIB.BASEBOARD_FAB2(SCH_1):PAGE227_I105@MSTR_DISCRETE.RES(CHIPS)':
 C_PATH='@baseboard_fab2_lib.baseboard_fab2(sch_1):page227_i105@mstr_discrete.re~
s(chips)',
 P_PATH='@baseboard_fab2_lib.baseboard_fab2(sch_1):page227_i105@mstr_discrete.re~
s(chips)',
 PATH='I105',
 DRAWING='@BASEBOARD_FAB2_LIB.BASEBOARD_FAB2(SCH_1):PAGE227',
 BOM_SS='NOPOP',
 WATTAGE='1/16W',
 TOLERANCE='1%',
 SEC_TYPE='0402',
 MATERIAL='EMPTY',
 PHYS_PAGE='227',
 XY='(4650,150)',
 ROT='0',
 VER='2',
 VALUE='68.1K',
 PACK_TYPE='0402',
 PART_NUMBER='G21796-187',
 LOCATION='R1A2',
 SEC='1',
 CDS_LIB='mstr_discrete',
 CDS_PART_NAME='RES_0402-68.1K,1%,1/16W,EMPTY,A',
 PRIM_FILE='./archive_libs/mstr_discrete/res/chips/chips.prt';

PART_NAME
 R1A3 'RES_0402-68.1K,1%,1/16W,EMPTY,A':;

SECTION_NUMBER 1
 '@BASEBOARD_FAB2_LIB.BASEBOARD_FAB2(SCH_1):PAGE227_I103@MSTR_DISCRETE.RES(CHIPS)':
 C_PATH='@baseboard_fab2_lib.baseboard_fab2(sch_1):page227_i103@mstr_discrete.re~
s(chips)',
 P_PATH='@baseboard_fab2_lib.baseboard_fab2(sch_1):page227_i103@mstr_discrete.re~
s(chips)',
 PATH='I103',
 DRAWING='@BASEBOARD_FAB2_LIB.BASEBOARD_FAB2(SCH_1):PAGE227',
 WATTAGE='1/16W',
 TOLERANCE='1%',
 SEC_TYPE='0402',
 MATERIAL='EMPTY',
 PHYS_PAGE='227',
 XY='(4650,2400)',
 ROT='0',
 VER='2',
 VALUE='68.1K',
 PACK_TYPE='0402',
 PART_NUMBER='G21796-187',
 LOCATION='R1A3',
 SEC='1',
 CDS_LIB='mstr_discrete',
 CDS_PART_NAME='RES_0402-68.1K,1%,1/16W,EMPTY,A',
 PRIM_FILE='./archive_libs/mstr_discrete/res/chips/chips.prt';

PART_NAME
 R1B1 'RES_0402-1.00K,1%,1/16W,CHIP,GA':
 ROOM='RQ_PVDDQ_KLM_VRHOT_LVT3_N';

SECTION_NUMBER 1
 '@BASEBOARD_FAB2_LIB.BASEBOARD_FAB2(SCH_1):PAGE226_I49@MSTR_DISCRETE.RES(CHIPS)':
 C_PATH='@baseboard_fab2_lib.baseboard_fab2(sch_1):page226_i49@mstr_discrete.res~
(chips)',
 P_PATH='@baseboard_fab2_lib.baseboard_fab2(sch_1):page226_i49@mstr_discrete.res~
(chips)',
 PATH='I49',
 DRAWING='@BASEBOARD_FAB2_LIB.BASEBOARD_FAB2(SCH_1):PAGE226',
 WATTAGE='1/16W',
 TOLERANCE='1%',
 SEC_TYPE='0402',
 MATERIAL='CHIP',
 PHYS_PAGE='226',
 XY='(1825,2350)',
 ROT='0',
 VER='2',
 VALUE='1.00K',
 PACK_TYPE='0402',
 PART_NUMBER='G21796-026',
 LOCATION='R1B1',
 ROOM='RQ_PVDDQ_KLM_VRHOT_LVT3_N',
 SEC='1',
 CDS_LIB='mstr_discrete',
 CDS_PART_NAME='RES_0402-1.00K,1%,1/16W,CHIP,GA',
 PRIM_FILE='./archive_libs/mstr_discrete/res/chips/chips.prt';

PART_NAME
 R1B2 'RES_0402-1.00K,1%,1/16W,CHIP,GA':
 ROOM='VDDQ_KLM_PWR_VR';

SECTION_NUMBER 1
 '@BASEBOARD_FAB2_LIB.BASEBOARD_FAB2(SCH_1):PAGE226_I50@MSTR_DISCRETE.RES(CHIPS)':
 C_PATH='@baseboard_fab2_lib.baseboard_fab2(sch_1):page226_i50@mstr_discrete.res~
(chips)',
 P_PATH='@baseboard_fab2_lib.baseboard_fab2(sch_1):page226_i50@mstr_discrete.res~
(chips)',
 PATH='I50',
 DRAWING='@BASEBOARD_FAB2_LIB.BASEBOARD_FAB2(SCH_1):PAGE226',
 WATTAGE='1/16W',
 TOLERANCE='1%',
 SEC_TYPE='0402',
 MATERIAL='CHIP',
 PHYS_PAGE='226',
 XY='(2100,2350)',
 ROT='0',
 VER='2',
 VALUE='1.00K',
 PACK_TYPE='0402',
 PART_NUMBER='G21796-026',
 LOCATION='R1B2',
 ROOM='VDDQ_KLM_PWR_VR',
 SEC='1',
 CDS_LIB='mstr_discrete',
 CDS_PART_NAME='RES_0402-1.00K,1%,1/16W,CHIP,GA',
 PRIM_FILE='./archive_libs/mstr_discrete/res/chips/chips.prt';

PART_NAME
 R1B4 'RES_0402-33.2,1%,1/16W,CHIP,G2A':;

SECTION_NUMBER 1
 '@BASEBOARD_FAB2_LIB.BASEBOARD_FAB2(SCH_1):PAGE226_I54@MSTR_DISCRETE.RES(CHIPS)':
 C_PATH='@baseboard_fab2_lib.baseboard_fab2(sch_1):page226_i54@mstr_discrete.res~
(chips)',
 P_PATH='@baseboard_fab2_lib.baseboard_fab2(sch_1):page226_i54@mstr_discrete.res~
(chips)',
 PATH='I54',
 DRAWING='@BASEBOARD_FAB2_LIB.BASEBOARD_FAB2(SCH_1):PAGE226',
 WATTAGE='1/16W',
 TOLERANCE='1%',
 SEC_TYPE='0402',
 MATERIAL='CHIP',
 PHYS_PAGE='226',
 XY='(3025,1725)',
 ROT='0',
 VER='1',
 VALUE='33.2',
 PACK_TYPE='0402',
 PART_NUMBER='G21796-074',
 LOCATION='R1B4',
 SEC='1',
 CDS_LIB='mstr_discrete',
 CDS_PART_NAME='RES_0402-33.2,1%,1/16W,CHIP,G2A',
 PRIM_FILE='./archive_libs/mstr_discrete/res/chips/chips.prt';

PART_NAME
 R1B5 'RES_0402-22.1,1.0%,1/16W,CHIP,A':
 ROOM='VDDQ_KLM_PWR_VR';

SECTION_NUMBER 1
 '@BASEBOARD_FAB2_LIB.BASEBOARD_FAB2(SCH_1):PAGE226_I55@MSTR_DISCRETE.RES(CHIPS)':
 C_PATH='@baseboard_fab2_lib.baseboard_fab2(sch_1):page226_i55@mstr_discrete.res~
(chips)',
 P_PATH='@baseboard_fab2_lib.baseboard_fab2(sch_1):page226_i55@mstr_discrete.res~
(chips)',
 PATH='I55',
 DRAWING='@BASEBOARD_FAB2_LIB.BASEBOARD_FAB2(SCH_1):PAGE226',
 POP='NOPOP',
 WATTAGE='1/16W',
 TOLERANCE='1.0%',
 SEC_TYPE='0402',
 MATERIAL='CHIP',
 PHYS_PAGE='226',
 XY='(3025,1825)',
 ROT='0',
 VER='1',
 VALUE='22.1',
 PACK_TYPE='0402',
 PART_NUMBER='G21796-250',
 LOCATION='R1B5',
 ROOM='VDDQ_KLM_PWR_VR',
 SEC='1',
 CDS_LIB='mstr_discrete',
 CDS_PART_NAME='RES_0402-22.1,1.0%,1/16W,CHIP,A',
 PRIM_FILE='./archive_libs/mstr_discrete/res/chips/chips.prt';

PART_NAME
 R1B8 'RES_0402-150.0,1%,1/16W,CHIP,GA':
 ROOM='VDDQ_KLM_PWR_VR';

SECTION_NUMBER 1
 '@BASEBOARD_FAB2_LIB.BASEBOARD_FAB2(SCH_1):PAGE226_I19@MSTR_DISCRETE.RES(CHIPS)':
 C_PATH='@baseboard_fab2_lib.baseboard_fab2(sch_1):page226_i19@mstr_discrete.res~
(chips)',
 P_PATH='@baseboard_fab2_lib.baseboard_fab2(sch_1):page226_i19@mstr_discrete.res~
(chips)',
 PATH='I19',
 DRAWING='@BASEBOARD_FAB2_LIB.BASEBOARD_FAB2(SCH_1):PAGE226',
 WATTAGE='1/16W',
 TOLERANCE='1%',
 SEC_TYPE='0402',
 MATERIAL='CHIP',
 PHYS_PAGE='226',
 XY='(-550,2350)',
 ROT='0',
 VER='1',
 VALUE='150.0',
 PACK_TYPE='0402',
 PART_NUMBER='G21796-009',
 LOCATION='R1B8',
 ROOM='VDDQ_KLM_PWR_VR',
 SEC='1',
 CDS_LIB='mstr_discrete',
 CDS_PART_NAME='RES_0402-150.0,1%,1/16W,CHIP,GA',
 PRIM_FILE='./archive_libs/mstr_discrete/res/chips/chips.prt';

PART_NAME
 R1B10 'RES_0402-0.0,5%,1/16W,CHIP,G21A':
 ROOM='VDDQ_KLM_PWR_VR';

SECTION_NUMBER 1
 '@BASEBOARD_FAB2_LIB.BASEBOARD_FAB2(SCH_1):PAGE226_I41@MSTR_DISCRETE.RES(CHIPS)':
 C_PATH='@baseboard_fab2_lib.baseboard_fab2(sch_1):page226_i41@mstr_discrete.res~
(chips)',
 P_PATH='@baseboard_fab2_lib.baseboard_fab2(sch_1):page226_i41@mstr_discrete.res~
(chips)',
 PATH='I41',
 DRAWING='@BASEBOARD_FAB2_LIB.BASEBOARD_FAB2(SCH_1):PAGE226',
 WATTAGE='1/16W',
 TOLERANCE='5%',
 SEC_TYPE='0402',
 MATERIAL='CHIP',
 PHYS_PAGE='226',
 XY='(2525,975)',
 ROT='0',
 VER='1',
 VALUE='0.0',
 PACK_TYPE='0402',
 PART_NUMBER='G21497-005',
 LOCATION='R1B10',
 ROOM='VDDQ_KLM_PWR_VR',
 SEC='1',
 CDS_LIB='mstr_discrete',
 CDS_PART_NAME='RES_0402-0.0,5%,1/16W,CHIP,G21A',
 PRIM_FILE='./archive_libs/mstr_discrete/res/chips/chips.prt';

PART_NAME
 R1B11 'RES_0402-0.0,5%,1/16W,CHIP,G21A':
 ROOM='VDDQ_KLM_PWR_VR';

SECTION_NUMBER 1
 '@BASEBOARD_FAB2_LIB.BASEBOARD_FAB2(SCH_1):PAGE226_I48@MSTR_DISCRETE.RES(CHIPS)':
 C_PATH='@baseboard_fab2_lib.baseboard_fab2(sch_1):page226_i48@mstr_discrete.res~
(chips)',
 P_PATH='@baseboard_fab2_lib.baseboard_fab2(sch_1):page226_i48@mstr_discrete.res~
(chips)',
 PATH='I48',
 DRAWING='@BASEBOARD_FAB2_LIB.BASEBOARD_FAB2(SCH_1):PAGE226',
 WATTAGE='1/16W',
 TOLERANCE='5%',
 SEC_TYPE='0402',
 MATERIAL='CHIP',
 PHYS_PAGE='226',
 XY='(2325,1675)',
 ROT='0',
 VER='1',
 VALUE='0.0',
 PACK_TYPE='0402',
 PART_NUMBER='G21497-005',
 LOCATION='R1B11',
 ROOM='VDDQ_KLM_PWR_VR',
 SEC='1',
 CDS_LIB='mstr_discrete',
 CDS_PART_NAME='RES_0402-0.0,5%,1/16W,CHIP,G21A',
 PRIM_FILE='./archive_libs/mstr_discrete/res/chips/chips.prt';

PART_NAME
 R1B12 'RES_0402-16K,1.0%,1/16W,CHIP,GA':
 ROOM='VDDQ_ABC_PWR_VR';

SECTION_NUMBER 1
 '@BASEBOARD_FAB2_LIB.BASEBOARD_FAB2(SCH_1):PAGE226_I72@MSTR_DISCRETE.RES(CHIPS)':
 C_PATH='@baseboard_fab2_lib.baseboard_fab2(sch_1):page226_i72@mstr_discrete.res~
(chips)',
 P_PATH='@baseboard_fab2_lib.baseboard_fab2(sch_1):page226_i72@mstr_discrete.res~
(chips)',
 PATH='I72',
 DRAWING='@BASEBOARD_FAB2_LIB.BASEBOARD_FAB2(SCH_1):PAGE226',
 WATTAGE='1/16W',
 TOLERANCE='1.0%',
 MATERIAL='CHIP',
 PHYS_PAGE='226',
 XY='(-50,-600)',
 ROT='0',
 VER='2',
 VALUE='16K',
 PACK_TYPE='0402',
 PART_NUMBER='G21796-317',
 LOCATION='R1B12',
 ROOM='VDDQ_ABC_PWR_VR',
 CDS_LIB='mstr_discrete',
 CDS_PART_NAME='RES_0402-16K,1.0%,1/16W,CHIP,GA',
 PRIM_FILE='./archive_libs/mstr_discrete/res/chips/chips.prt';

PART_NAME
 R1B13 'RES_0402-2.26K,1.0%,1/16W,CHIPA':
 ROOM='SMBUS';

SECTION_NUMBER 1
 '@BASEBOARD_FAB2_LIB.BASEBOARD_FAB2(SCH_1):PAGE226_I75@MSTR_DISCRETE.RES(CHIPS)':
 C_PATH='@baseboard_fab2_lib.baseboard_fab2(sch_1):page226_i75@mstr_discrete.res~
(chips)',
 P_PATH='@baseboard_fab2_lib.baseboard_fab2(sch_1):page226_i75@mstr_discrete.res~
(chips)',
 PATH='I75',
 DRAWING='@BASEBOARD_FAB2_LIB.BASEBOARD_FAB2(SCH_1):PAGE226',
 SKU='B',
 WATTAGE='1/16W',
 TOLERANCE='1.0%',
 MATERIAL='CHIP',
 BOM_COST='SM_CONTROLLER',
 PHYS_PAGE='226',
 XY='(3250,2350)',
 ROT='0',
 VER='2',
 VALUE='2.26K',
 PACK_TYPE='0402',
 PART_NUMBER='G21796-311',
 LOCATION='R1B13',
 ROOM='SMBUS',
 CDS_LIB='mstr_discrete',
 CDS_PART_NAME='RES_0402-2.26K,1.0%,1/16W,CHIPA',
 PRIM_FILE='./archive_libs/mstr_discrete/res/chips/chips.prt';

PART_NAME
 R1B15 'RES_0402-3.16K,1%,1/16W,CHIP,GA':
 ROOM='PVCCIN_CPU1_VR';

SECTION_NUMBER 1
 '@BASEBOARD_FAB2_LIB.BASEBOARD_FAB2(SCH_1):PAGE226_I73@MSTR_DISCRETE.RES(CHIPS)':
 C_PATH='@baseboard_fab2_lib.baseboard_fab2(sch_1):page226_i73@mstr_discrete.res~
(chips)',
 P_PATH='@baseboard_fab2_lib.baseboard_fab2(sch_1):page226_i73@mstr_discrete.res~
(chips)',
 PATH='I73',
 DRAWING='@BASEBOARD_FAB2_LIB.BASEBOARD_FAB2(SCH_1):PAGE226',
 WATTAGE='1/16W',
 TOLERANCE='1%',
 SEC_TYPE='0402',
 MATERIAL='CHIP',
 PHYS_PAGE='226',
 XY='(325,-600)',
 ROT='0',
 VER='2',
 VALUE='3.16K',
 PACK_TYPE='0402',
 PART_NUMBER='G21796-043',
 LOCATION='R1B15',
 ROOM='PVCCIN_CPU1_VR',
 SEC='1',
 CDS_LIB='mstr_discrete',
 CDS_PART_NAME='RES_0402-3.16K,1%,1/16W,CHIP,GA',
 PRIM_FILE='./archive_libs/mstr_discrete/res/chips/chips.prt';

PART_NAME
 R1B16 'RES_0402-10.0,1%,1/16W,CHIP,G2A':
 ROOM='VDDQ_KLM_PWR_VR',
 NO_XNET_CONNECTION='1';

SECTION_NUMBER 1
 '@BASEBOARD_FAB2_LIB.BASEBOARD_FAB2(SCH_1):PAGE226_I13@MSTR_DISCRETE.RES(CHIPS)':
 C_PATH='@baseboard_fab2_lib.baseboard_fab2(sch_1):page226_i13@mstr_discrete.res~
(chips)',
 P_PATH='@baseboard_fab2_lib.baseboard_fab2(sch_1):page226_i13@mstr_discrete.res~
(chips)',
 PATH='I13',
 DRAWING='@BASEBOARD_FAB2_LIB.BASEBOARD_FAB2(SCH_1):PAGE226',
 WATTAGE='1/16W',
 TOLERANCE='1%',
 SEC_TYPE='0402',
 MATERIAL='CHIP',
 NO_XNET_CONNECTION='1',
 PHYS_PAGE='226',
 XY='(-1925,475)',
 ROT='0',
 VER='1',
 VALUE='10.0',
 PACK_TYPE='0402',
 PART_NUMBER='G21796-066',
 LOCATION='R1B16',
 ROOM='VDDQ_KLM_PWR_VR',
 SEC='1',
 CDS_LIB='mstr_discrete',
 CDS_PART_NAME='RES_0402-10.0,1%,1/16W,CHIP,G2A',
 PRIM_FILE='./archive_libs/mstr_discrete/res/chips/chips.prt';

PART_NAME
 R1B21 'RES_0402-4.75K,1%,1/16W,CHIP,GA':
 ROOM='CPU_FANS';

SECTION_NUMBER 1
 '@BASEBOARD_FAB2_LIB.BASEBOARD_FAB2(SCH_1):PAGE161_I70@MSTR_DISCRETE.RES(CHIPS)':
 C_PATH='@baseboard_fab2_lib.baseboard_fab2(sch_1):page161_i70@mstr_discrete.res~
(chips)',
 P_PATH='@baseboard_fab2_lib.baseboard_fab2(sch_1):page161_i70@mstr_discrete.res~
(chips)',
 PATH='I70',
 DRAWING='@BASEBOARD_FAB2_LIB.BASEBOARD_FAB2(SCH_1):PAGE161',
 WATTAGE='1/16W',
 TOLERANCE='1%',
 SEC_TYPE='0402',
 MATERIAL='CHIP',
 BOM_COST='SM_THERM',
 PHYS_PAGE='161',
 XY='(-3050,1950)',
 ROT='0',
 VER='2',
 VALUE='4.75K',
 PACK_TYPE='0402',
 PART_NUMBER='G21796-072',
 LOCATION='R1B21',
 ROOM='CPU_FANS',
 SEC='1',
 CDS_LIB='mstr_discrete',
 CDS_PART_NAME='RES_0402-4.75K,1%,1/16W,CHIP,GA',
 PRIM_FILE='./archive_libs/mstr_discrete/res/chips/chips.prt';

PART_NAME
 R1B22 'RES_0402-100.0,1%,1/16W,CHIP,GA':
 ROOM='CPU_FANS',
 NO_XNET_CONNECTION='1';

SECTION_NUMBER 1
 '@BASEBOARD_FAB2_LIB.BASEBOARD_FAB2(SCH_1):PAGE161_I67@MSTR_DISCRETE.RES(CHIPS)':
 C_PATH='@baseboard_fab2_lib.baseboard_fab2(sch_1):page161_i67@mstr_discrete.res~
(chips)',
 P_PATH='@baseboard_fab2_lib.baseboard_fab2(sch_1):page161_i67@mstr_discrete.res~
(chips)',
 PATH='I67',
 DRAWING='@BASEBOARD_FAB2_LIB.BASEBOARD_FAB2(SCH_1):PAGE161',
 WATTAGE='1/16W',
 TOLERANCE='1%',
 SEC_TYPE='0402',
 MATERIAL='CHIP',
 BOM_COST='SM_THERM',
 NO_XNET_CONNECTION='1',
 PHYS_PAGE='161',
 XY='(-2675,1750)',
 ROT='0',
 VER='1',
 VALUE='100.0',
 PACK_TYPE='0402',
 PART_NUMBER='G21796-017',
 LOCATION='R1B22',
 ROOM='CPU_FANS',
 SEC='1',
 CDS_LIB='mstr_discrete',
 CDS_PART_NAME='RES_0402-100.0,1%,1/16W,CHIP,GA',
 PRIM_FILE='./archive_libs/mstr_discrete/res/chips/chips.prt';

PART_NAME
 R1C1 'RES_0402-221,1.0%,1/16W,CHIP,GA':
 ROOM='CPU1';

SECTION_NUMBER 1
 '@BASEBOARD_FAB2_LIB.BASEBOARD_FAB2(SCH_1):PAGE55_I26@MSTR_DISCRETE.RES(CHIPS)':
 C_PATH='@baseboard_fab2_lib.baseboard_fab2(sch_1):page55_i26@mstr_discrete.res(~
chips)',
 P_PATH='@baseboard_fab2_lib.baseboard_fab2(sch_1):page55_i26@mstr_discrete.res(~
chips)',
 PATH='I26',
 DRAWING='@BASEBOARD_FAB2_LIB.BASEBOARD_FAB2(SCH_1):PAGE55',
 WATTAGE='1/16W',
 TOLERANCE='1.0%',
 MATERIAL='CHIP',
 BOM_COST='PROC_SOCKET',
 PHYS_PAGE='55',
 XY='(12250,3550)',
 ROT='0',
 VER='1',
 VALUE='221',
 PACK_TYPE='0402',
 PART_NUMBER='G21796-271',
 LOCATION='R1C1',
 ROOM='CPU1',
 CDS_LIB='mstr_discrete',
 CDS_PART_NAME='RES_0402-221,1.0%,1/16W,CHIP,GA',
 PRIM_FILE='./archive_libs/mstr_discrete/res/chips/chips.prt';

PART_NAME
 R1C2 'RES_0402-0.0,5%,1/16W,CHIP,G21A':
 ROOM='CPU1';

SECTION_NUMBER 1
 '@BASEBOARD_FAB2_LIB.BASEBOARD_FAB2(SCH_1):PAGE55_I24@MSTR_DISCRETE.RES(CHIPS)':
 C_PATH='@baseboard_fab2_lib.baseboard_fab2(sch_1):page55_i24@mstr_discrete.res(~
chips)',
 P_PATH='@baseboard_fab2_lib.baseboard_fab2(sch_1):page55_i24@mstr_discrete.res(~
chips)',
 PATH='I24',
 DRAWING='@BASEBOARD_FAB2_LIB.BASEBOARD_FAB2(SCH_1):PAGE55',
 WATTAGE='1/16W',
 TOLERANCE='5%',
 MATERIAL='CHIP',
 BOM_COST='PROC_SOCKET',
 PHYS_PAGE='55',
 XY='(12250,3650)',
 ROT='0',
 VER='1',
 VALUE='0.0',
 PACK_TYPE='0402',
 PART_NUMBER='G21497-005',
 LOCATION='R1C2',
 ROOM='CPU1',
 CDS_LIB='mstr_discrete',
 CDS_PART_NAME='RES_0402-0.0,5%,1/16W,CHIP,G21A',
 PRIM_FILE='./archive_libs/mstr_discrete/res/chips/chips.prt';

PART_NAME
 R1C3 'RES_0402-0.0,5%,1/16W,CHIP,G21A':
 ROOM='CPU1';

SECTION_NUMBER 1
 '@BASEBOARD_FAB2_LIB.BASEBOARD_FAB2(SCH_1):PAGE55_I25@MSTR_DISCRETE.RES(CHIPS)':
 C_PATH='@baseboard_fab2_lib.baseboard_fab2(sch_1):page55_i25@mstr_discrete.res(~
chips)',
 P_PATH='@baseboard_fab2_lib.baseboard_fab2(sch_1):page55_i25@mstr_discrete.res(~
chips)',
 PATH='I25',
 DRAWING='@BASEBOARD_FAB2_LIB.BASEBOARD_FAB2(SCH_1):PAGE55',
 WATTAGE='1/16W',
 TOLERANCE='5%',
 MATERIAL='CHIP',
 BOM_COST='PROC_SOCKET',
 PHYS_PAGE='55',
 XY='(12250,3600)',
 ROT='0',
 VER='1',
 VALUE='0.0',
 PACK_TYPE='0402',
 PART_NUMBER='G21497-005',
 LOCATION='R1C3',
 ROOM='CPU1',
 CDS_LIB='mstr_discrete',
 CDS_PART_NAME='RES_0402-0.0,5%,1/16W,CHIP,G21A',
 PRIM_FILE='./archive_libs/mstr_discrete/res/chips/chips.prt';

PART_NAME
 R1C4 'RES_0402-100.0,1%,1/16W,CHIP,GA':
 ROOM='PVSA_CPU1_VSENSE_VR';

SECTION_NUMBER 1
 '@BASEBOARD_FAB2_LIB.BASEBOARD_FAB2(SCH_1):PAGE210_I33@MSTR_DISCRETE.RES(CHIPS)':
 C_PATH='@baseboard_fab2_lib.baseboard_fab2(sch_1):page210_i33@mstr_discrete.res~
(chips)',
 P_PATH='@baseboard_fab2_lib.baseboard_fab2(sch_1):page210_i33@mstr_discrete.res~
(chips)',
 PATH='I33',
 DRAWING='@BASEBOARD_FAB2_LIB.BASEBOARD_FAB2(SCH_1):PAGE210',
 WATTAGE='1/16W',
 TOLERANCE='1%',
 SEC_TYPE='0402',
 MATERIAL='CHIP',
 BOM_COST='PROC_VRD_VCCIN_CPU0',
 PHYS_PAGE='210',
 XY='(-5275,1100)',
 ROT='0',
 VER='1',
 VALUE='100.0',
 PACK_TYPE='0402',
 PART_NUMBER='G21796-017',
 LOCATION='R1C4',
 ROOM='PVSA_CPU1_VSENSE_VR',
 SEC='1',
 CDS_LIB='mstr_discrete',
 CDS_PART_NAME='RES_0402-100.0,1%,1/16W,CHIP,GA',
 PRIM_FILE='./archive_libs/mstr_discrete/res/chips/chips.prt';

PART_NAME
 R1C5 'RES_0402-0.0,5%,1/16W,CHIP,G21A':
 ROOM='PVSA_CPU1_VSENSE_VR';

SECTION_NUMBER 1
 '@BASEBOARD_FAB2_LIB.BASEBOARD_FAB2(SCH_1):PAGE210_I32@MSTR_DISCRETE.RES(CHIPS)':
 C_PATH='@baseboard_fab2_lib.baseboard_fab2(sch_1):page210_i32@mstr_discrete.res~
(chips)',
 P_PATH='@baseboard_fab2_lib.baseboard_fab2(sch_1):page210_i32@mstr_discrete.res~
(chips)',
 PATH='I32',
 DRAWING='@BASEBOARD_FAB2_LIB.BASEBOARD_FAB2(SCH_1):PAGE210',
 WATTAGE='1/16W',
 TOLERANCE='5%',
 SEC_TYPE='0402',
 MATERIAL='CHIP',
 BOM_COST='PROC_VRD_VCCIN_CPU0',
 PHYS_PAGE='210',
 XY='(-5275,1475)',
 ROT='0',
 VER='1',
 VALUE='0.0',
 PACK_TYPE='0402',
 PART_NUMBER='G21497-005',
 LOCATION='R1C5',
 ROOM='PVSA_CPU1_VSENSE_VR',
 SEC='1',
 CDS_LIB='mstr_discrete',
 CDS_PART_NAME='RES_0402-0.0,5%,1/16W,CHIP,G21A',
 PRIM_FILE='./archive_libs/mstr_discrete/res/chips/chips.prt';

PART_NAME
 R1C6 'RES_0402-1.00K,1%,1/16W,EMPTY,A':
 ROOM='PVSA_CPU1_VSENSE_VR',
 NO_XNET_CONNECTION='1';

SECTION_NUMBER 1
 '@BASEBOARD_FAB2_LIB.BASEBOARD_FAB2(SCH_1):PAGE210_I34@MSTR_DISCRETE.RES(CHIPS)':
 C_PATH='@baseboard_fab2_lib.baseboard_fab2(sch_1):page210_i34@mstr_discrete.res~
(chips)',
 P_PATH='@baseboard_fab2_lib.baseboard_fab2(sch_1):page210_i34@mstr_discrete.res~
(chips)',
 PATH='I34',
 DRAWING='@BASEBOARD_FAB2_LIB.BASEBOARD_FAB2(SCH_1):PAGE210',
 WATTAGE='1/16W',
 TOLERANCE='1%',
 SEC_TYPE='0402',
 MATERIAL='EMPTY',
 BOM_COST='PROC_VRD_VCCIN_CPU0',
 NO_XNET_CONNECTION='1',
 PHYS_PAGE='210',
 XY='(-5950,1725)',
 ROT='0',
 VER='2',
 VALUE='1.00K',
 PACK_TYPE='0402',
 PART_NUMBER='G21796-026',
 LOCATION='R1C6',
 ROOM='PVSA_CPU1_VSENSE_VR',
 SEC='1',
 CDS_LIB='mstr_discrete',
 CDS_PART_NAME='RES_0402-1.00K,1%,1/16W,EMPTY,A',
 PRIM_FILE='./archive_libs/mstr_discrete/res/chips/chips.prt';

PART_NAME
 R1C7 'RES_0402-0.0,5%,1/16W,CHIP,G21A':
 ROOM='PVSA_CPU1_VSENSE_VR';

SECTION_NUMBER 1
 '@BASEBOARD_FAB2_LIB.BASEBOARD_FAB2(SCH_1):PAGE210_I31@MSTR_DISCRETE.RES(CHIPS)':
 C_PATH='@baseboard_fab2_lib.baseboard_fab2(sch_1):page210_i31@mstr_discrete.res~
(chips)',
 P_PATH='@baseboard_fab2_lib.baseboard_fab2(sch_1):page210_i31@mstr_discrete.res~
(chips)',
 PATH='I31',
 DRAWING='@BASEBOARD_FAB2_LIB.BASEBOARD_FAB2(SCH_1):PAGE210',
 WATTAGE='1/16W',
 TOLERANCE='5%',
 SEC_TYPE='0402',
 MATERIAL='CHIP',
 BOM_COST='PROC_VRD_VCCIN_CPU0',
 PHYS_PAGE='210',
 XY='(-5275,1925)',
 ROT='0',
 VER='1',
 VALUE='0.0',
 PACK_TYPE='0402',
 PART_NUMBER='G21497-005',
 LOCATION='R1C7',
 ROOM='PVSA_CPU1_VSENSE_VR',
 SEC='1',
 CDS_LIB='mstr_discrete',
 CDS_PART_NAME='RES_0402-0.0,5%,1/16W,CHIP,G21A',
 PRIM_FILE='./archive_libs/mstr_discrete/res/chips/chips.prt';

PART_NAME
 R1C9 'RES_0402-0.0,5%,1/16W,EMPTY,G2A':
 ROOM='IO_SLOT',
 NO_XNET_CONNECTION='1';

SECTION_NUMBER 1
 '@BASEBOARD_FAB2_LIB.BASEBOARD_FAB2(SCH_1):PAGE182_I8@MSTR_DISCRETE.RES(CHIPS)':
 C_PATH='@baseboard_fab2_lib.baseboard_fab2(sch_1):page182_i8@mstr_discrete.res(~
chips)',
 P_PATH='@baseboard_fab2_lib.baseboard_fab2(sch_1):page182_i8@mstr_discrete.res(~
chips)',
 PATH='I8',
 DRAWING='@BASEBOARD_FAB2_LIB.BASEBOARD_FAB2(SCH_1):PAGE182',
 WATTAGE='1/16W',
 TOLERANCE='5%',
 SEC_TYPE='0402',
 MATERIAL='EMPTY',
 NO_XNET_CONNECTION='1',
 PHYS_PAGE='182',
 XY='(-7000,100)',
 ROT='0',
 VER='1',
 VALUE='0.0',
 PACK_TYPE='0402',
 PART_NUMBER='G21497-005',
 LOCATION='R1C9',
 ROOM='IO_SLOT',
 SEC='1',
 CDS_LIB='mstr_discrete',
 CDS_PART_NAME='RES_0402-0.0,5%,1/16W,EMPTY,G2A',
 PRIM_FILE='./archive_libs/mstr_discrete/res/chips/chips.prt';

PART_NAME
 R1C10 'RES_0402-0.0,5%,1/16W,EMPTY,G2A':
 ROOM='IO_SLOT',
 NO_XNET_CONNECTION='1';

SECTION_NUMBER 1
 '@BASEBOARD_FAB2_LIB.BASEBOARD_FAB2(SCH_1):PAGE182_I9@MSTR_DISCRETE.RES(CHIPS)':
 C_PATH='@baseboard_fab2_lib.baseboard_fab2(sch_1):page182_i9@mstr_discrete.res(~
chips)',
 P_PATH='@baseboard_fab2_lib.baseboard_fab2(sch_1):page182_i9@mstr_discrete.res(~
chips)',
 PATH='I9',
 DRAWING='@BASEBOARD_FAB2_LIB.BASEBOARD_FAB2(SCH_1):PAGE182',
 WATTAGE='1/16W',
 TOLERANCE='5%',
 SEC_TYPE='0402',
 MATERIAL='EMPTY',
 NO_XNET_CONNECTION='1',
 PHYS_PAGE='182',
 XY='(-7000,225)',
 ROT='0',
 VER='1',
 VALUE='0.0',
 PACK_TYPE='0402',
 PART_NUMBER='G21497-005',
 LOCATION='R1C10',
 ROOM='IO_SLOT',
 SEC='1',
 CDS_LIB='mstr_discrete',
 CDS_PART_NAME='RES_0402-0.0,5%,1/16W,EMPTY,G2A',
 PRIM_FILE='./archive_libs/mstr_discrete/res/chips/chips.prt';

PART_NAME
 R1C11 'RES_0402-0.0,5%,1/16W,EMPTY,G2A':
 ROOM='IO_SLOT',
 NO_XNET_CONNECTION='1';

SECTION_NUMBER 1
 '@BASEBOARD_FAB2_LIB.BASEBOARD_FAB2(SCH_1):PAGE182_I10@MSTR_DISCRETE.RES(CHIPS)':
 C_PATH='@baseboard_fab2_lib.baseboard_fab2(sch_1):page182_i10@mstr_discrete.res~
(chips)',
 P_PATH='@baseboard_fab2_lib.baseboard_fab2(sch_1):page182_i10@mstr_discrete.res~
(chips)',
 PATH='I10',
 DRAWING='@BASEBOARD_FAB2_LIB.BASEBOARD_FAB2(SCH_1):PAGE182',
 WATTAGE='1/16W',
 TOLERANCE='5%',
 SEC_TYPE='0402',
 MATERIAL='EMPTY',
 NO_XNET_CONNECTION='1',
 PHYS_PAGE='182',
 XY='(-7000,350)',
 ROT='0',
 VER='1',
 VALUE='0.0',
 PACK_TYPE='0402',
 PART_NUMBER='G21497-005',
 LOCATION='R1C11',
 ROOM='IO_SLOT',
 SEC='1',
 CDS_LIB='mstr_discrete',
 CDS_PART_NAME='RES_0402-0.0,5%,1/16W,EMPTY,G2A',
 PRIM_FILE='./archive_libs/mstr_discrete/res/chips/chips.prt';

PART_NAME
 R1C12 'RES_0402-100.0,1%,1/16W,CHIP,GA':
 ROOM='PVSA_CPU1_VSENSE_VR';

SECTION_NUMBER 1
 '@BASEBOARD_FAB2_LIB.BASEBOARD_FAB2(SCH_1):PAGE210_I29@MSTR_DISCRETE.RES(CHIPS)':
 C_PATH='@baseboard_fab2_lib.baseboard_fab2(sch_1):page210_i29@mstr_discrete.res~
(chips)',
 P_PATH='@baseboard_fab2_lib.baseboard_fab2(sch_1):page210_i29@mstr_discrete.res~
(chips)',
 PATH='I29',
 DRAWING='@BASEBOARD_FAB2_LIB.BASEBOARD_FAB2(SCH_1):PAGE210',
 WATTAGE='1/16W',
 TOLERANCE='1%',
 SEC_TYPE='0402',
 MATERIAL='CHIP',
 BOM_COST='PROC_VRD_VCCIN_CPU0',
 PHYS_PAGE='210',
 XY='(-5300,2325)',
 ROT='0',
 VER='1',
 VALUE='100.0',
 PACK_TYPE='0402',
 PART_NUMBER='G21796-017',
 LOCATION='R1C12',
 ROOM='PVSA_CPU1_VSENSE_VR',
 SEC='1',
 CDS_LIB='mstr_discrete',
 CDS_PART_NAME='RES_0402-100.0,1%,1/16W,CHIP,GA',
 PRIM_FILE='./archive_libs/mstr_discrete/res/chips/chips.prt';

PART_NAME
 R1C13 'RES_0402-100.0K,1%,1/16W,CHIP,B':
 ROOM='PVCCIN_CPU1_VR';

SECTION_NUMBER 1
 '@BASEBOARD_FAB2_LIB.BASEBOARD_FAB2(SCH_1):PAGE206_I49@MSTR_DISCRETE.RES(CHIPS)':
 C_PATH='@baseboard_fab2_lib.baseboard_fab2(sch_1):page206_i49@mstr_discrete.res~
(chips)',
 P_PATH='@baseboard_fab2_lib.baseboard_fab2(sch_1):page206_i49@mstr_discrete.res~
(chips)',
 PATH='I49',
 DRAWING='@BASEBOARD_FAB2_LIB.BASEBOARD_FAB2(SCH_1):PAGE206',
 WATTAGE='1/16W',
 TOLERANCE='1%',
 SEC_TYPE='0402',
 MATERIAL='CHIP',
 PHYS_PAGE='206',
 XY='(-6150,4575)',
 ROT='0',
 VER='2',
 VALUE='100.0K',
 PACK_TYPE='0402',
 PART_NUMBER='G21796-160',
 LOCATION='R1C13',
 ROOM='PVCCIN_CPU1_VR',
 SEC='1',
 CDS_LIB='mstr_discrete',
 CDS_PART_NAME='RES_0402-100.0K,1%,1/16W,CHIP,B',
 PRIM_FILE='./archive_libs/mstr_discrete/res/chips/chips.prt';

PART_NAME
 R1C14 'RES_0402-0.0,5%,1/16W,CHIP,G21A':
 ROOM='PVCCIN_CPU1_VR';

SECTION_NUMBER 1
 '@BASEBOARD_FAB2_LIB.BASEBOARD_FAB2(SCH_1):PAGE206_I46@MSTR_DISCRETE.RES(CHIPS)':
 C_PATH='@baseboard_fab2_lib.baseboard_fab2(sch_1):page206_i46@mstr_discrete.res~
(chips)',
 P_PATH='@baseboard_fab2_lib.baseboard_fab2(sch_1):page206_i46@mstr_discrete.res~
(chips)',
 PATH='I46',
 DRAWING='@BASEBOARD_FAB2_LIB.BASEBOARD_FAB2(SCH_1):PAGE206',
 WATTAGE='1/16W',
 TOLERANCE='5%',
 SEC_TYPE='0402',
 MATERIAL='CHIP',
 PHYS_PAGE='206',
 XY='(-4350,4275)',
 ROT='0',
 VER='2',
 VALUE='0.0',
 PACK_TYPE='0402',
 PART_NUMBER='G21497-005',
 LOCATION='R1C14',
 ROOM='PVCCIN_CPU1_VR',
 SEC='1',
 CDS_LIB='mstr_discrete',
 CDS_PART_NAME='RES_0402-0.0,5%,1/16W,CHIP,G21A',
 PRIM_FILE='./archive_libs/mstr_discrete/res/chips/chips.prt';

PART_NAME
 R1C16 'RES_0402-1.5K,1%,1/16W,CHIP,G2A':
 ROOM='PVCCIN_CPU1_VR';

SECTION_NUMBER 1
 '@BASEBOARD_FAB2_LIB.BASEBOARD_FAB2(SCH_1):PAGE206_I56@MSTR_DISCRETE.RES(CHIPS)':
 C_PATH='@baseboard_fab2_lib.baseboard_fab2(sch_1):page206_i56@mstr_discrete.res~
(chips)',
 P_PATH='@baseboard_fab2_lib.baseboard_fab2(sch_1):page206_i56@mstr_discrete.res~
(chips)',
 PATH='I56',
 DRAWING='@BASEBOARD_FAB2_LIB.BASEBOARD_FAB2(SCH_1):PAGE206',
 WATTAGE='1/16W',
 TOLERANCE='1%',
 SEC_TYPE='0402',
 MATERIAL='CHIP',
 PHYS_PAGE='206',
 XY='(-6150,4225)',
 ROT='0',
 VER='2',
 VALUE='1.5K',
 PACK_TYPE='0402',
 PART_NUMBER='G21796-003',
 LOCATION='R1C16',
 ROOM='PVCCIN_CPU1_VR',
 SEC='1',
 CDS_LIB='mstr_discrete',
 CDS_PART_NAME='RES_0402-1.5K,1%,1/16W,CHIP,G2A',
 PRIM_FILE='./archive_libs/mstr_discrete/res/chips/chips.prt';

PART_NAME
 R1C18 'RES_0402-2.26K,1.0%,1/16W,EMPTA':
 ROOM='PVCCIN_CPU1_VR';

SECTION_NUMBER 1
 '@BASEBOARD_FAB2_LIB.BASEBOARD_FAB2(SCH_1):PAGE206_I34@MSTR_DISCRETE.RES(CHIPS)':
 C_PATH='@baseboard_fab2_lib.baseboard_fab2(sch_1):page206_i34@mstr_discrete.res~
(chips)',
 P_PATH='@baseboard_fab2_lib.baseboard_fab2(sch_1):page206_i34@mstr_discrete.res~
(chips)',
 PATH='I34',
 DRAWING='@BASEBOARD_FAB2_LIB.BASEBOARD_FAB2(SCH_1):PAGE206',
 WATTAGE='1/16W',
 TOLERANCE='1.0%',
 SEC_TYPE='0402',
 MATERIAL='EMPTY',
 PHYS_PAGE='206',
 XY='(-2225,3750)',
 ROT='0',
 VER='2',
 VALUE='2.26K',
 PACK_TYPE='0402',
 PART_NUMBER='G21796-311',
 LOCATION='R1C18',
 ROOM='PVCCIN_CPU1_VR',
 SEC='1',
 CDS_LIB='mstr_discrete',
 CDS_PART_NAME='RES_0402-2.26K,1.0%,1/16W,EMPTA',
 PRIM_FILE='./archive_libs/mstr_discrete/res/chips/chips.prt';

PART_NAME
 R1C21 'RES_0402-10.0,1%,1/16W,CHIP,G2A':
 ROOM='PVCCIN_CPU1_VR',
 NO_XNET_CONNECTION='1';

SECTION_NUMBER 1
 '@BASEBOARD_FAB2_LIB.BASEBOARD_FAB2(SCH_1):PAGE206_I77@MSTR_DISCRETE.RES(CHIPS)':
 C_PATH='@baseboard_fab2_lib.baseboard_fab2(sch_1):page206_i77@mstr_discrete.res~
(chips)',
 P_PATH='@baseboard_fab2_lib.baseboard_fab2(sch_1):page206_i77@mstr_discrete.res~
(chips)',
 PATH='I77',
 DRAWING='@BASEBOARD_FAB2_LIB.BASEBOARD_FAB2(SCH_1):PAGE206',
 WATTAGE='1/16W',
 TOLERANCE='1%',
 SEC_TYPE='0402',
 MATERIAL='CHIP',
 NO_XNET_CONNECTION='1',
 PHYS_PAGE='206',
 XY='(-6350,2075)',
 ROT='0',
 VER='1',
 VALUE='10.0',
 PACK_TYPE='0402',
 PART_NUMBER='G21796-066',
 LOCATION='R1C21',
 ROOM='PVCCIN_CPU1_VR',
 SEC='1',
 CDS_LIB='mstr_discrete',
 CDS_PART_NAME='RES_0402-10.0,1%,1/16W,CHIP,G2A',
 PRIM_FILE='./archive_libs/mstr_discrete/res/chips/chips.prt';

PART_NAME
 R1C28 'RES_0402-1.00K,1%,1/16W,CHIP,GA':
 ROOM='PVCCIN_CPU1_VR';

SECTION_NUMBER 1
 '@BASEBOARD_FAB2_LIB.BASEBOARD_FAB2(SCH_1):PAGE206_I35@MSTR_DISCRETE.RES(CHIPS)':
 C_PATH='@baseboard_fab2_lib.baseboard_fab2(sch_1):page206_i35@mstr_discrete.res~
(chips)',
 P_PATH='@baseboard_fab2_lib.baseboard_fab2(sch_1):page206_i35@mstr_discrete.res~
(chips)',
 PATH='I35',
 DRAWING='@BASEBOARD_FAB2_LIB.BASEBOARD_FAB2(SCH_1):PAGE206',
 WATTAGE='1/16W',
 TOLERANCE='1%',
 SEC_TYPE='0402',
 MATERIAL='CHIP',
 PHYS_PAGE='206',
 XY='(-2725,3925)',
 ROT='0',
 VER='2',
 VALUE='1.00K',
 PACK_TYPE='0402',
 PART_NUMBER='G21796-026',
 LOCATION='R1C28',
 ROOM='PVCCIN_CPU1_VR',
 SEC='1',
 CDS_LIB='mstr_discrete',
 CDS_PART_NAME='RES_0402-1.00K,1%,1/16W,CHIP,GA',
 PRIM_FILE='./archive_libs/mstr_discrete/res/chips/chips.prt';

PART_NAME
 R1C30 'RES_0402-22.1,1.0%,1/16W,CHIP,A':
 ROOM='PVCCIN_CPU1_VR';

SECTION_NUMBER 1
 '@BASEBOARD_FAB2_LIB.BASEBOARD_FAB2(SCH_1):PAGE206_I113@MSTR_DISCRETE.RES(CHIPS)':
 C_PATH='@baseboard_fab2_lib.baseboard_fab2(sch_1):page206_i113@mstr_discrete.re~
s(chips)',
 P_PATH='@baseboard_fab2_lib.baseboard_fab2(sch_1):page206_i113@mstr_discrete.re~
s(chips)',
 PATH='I113',
 DRAWING='@BASEBOARD_FAB2_LIB.BASEBOARD_FAB2(SCH_1):PAGE206',
 WATTAGE='1/16W',
 TOLERANCE='1.0%',
 SEC_TYPE='0402',
 MATERIAL='CHIP',
 PHYS_PAGE='206',
 XY='(-1200,3375)',
 ROT='0',
 VER='1',
 VALUE='22.1',
 PACK_TYPE='0402',
 PART_NUMBER='G21796-250',
 LOCATION='R1C30',
 ROOM='PVCCIN_CPU1_VR',
 SEC='1',
 CDS_LIB='mstr_discrete',
 CDS_PART_NAME='RES_0402-22.1,1.0%,1/16W,CHIP,A',
 PRIM_FILE='./archive_libs/mstr_discrete/res/chips/chips.prt';

PART_NAME
 R1C31 'RES_0402-0.0,5%,1/16W,EMPTY,G2A':
 ROOM='IO_SLOT',
 NO_XNET_CONNECTION='1';

SECTION_NUMBER 1
 '@BASEBOARD_FAB2_LIB.BASEBOARD_FAB2(SCH_1):PAGE182_I6@MSTR_DISCRETE.RES(CHIPS)':
 C_PATH='@baseboard_fab2_lib.baseboard_fab2(sch_1):page182_i6@mstr_discrete.res(~
chips)',
 P_PATH='@baseboard_fab2_lib.baseboard_fab2(sch_1):page182_i6@mstr_discrete.res(~
chips)',
 PATH='I6',
 DRAWING='@BASEBOARD_FAB2_LIB.BASEBOARD_FAB2(SCH_1):PAGE182',
 WATTAGE='1/16W',
 TOLERANCE='5%',
 SEC_TYPE='0402',
 MATERIAL='EMPTY',
 NO_XNET_CONNECTION='1',
 PHYS_PAGE='182',
 XY='(-7000,-175)',
 ROT='0',
 VER='1',
 VALUE='0.0',
 PACK_TYPE='0402',
 PART_NUMBER='G21497-005',
 LOCATION='R1C31',
 ROOM='IO_SLOT',
 SEC='1',
 CDS_LIB='mstr_discrete',
 CDS_PART_NAME='RES_0402-0.0,5%,1/16W,EMPTY,G2A',
 PRIM_FILE='./archive_libs/mstr_discrete/res/chips/chips.prt';

PART_NAME
 R1C32 'RES_0402-1.00K,1%,1/16W,CHIP,GA':
 ROOM='CPU1';

SECTION_NUMBER 1
 '@BASEBOARD_FAB2_LIB.BASEBOARD_FAB2(SCH_1):PAGE156_I312@MSTR_DISCRETE.RES(CHIPS)':
 C_PATH='@baseboard_fab2_lib.baseboard_fab2(sch_1):page156_i312@mstr_discrete.re~
s(chips)',
 P_PATH='@baseboard_fab2_lib.baseboard_fab2(sch_1):page156_i312@mstr_discrete.re~
s(chips)',
 PATH='I312',
 DRAWING='@BASEBOARD_FAB2_LIB.BASEBOARD_FAB2(SCH_1):PAGE156',
 WATTAGE='1/16W',
 TOLERANCE='1%',
 SEC_TYPE='0402',
 MATERIAL='CHIP',
 PHYS_PAGE='156',
 XY='(-1900,575)',
 ROT='0',
 VER='1',
 VALUE='1.00K',
 PACK_TYPE='0402',
 PART_NUMBER='G21796-026',
 LOCATION='R1C32',
 ROOM='CPU1',
 SEC='1',
 CDS_LIB='mstr_discrete',
 CDS_PART_NAME='RES_0402-1.00K,1%,1/16W,CHIP,GA',
 PRIM_FILE='./archive_libs/mstr_discrete/res/chips/chips.prt';

PART_NAME
 R1C33 'RES_0402-1.00K,1%,1/16W,CHIP,GA':
 ROOM='CPU1';

SECTION_NUMBER 1
 '@BASEBOARD_FAB2_LIB.BASEBOARD_FAB2(SCH_1):PAGE156_I313@MSTR_DISCRETE.RES(CHIPS)':
 C_PATH='@baseboard_fab2_lib.baseboard_fab2(sch_1):page156_i313@mstr_discrete.re~
s(chips)',
 P_PATH='@baseboard_fab2_lib.baseboard_fab2(sch_1):page156_i313@mstr_discrete.re~
s(chips)',
 PATH='I313',
 DRAWING='@BASEBOARD_FAB2_LIB.BASEBOARD_FAB2(SCH_1):PAGE156',
 WATTAGE='1/16W',
 TOLERANCE='1%',
 SEC_TYPE='0402',
 MATERIAL='CHIP',
 PHYS_PAGE='156',
 XY='(-1900,775)',
 ROT='0',
 VER='1',
 VALUE='1.00K',
 PACK_TYPE='0402',
 PART_NUMBER='G21796-026',
 LOCATION='R1C33',
 ROOM='CPU1',
 SEC='1',
 CDS_LIB='mstr_discrete',
 CDS_PART_NAME='RES_0402-1.00K,1%,1/16W,CHIP,GA',
 PRIM_FILE='./archive_libs/mstr_discrete/res/chips/chips.prt';

PART_NAME
 R1C34 'RES_0402-10.0K,1%,1/16W,CHIP,GA':
 ROOM='CPU1';

SECTION_NUMBER 1
 '@BASEBOARD_FAB2_LIB.BASEBOARD_FAB2(SCH_1):PAGE156_I320@MSTR_DISCRETE.RES(CHIPS)':
 C_PATH='@baseboard_fab2_lib.baseboard_fab2(sch_1):page156_i320@mstr_discrete.re~
s(chips)',
 P_PATH='@baseboard_fab2_lib.baseboard_fab2(sch_1):page156_i320@mstr_discrete.re~
s(chips)',
 PATH='I320',
 DRAWING='@BASEBOARD_FAB2_LIB.BASEBOARD_FAB2(SCH_1):PAGE156',
 WATTAGE='1/16W',
 TOLERANCE='1%',
 SEC_TYPE='0402',
 MATERIAL='CHIP',
 PHYS_PAGE='156',
 XY='(-1900,975)',
 ROT='0',
 VER='1',
 VALUE='10.0K',
 PACK_TYPE='0402',
 PART_NUMBER='G21796-016',
 LOCATION='R1C34',
 ROOM='CPU1',
 SEC='1',
 CDS_LIB='mstr_discrete',
 CDS_PART_NAME='RES_0402-10.0K,1%,1/16W,CHIP,GA',
 PRIM_FILE='./archive_libs/mstr_discrete/res/chips/chips.prt';

PART_NAME
 R1C35 'RES_0402-3.32K,1%,1/16W,EMPTY,A':
 ROOM='CPU1';

SECTION_NUMBER 1
 '@BASEBOARD_FAB2_LIB.BASEBOARD_FAB2(SCH_1):PAGE156_I336@MSTR_DISCRETE.RES(CHIPS)':
 C_PATH='@baseboard_fab2_lib.baseboard_fab2(sch_1):page156_i336@mstr_discrete.re~
s(chips)',
 P_PATH='@baseboard_fab2_lib.baseboard_fab2(sch_1):page156_i336@mstr_discrete.re~
s(chips)',
 PATH='I336',
 DRAWING='@BASEBOARD_FAB2_LIB.BASEBOARD_FAB2(SCH_1):PAGE156',
 WATTAGE='1/16W',
 TOLERANCE='1%',
 SEC_TYPE='0402',
 MATERIAL='EMPTY',
 PHYS_PAGE='156',
 XY='(-6025,1725)',
 ROT='0',
 VER='2',
 VALUE='3.32K',
 PACK_TYPE='0402',
 PART_NUMBER='G21796-027',
 LOCATION='R1C35',
 ROOM='CPU1',
 SEC='1',
 CDS_LIB='mstr_discrete',
 CDS_PART_NAME='RES_0402-3.32K,1%,1/16W,EMPTY,A',
 PRIM_FILE='./archive_libs/mstr_discrete/res/chips/chips.prt';

PART_NAME
 R1C36 'RES_0402-1.00K,1%,1/16W,CHIP,GA':
 ROOM='CPU1';

SECTION_NUMBER 1
 '@BASEBOARD_FAB2_LIB.BASEBOARD_FAB2(SCH_1):PAGE156_I337@MSTR_DISCRETE.RES(CHIPS)':
 C_PATH='@baseboard_fab2_lib.baseboard_fab2(sch_1):page156_i337@mstr_discrete.re~
s(chips)',
 P_PATH='@baseboard_fab2_lib.baseboard_fab2(sch_1):page156_i337@mstr_discrete.re~
s(chips)',
 PATH='I337',
 DRAWING='@BASEBOARD_FAB2_LIB.BASEBOARD_FAB2(SCH_1):PAGE156',
 WATTAGE='1/16W',
 TOLERANCE='1%',
 SEC_TYPE='0402',
 MATERIAL='CHIP',
 PHYS_PAGE='156',
 XY='(-6025,1350)',
 ROT='0',
 VER='2',
 VALUE='1.00K',
 PACK_TYPE='0402',
 PART_NUMBER='G21796-026',
 LOCATION='R1C36',
 ROOM='CPU1',
 SEC='1',
 CDS_LIB='mstr_discrete',
 CDS_PART_NAME='RES_0402-1.00K,1%,1/16W,CHIP,GA',
 PRIM_FILE='./archive_libs/mstr_discrete/res/chips/chips.prt';

PART_NAME
 R1C37 'RES_0402-68.1K,1%,1/16W,EMPTY,A':;

SECTION_NUMBER 1
 '@BASEBOARD_FAB2_LIB.BASEBOARD_FAB2(SCH_1):PAGE210_I52@MSTR_DISCRETE.RES(CHIPS)':
 C_PATH='@baseboard_fab2_lib.baseboard_fab2(sch_1):page210_i52@mstr_discrete.res~
(chips)',
 P_PATH='@baseboard_fab2_lib.baseboard_fab2(sch_1):page210_i52@mstr_discrete.res~
(chips)',
 PATH='I52',
 DRAWING='@BASEBOARD_FAB2_LIB.BASEBOARD_FAB2(SCH_1):PAGE210',
 WATTAGE='1/16W',
 TOLERANCE='1%',
 MATERIAL='EMPTY',
 PHYS_PAGE='210',
 XY='(-1450,3775)',
 ROT='0',
 VER='2',
 VALUE='68.1K',
 PACK_TYPE='0402',
 PART_NUMBER='G21796-187',
 LOCATION='R1C37',
 CDS_LIB='mstr_discrete',
 CDS_PART_NAME='RES_0402-68.1K,1%,1/16W,EMPTY,A',
 PRIM_FILE='./archive_libs/mstr_discrete/res/chips/chips.prt';

PART_NAME
 R1D1 'RES_0402-33.2,1%,1/16W,CHIP,G2A':;

SECTION_NUMBER 1
 '@BASEBOARD_FAB2_LIB.BASEBOARD_FAB2(SCH_1):PAGE206_I116@MSTR_DISCRETE.RES(CHIPS)':
 C_PATH='@baseboard_fab2_lib.baseboard_fab2(sch_1):page206_i116@mstr_discrete.re~
s(chips)',
 P_PATH='@baseboard_fab2_lib.baseboard_fab2(sch_1):page206_i116@mstr_discrete.re~
s(chips)',
 PATH='I116',
 DRAWING='@BASEBOARD_FAB2_LIB.BASEBOARD_FAB2(SCH_1):PAGE206',
 WATTAGE='1/16W',
 TOLERANCE='1%',
 SEC_TYPE='0402',
 MATERIAL='CHIP',
 PHYS_PAGE='206',
 XY='(-2175,2725)',
 ROT='0',
 VER='1',
 VALUE='33.2',
 PACK_TYPE='0402',
 PART_NUMBER='G21796-074',
 LOCATION='R1D1',
 SEC='1',
 CDS_LIB='mstr_discrete',
 CDS_PART_NAME='RES_0402-33.2,1%,1/16W,CHIP,G2A',
 PRIM_FILE='./archive_libs/mstr_discrete/res/chips/chips.prt';

PART_NAME
 R1D2 'RES_0402-0.0,5%,1/16W,CHIP,G21A':
 ROOM='PVCCIN_CPU1_VR';

SECTION_NUMBER 1
 '@BASEBOARD_FAB2_LIB.BASEBOARD_FAB2(SCH_1):PAGE206_I38@MSTR_DISCRETE.RES(CHIPS)':
 C_PATH='@baseboard_fab2_lib.baseboard_fab2(sch_1):page206_i38@mstr_discrete.res~
(chips)',
 P_PATH='@baseboard_fab2_lib.baseboard_fab2(sch_1):page206_i38@mstr_discrete.res~
(chips)',
 PATH='I38',
 DRAWING='@BASEBOARD_FAB2_LIB.BASEBOARD_FAB2(SCH_1):PAGE206',
 WATTAGE='1/16W',
 TOLERANCE='5%',
 SEC_TYPE='0402',
 MATERIAL='CHIP',
 PHYS_PAGE='206',
 XY='(-2500,2775)',
 ROT='0',
 VER='1',
 VALUE='0.0',
 PACK_TYPE='0402',
 PART_NUMBER='G21497-005',
 LOCATION='R1D2',
 ROOM='PVCCIN_CPU1_VR',
 SEC='1',
 CDS_LIB='mstr_discrete',
 CDS_PART_NAME='RES_0402-0.0,5%,1/16W,CHIP,G21A',
 PRIM_FILE='./archive_libs/mstr_discrete/res/chips/chips.prt';

PART_NAME
 R1D3 'RES_0402-0.0,5%,1/16W,CHIP,G21A':
 ROOM='PVCCIN_CPU1_VR';

SECTION_NUMBER 1
 '@BASEBOARD_FAB2_LIB.BASEBOARD_FAB2(SCH_1):PAGE206_I37@MSTR_DISCRETE.RES(CHIPS)':
 C_PATH='@baseboard_fab2_lib.baseboard_fab2(sch_1):page206_i37@mstr_discrete.res~
(chips)',
 P_PATH='@baseboard_fab2_lib.baseboard_fab2(sch_1):page206_i37@mstr_discrete.res~
(chips)',
 PATH='I37',
 DRAWING='@BASEBOARD_FAB2_LIB.BASEBOARD_FAB2(SCH_1):PAGE206',
 WATTAGE='1/16W',
 TOLERANCE='5%',
 SEC_TYPE='0402',
 MATERIAL='CHIP',
 PHYS_PAGE='206',
 XY='(-2125,2925)',
 ROT='0',
 VER='1',
 VALUE='0.0',
 PACK_TYPE='0402',
 PART_NUMBER='G21497-005',
 LOCATION='R1D3',
 ROOM='PVCCIN_CPU1_VR',
 SEC='1',
 CDS_LIB='mstr_discrete',
 CDS_PART_NAME='RES_0402-0.0,5%,1/16W,CHIP,G21A',
 PRIM_FILE='./archive_libs/mstr_discrete/res/chips/chips.prt';

PART_NAME
 R1D4 'RES_0402-10.0,1%,1/16W,CHIP,G2A':
 ROOM='PVCCIN_CPU1_VR',
 NO_XNET_CONNECTION='1';

SECTION_NUMBER 1
 '@BASEBOARD_FAB2_LIB.BASEBOARD_FAB2(SCH_1):PAGE206_I79@MSTR_DISCRETE.RES(CHIPS)':
 C_PATH='@baseboard_fab2_lib.baseboard_fab2(sch_1):page206_i79@mstr_discrete.res~
(chips)',
 P_PATH='@baseboard_fab2_lib.baseboard_fab2(sch_1):page206_i79@mstr_discrete.res~
(chips)',
 PATH='I79',
 DRAWING='@BASEBOARD_FAB2_LIB.BASEBOARD_FAB2(SCH_1):PAGE206',
 WATTAGE='1/16W',
 TOLERANCE='1%',
 SEC_TYPE='0402',
 MATERIAL='CHIP',
 NO_XNET_CONNECTION='1',
 PHYS_PAGE='206',
 XY='(-6775,2575)',
 ROT='0',
 VER='1',
 VALUE='10.0',
 PACK_TYPE='0402',
 PART_NUMBER='G21796-066',
 LOCATION='R1D4',
 ROOM='PVCCIN_CPU1_VR',
 SEC='1',
 CDS_LIB='mstr_discrete',
 CDS_PART_NAME='RES_0402-10.0,1%,1/16W,CHIP,G2A',
 PRIM_FILE='./archive_libs/mstr_discrete/res/chips/chips.prt';

PART_NAME
 R1D6 'RES_0402-1.00K,1%,1/16W,CHIP,GA':
 ROOM='PVCCIN_CPU1_VR';

SECTION_NUMBER 1
 '@BASEBOARD_FAB2_LIB.BASEBOARD_FAB2(SCH_1):PAGE206_I6@MSTR_DISCRETE.RES(CHIPS)':
 C_PATH='@baseboard_fab2_lib.baseboard_fab2(sch_1):page206_i6@mstr_discrete.res(~
chips)',
 P_PATH='@baseboard_fab2_lib.baseboard_fab2(sch_1):page206_i6@mstr_discrete.res(~
chips)',
 PATH='I6',
 DRAWING='@BASEBOARD_FAB2_LIB.BASEBOARD_FAB2(SCH_1):PAGE206',
 WATTAGE='1/16W',
 TOLERANCE='1%',
 SEC_TYPE='0402',
 MATERIAL='CHIP',
 PHYS_PAGE='206',
 XY='(-3150,4000)',
 ROT='2',
 VER='2',
 VALUE='1.00K',
 PACK_TYPE='0402',
 PART_NUMBER='G21796-026',
 LOCATION='R1D6',
 ROOM='PVCCIN_CPU1_VR',
 SEC='1',
 CDS_LIB='mstr_discrete',
 CDS_PART_NAME='RES_0402-1.00K,1%,1/16W,CHIP,GA',
 PRIM_FILE='./archive_libs/mstr_discrete/res/chips/chips.prt';

PART_NAME
 R1D7 'RES_0402-1.00K,1%,1/16W,CHIP,GA':
 ROOM='PVCCIN_CPU1_VR';

SECTION_NUMBER 1
 '@BASEBOARD_FAB2_LIB.BASEBOARD_FAB2(SCH_1):PAGE206_I155@MSTR_DISCRETE.RES(CHIPS)':
 C_PATH='@baseboard_fab2_lib.baseboard_fab2(sch_1):page206_i155@mstr_discrete.re~
s(chips)',
 P_PATH='@baseboard_fab2_lib.baseboard_fab2(sch_1):page206_i155@mstr_discrete.re~
s(chips)',
 PATH='I155',
 DRAWING='@BASEBOARD_FAB2_LIB.BASEBOARD_FAB2(SCH_1):PAGE206',
 WATTAGE='1/16W',
 TOLERANCE='1%',
 SEC_TYPE='0402',
 MATERIAL='CHIP',
 PHYS_PAGE='206',
 XY='(-2050,4150)',
 ROT='0',
 VER='2',
 VALUE='1.00K',
 PACK_TYPE='0402',
 PART_NUMBER='G21796-026',
 LOCATION='R1D7',
 ROOM='PVCCIN_CPU1_VR',
 SEC='1',
 CDS_LIB='mstr_discrete',
 CDS_PART_NAME='RES_0402-1.00K,1%,1/16W,CHIP,GA',
 PRIM_FILE='./archive_libs/mstr_discrete/res/chips/chips.prt';

PART_NAME
 R1D8 'RES_0402-1.00K,1%,1/16W,CHIP,GA':
 ROOM='PVCCIN_CPU1_VR';

SECTION_NUMBER 1
 '@BASEBOARD_FAB2_LIB.BASEBOARD_FAB2(SCH_1):PAGE206_I36@MSTR_DISCRETE.RES(CHIPS)':
 C_PATH='@baseboard_fab2_lib.baseboard_fab2(sch_1):page206_i36@mstr_discrete.res~
(chips)',
 P_PATH='@baseboard_fab2_lib.baseboard_fab2(sch_1):page206_i36@mstr_discrete.res~
(chips)',
 PATH='I36',
 DRAWING='@BASEBOARD_FAB2_LIB.BASEBOARD_FAB2(SCH_1):PAGE206',
 WATTAGE='1/16W',
 TOLERANCE='1%',
 SEC_TYPE='0402',
 MATERIAL='CHIP',
 PHYS_PAGE='206',
 XY='(-2875,3925)',
 ROT='2',
 VER='2',
 VALUE='1.00K',
 PACK_TYPE='0402',
 PART_NUMBER='G21796-026',
 LOCATION='R1D8',
 ROOM='PVCCIN_CPU1_VR',
 SEC='1',
 CDS_LIB='mstr_discrete',
 CDS_PART_NAME='RES_0402-1.00K,1%,1/16W,CHIP,GA',
 PRIM_FILE='./archive_libs/mstr_discrete/res/chips/chips.prt';

PART_NAME
 R1D9 'RES_0402-150.0,1%,1/16W,CHIP,GA':
 ROOM='PVCCIN_CPU1_VR';

SECTION_NUMBER 1
 '@BASEBOARD_FAB2_LIB.BASEBOARD_FAB2(SCH_1):PAGE206_I54@MSTR_DISCRETE.RES(CHIPS)':
 C_PATH='@baseboard_fab2_lib.baseboard_fab2(sch_1):page206_i54@mstr_discrete.res~
(chips)',
 P_PATH='@baseboard_fab2_lib.baseboard_fab2(sch_1):page206_i54@mstr_discrete.res~
(chips)',
 PATH='I54',
 DRAWING='@BASEBOARD_FAB2_LIB.BASEBOARD_FAB2(SCH_1):PAGE206',
 WATTAGE='1/16W',
 TOLERANCE='1%',
 MATERIAL='CHIP',
 PHYS_PAGE='206',
 XY='(-5375,3900)',
 ROT='0',
 VER='1',
 VALUE='150.0',
 PACK_TYPE='0402',
 PART_NUMBER='G21796-009',
 LOCATION='R1D9',
 ROOM='PVCCIN_CPU1_VR',
 CDS_LIB='mstr_discrete',
 CDS_PART_NAME='RES_0402-150.0,1%,1/16W,CHIP,GA',
 PRIM_FILE='./archive_libs/mstr_discrete/res/chips/chips.prt';

PART_NAME
 R1D10 'RES_0402-10.0K,1%,1/16W,CHIP,GA':
 ROOM='HOT_SWAP';

SECTION_NUMBER 1
 '@BASEBOARD_FAB2_LIB.BASEBOARD_FAB2(SCH_1):PAGE200_I244@MSTR_DISCRETE.RES(CHIPS)':
 C_PATH='@baseboard_fab2_lib.baseboard_fab2(sch_1):page200_i244@mstr_discrete.re~
s(chips)',
 P_PATH='@baseboard_fab2_lib.baseboard_fab2(sch_1):page200_i244@mstr_discrete.re~
s(chips)',
 PATH='I244',
 DRAWING='@BASEBOARD_FAB2_LIB.BASEBOARD_FAB2(SCH_1):PAGE200',
 WATTAGE='1/16W',
 TOLERANCE='1%',
 SEC_TYPE='0402',
 MATERIAL='CHIP',
 PHYS_PAGE='200',
 XY='(-2600,3550)',
 ROT='0',
 VER='2',
 VALUE='10.0K',
 PACK_TYPE='0402',
 PART_NUMBER='G21796-016',
 LOCATION='R1D10',
 ROOM='HOT_SWAP',
 SEC='1',
 CDS_LIB='mstr_discrete',
 CDS_PART_NAME='RES_0402-10.0K,1%,1/16W,CHIP,GA',
 PRIM_FILE='./archive_libs/mstr_discrete/res/chips/chips.prt';

PART_NAME
 R1D11 'RES_0402-100.0K,1%,1/16W,CHIP,A':
 ROOM='HOT_SWAP';

SECTION_NUMBER 1
 '@BASEBOARD_FAB2_LIB.BASEBOARD_FAB2(SCH_1):PAGE199_I88@MSTR_DISCRETE.RES(CHIPS)':
 C_PATH='@baseboard_fab2_lib.baseboard_fab2(sch_1):page199_i88@mstr_discrete.res~
(chips)',
 P_PATH='@baseboard_fab2_lib.baseboard_fab2(sch_1):page199_i88@mstr_discrete.res~
(chips)',
 PATH='I88',
 DRAWING='@BASEBOARD_FAB2_LIB.BASEBOARD_FAB2(SCH_1):PAGE199',
 WATTAGE='1/16W',
 TOLERANCE='1%',
 SEC_TYPE='0402',
 MATERIAL='CHIP',
 PHYS_PAGE='199',
 XY='(-6300,-50)',
 ROT='0',
 VER='2',
 VALUE='100.0K',
 PACK_TYPE='0402',
 PART_NUMBER='G21796-010',
 LOCATION='R1D11',
 ROOM='HOT_SWAP',
 SEC='1',
 CDS_LIB='mstr_discrete',
 CDS_PART_NAME='RES_0402-100.0K,1%,1/16W,CHIP,A',
 PRIM_FILE='./archive_libs/mstr_discrete/res/chips/chips.prt';

PART_NAME
 R1D12 'RES_0402-10.0K,1%,1/16W,CHIP,GA':
 ROOM='HOT_SWAP';

SECTION_NUMBER 1
 '@BASEBOARD_FAB2_LIB.BASEBOARD_FAB2(SCH_1):PAGE200_I174@MSTR_DISCRETE.RES(CHIPS)':
 C_PATH='@baseboard_fab2_lib.baseboard_fab2(sch_1):page200_i174@mstr_discrete.re~
s(chips)',
 P_PATH='@baseboard_fab2_lib.baseboard_fab2(sch_1):page200_i174@mstr_discrete.re~
s(chips)',
 PATH='I174',
 DRAWING='@BASEBOARD_FAB2_LIB.BASEBOARD_FAB2(SCH_1):PAGE200',
 CONFIG='64.1002D.6DL',
 WATTAGE='1/16W',
 TOLERANCE='1%',
 SEC_TYPE='0402',
 MATERIAL='CHIP',
 PHYS_PAGE='200',
 XY='(-4575,2875)',
 ROT='0',
 VER='2',
 VALUE='10.0K',
 PACK_TYPE='0402',
 PART_NUMBER='G21796-016',
 LOCATION='R1D12',
 ROOM='HOT_SWAP',
 SEC='1',
 CDS_LIB='mstr_discrete',
 CDS_PART_NAME='RES_0402-10.0K,1%,1/16W,CHIP,GA',
 PRIM_FILE='./archive_libs/mstr_discrete/res/chips/chips.prt';

PART_NAME
 R1D13 'RES_0402-90.9K,1%,1/16W,CHIP,GA':
 ROOM='HOT_SWAP',
 NO_XNET_CONNECTION='1';

SECTION_NUMBER 1
 '@BASEBOARD_FAB2_LIB.BASEBOARD_FAB2(SCH_1):PAGE199_I84@MSTR_DISCRETE.RES(CHIPS)':
 C_PATH='@baseboard_fab2_lib.baseboard_fab2(sch_1):page199_i84@mstr_discrete.res~
(chips)',
 P_PATH='@baseboard_fab2_lib.baseboard_fab2(sch_1):page199_i84@mstr_discrete.res~
(chips)',
 PATH='I84',
 DRAWING='@BASEBOARD_FAB2_LIB.BASEBOARD_FAB2(SCH_1):PAGE199',
 BOM_DS='64.68125.6DL',
 WATTAGE='1/16W',
 TOLERANCE='1%',
 SEC_TYPE='0402',
 MATERIAL='CHIP',
 NO_XNET_CONNECTION='1',
 PHYS_PAGE='199',
 XY='(-6600,975)',
 ROT='1',
 VER='1',
 VALUE='90.9K',
 PACK_TYPE='0402',
 PART_NUMBER='G21796-058',
 LOCATION='R1D13',
 ROOM='HOT_SWAP',
 SEC='1',
 CDS_LIB='mstr_discrete',
 CDS_PART_NAME='RES_0402-90.9K,1%,1/16W,CHIP,GA',
 PRIM_FILE='./archive_libs/mstr_discrete/res/chips/chips.prt';

PART_NAME
 R1D14 'RES_0402-105.0K,1%,1/16W,CHIP,A':;

SECTION_NUMBER 1
 '@BASEBOARD_FAB2_LIB.BASEBOARD_FAB2(SCH_1):PAGE200_I246@MSTR_DISCRETE.RES(CHIPS)':
 C_PATH='@baseboard_fab2_lib.baseboard_fab2(sch_1):page200_i246@mstr_discrete.re~
s(chips)',
 P_PATH='@baseboard_fab2_lib.baseboard_fab2(sch_1):page200_i246@mstr_discrete.re~
s(chips)',
 PATH='I246',
 DRAWING='@BASEBOARD_FAB2_LIB.BASEBOARD_FAB2(SCH_1):PAGE200',
 BOM_SS='64.16535.6DL',
 BOM_DS='64.15435.6DL',
 WATTAGE='1/16W',
 TOLERANCE='1%',
 SEC_TYPE='0402',
 MATERIAL='CHIP',
 PHYS_PAGE='200',
 XY='(-4575,3450)',
 ROT='0',
 VER='2',
 VALUE='105.0K',
 PACK_TYPE='0402',
 PART_NUMBER='G21796-099',
 LOCATION='R1D14',
 SEC='1',
 CDS_LIB='mstr_discrete',
 CDS_PART_NAME='RES_0402-105.0K,1%,1/16W,CHIP,A',
 PRIM_FILE='./archive_libs/mstr_discrete/res/chips/chips.prt';

PART_NAME
 R1D15 'RES_0402-100.0K,1%,1/16W,CHIP,A':
 ROOM='HOT_SWAP';

SECTION_NUMBER 1
 '@BASEBOARD_FAB2_LIB.BASEBOARD_FAB2(SCH_1):PAGE199_I92@MSTR_DISCRETE.RES(CHIPS)':
 C_PATH='@baseboard_fab2_lib.baseboard_fab2(sch_1):page199_i92@mstr_discrete.res~
(chips)',
 P_PATH='@baseboard_fab2_lib.baseboard_fab2(sch_1):page199_i92@mstr_discrete.res~
(chips)',
 PATH='I92',
 DRAWING='@BASEBOARD_FAB2_LIB.BASEBOARD_FAB2(SCH_1):PAGE199',
 WATTAGE='1/16W',
 TOLERANCE='1%',
 SEC_TYPE='0402',
 MATERIAL='CHIP',
 PHYS_PAGE='199',
 XY='(-7300,750)',
 ROT='0',
 VER='2',
 VALUE='100.0K',
 PACK_TYPE='0402',
 PART_NUMBER='G21796-010',
 LOCATION='R1D15',
 ROOM='HOT_SWAP',
 SEC='1',
 CDS_LIB='mstr_discrete',
 CDS_PART_NAME='RES_0402-100.0K,1%,1/16W,CHIP,A',
 PRIM_FILE='./archive_libs/mstr_discrete/res/chips/chips.prt';

PART_NAME
 R1D16 'RES_0402-69.8K,1%,1/16W,CHIP,GA':
 ROOM='HOT_SWAP',
 NO_XNET_CONNECTION='1';

SECTION_NUMBER 1
 '@BASEBOARD_FAB2_LIB.BASEBOARD_FAB2(SCH_1):PAGE199_I85@MSTR_DISCRETE.RES(CHIPS)':
 C_PATH='@baseboard_fab2_lib.baseboard_fab2(sch_1):page199_i85@mstr_discrete.res~
(chips)',
 P_PATH='@baseboard_fab2_lib.baseboard_fab2(sch_1):page199_i85@mstr_discrete.res~
(chips)',
 PATH='I85',
 DRAWING='@BASEBOARD_FAB2_LIB.BASEBOARD_FAB2(SCH_1):PAGE199',
 BOM_DS='64.57625.6DL',
 WATTAGE='1/16W',
 TOLERANCE='1%',
 SEC_TYPE='0402',
 MATERIAL='CHIP',
 NO_XNET_CONNECTION='1',
 PHYS_PAGE='199',
 XY='(-5875,875)',
 ROT='0',
 VER='2',
 VALUE='69.8K',
 PACK_TYPE='0402',
 PART_NUMBER='G21796-007',
 LOCATION='R1D16',
 ROOM='HOT_SWAP',
 SEC='1',
 CDS_LIB='mstr_discrete',
 CDS_PART_NAME='RES_0402-69.8K,1%,1/16W,CHIP,GA',
 PRIM_FILE='./archive_libs/mstr_discrete/res/chips/chips.prt';

PART_NAME
 R1D18 'RES_0402-100.0K,1%,1/16W,CHIP,A':
 ROOM='HOT_SWAP';

SECTION_NUMBER 1
 '@BASEBOARD_FAB2_LIB.BASEBOARD_FAB2(SCH_1):PAGE199_I87@MSTR_DISCRETE.RES(CHIPS)':
 C_PATH='@baseboard_fab2_lib.baseboard_fab2(sch_1):page199_i87@mstr_discrete.res~
(chips)',
 P_PATH='@baseboard_fab2_lib.baseboard_fab2(sch_1):page199_i87@mstr_discrete.res~
(chips)',
 PATH='I87',
 DRAWING='@BASEBOARD_FAB2_LIB.BASEBOARD_FAB2(SCH_1):PAGE199',
 WATTAGE='1/16W',
 TOLERANCE='1%',
 SEC_TYPE='0402',
 MATERIAL='CHIP',
 PHYS_PAGE='199',
 XY='(-6950,-50)',
 ROT='0',
 VER='2',
 VALUE='100.0K',
 PACK_TYPE='0402',
 PART_NUMBER='G21796-010',
 LOCATION='R1D18',
 ROOM='HOT_SWAP',
 SEC='1',
 CDS_LIB='mstr_discrete',
 CDS_PART_NAME='RES_0402-100.0K,1%,1/16W,CHIP,A',
 PRIM_FILE='./archive_libs/mstr_discrete/res/chips/chips.prt';

PART_NAME
 R1D19 'RES_0402-10.0K,1%,1/16W,CHIP,GA':
 ROOM='HOT_SWAP';

SECTION_NUMBER 1
 '@BASEBOARD_FAB2_LIB.BASEBOARD_FAB2(SCH_1):PAGE200_I175@MSTR_DISCRETE.RES(CHIPS)':
 C_PATH='@baseboard_fab2_lib.baseboard_fab2(sch_1):page200_i175@mstr_discrete.re~
s(chips)',
 P_PATH='@baseboard_fab2_lib.baseboard_fab2(sch_1):page200_i175@mstr_discrete.re~
s(chips)',
 PATH='I175',
 DRAWING='@BASEBOARD_FAB2_LIB.BASEBOARD_FAB2(SCH_1):PAGE200',
 CONFIG='64.1002D.6DL',
 WATTAGE='1/16W',
 TOLERANCE='1%',
 SEC_TYPE='0402',
 MATERIAL='CHIP',
 PHYS_PAGE='200',
 XY='(-4150,2450)',
 ROT='0',
 VER='2',
 VALUE='10.0K',
 PACK_TYPE='0402',
 PART_NUMBER='G21796-016',
 LOCATION='R1D19',
 ROOM='HOT_SWAP',
 SEC='1',
 CDS_LIB='mstr_discrete',
 CDS_PART_NAME='RES_0402-10.0K,1%,1/16W,CHIP,GA',
 PRIM_FILE='./archive_libs/mstr_discrete/res/chips/chips.prt';

PART_NAME
 R1D20 'RES_0402-200.0K,1%,1/16W,CHIP,A':
 ROOM='BMC_VOLT_MONITOR';

SECTION_NUMBER 1
 '@BASEBOARD_FAB2_LIB.BASEBOARD_FAB2(SCH_1):PAGE200_I253@MSTR_DISCRETE.RES(CHIPS)':
 C_PATH='@baseboard_fab2_lib.baseboard_fab2(sch_1):page200_i253@mstr_discrete.re~
s(chips)',
 P_PATH='@baseboard_fab2_lib.baseboard_fab2(sch_1):page200_i253@mstr_discrete.re~
s(chips)',
 PATH='I253',
 DRAWING='@BASEBOARD_FAB2_LIB.BASEBOARD_FAB2(SCH_1):PAGE200',
 BOM_DS='64.16935.6DL',
 WATTAGE='1/16W',
 TOLERANCE='1%',
 SEC_TYPE='0402',
 MATERIAL='CHIP',
 BOM_COST='SM_HM',
 PHYS_PAGE='200',
 XY='(-4150,2825)',
 ROT='0',
 VER='2',
 VALUE='200.0K',
 PACK_TYPE='0402',
 PART_NUMBER='G21796-080',
 LOCATION='R1D20',
 ROOM='BMC_VOLT_MONITOR',
 SEC='1',
 CDS_LIB='mstr_discrete',
 CDS_PART_NAME='RES_0402-200.0K,1%,1/16W,CHIP,A',
 PRIM_FILE='./archive_libs/mstr_discrete/res/chips/chips.prt';

PART_NAME
 R1D21 'RES_0402-4.75K,1%,1/16W,CHIP,GA':
 ROOM='HOT_SWAP';

SECTION_NUMBER 1
 '@BASEBOARD_FAB2_LIB.BASEBOARD_FAB2(SCH_1):PAGE200_I204@MSTR_DISCRETE.RES(CHIPS)':
 C_PATH='@baseboard_fab2_lib.baseboard_fab2(sch_1):page200_i204@mstr_discrete.re~
s(chips)',
 P_PATH='@baseboard_fab2_lib.baseboard_fab2(sch_1):page200_i204@mstr_discrete.re~
s(chips)',
 PATH='I204',
 DRAWING='@BASEBOARD_FAB2_LIB.BASEBOARD_FAB2(SCH_1):PAGE200',
 WATTAGE='1/16W',
 TOLERANCE='1%',
 SEC_TYPE='0402',
 MATERIAL='CHIP',
 PHYS_PAGE='200',
 XY='(-3500,1750)',
 ROT='0',
 VER='2',
 VALUE='4.75K',
 PACK_TYPE='0402',
 PART_NUMBER='G21796-072',
 LOCATION='R1D21',
 ROOM='HOT_SWAP',
 SEC='1',
 CDS_LIB='mstr_discrete',
 CDS_PART_NAME='RES_0402-4.75K,1%,1/16W,CHIP,GA',
 PRIM_FILE='./archive_libs/mstr_discrete/res/chips/chips.prt';

PART_NAME
 R1D22 'RES_0402-10.0K,1%,1/16W,CHIP,GA':
 ROOM='HOT_SWAP';

SECTION_NUMBER 1
 '@BASEBOARD_FAB2_LIB.BASEBOARD_FAB2(SCH_1):PAGE200_I158@MSTR_DISCRETE.RES(CHIPS)':
 C_PATH='@baseboard_fab2_lib.baseboard_fab2(sch_1):page200_i158@mstr_discrete.re~
s(chips)',
 P_PATH='@baseboard_fab2_lib.baseboard_fab2(sch_1):page200_i158@mstr_discrete.re~
s(chips)',
 PATH='I158',
 DRAWING='@BASEBOARD_FAB2_LIB.BASEBOARD_FAB2(SCH_1):PAGE200',
 WATTAGE='1/16W',
 TOLERANCE='1%',
 SEC_TYPE='0402',
 MATERIAL='CHIP',
 PHYS_PAGE='200',
 XY='(-1650,2350)',
 ROT='0',
 VER='2',
 VALUE='10.0K',
 PACK_TYPE='0402',
 PART_NUMBER='G21796-016',
 LOCATION='R1D22',
 ROOM='HOT_SWAP',
 SEC='1',
 CDS_LIB='mstr_discrete',
 CDS_PART_NAME='RES_0402-10.0K,1%,1/16W,CHIP,GA',
 PRIM_FILE='./archive_libs/mstr_discrete/res/chips/chips.prt';

PART_NAME
 R1D23 'RES_0402-10.0K,1%,1/16W,CHIP,GA':
 ROOM='HOT_SWAP';

SECTION_NUMBER 1
 '@BASEBOARD_FAB2_LIB.BASEBOARD_FAB2(SCH_1):PAGE200_I191@MSTR_DISCRETE.RES(CHIPS)':
 C_PATH='@baseboard_fab2_lib.baseboard_fab2(sch_1):page200_i191@mstr_discrete.re~
s(chips)',
 P_PATH='@baseboard_fab2_lib.baseboard_fab2(sch_1):page200_i191@mstr_discrete.re~
s(chips)',
 PATH='I191',
 DRAWING='@BASEBOARD_FAB2_LIB.BASEBOARD_FAB2(SCH_1):PAGE200',
 WATTAGE='1/16W',
 TOLERANCE='1%',
 SEC_TYPE='0402',
 MATERIAL='CHIP',
 PHYS_PAGE='200',
 XY='(-2950,3550)',
 ROT='0',
 VER='2',
 VALUE='10.0K',
 PACK_TYPE='0402',
 PART_NUMBER='G21796-016',
 LOCATION='R1D23',
 ROOM='HOT_SWAP',
 SEC='1',
 CDS_LIB='mstr_discrete',
 CDS_PART_NAME='RES_0402-10.0K,1%,1/16W,CHIP,GA',
 PRIM_FILE='./archive_libs/mstr_discrete/res/chips/chips.prt';

PART_NAME
 R1D24 'RES_0402-0.0,5%,1/16W,CHIP,G21A':
 ROOM='HOT_SWAP';

SECTION_NUMBER 1
 '@BASEBOARD_FAB2_LIB.BASEBOARD_FAB2(SCH_1):PAGE199_I27@MSTR_DISCRETE.RES(CHIPS)':
 C_PATH='@baseboard_fab2_lib.baseboard_fab2(sch_1):page199_i27@mstr_discrete.res~
(chips)',
 P_PATH='@baseboard_fab2_lib.baseboard_fab2(sch_1):page199_i27@mstr_discrete.res~
(chips)',
 PATH='I27',
 DRAWING='@BASEBOARD_FAB2_LIB.BASEBOARD_FAB2(SCH_1):PAGE199',
 WATTAGE='1/16W',
 TOLERANCE='5%',
 SEC_TYPE='0402',
 MATERIAL='CHIP',
 PHYS_PAGE='199',
 XY='(-5600,2725)',
 ROT='0',
 VER='1',
 VALUE='0.0',
 PACK_TYPE='0402',
 PART_NUMBER='G21497-005',
 LOCATION='R1D24',
 ROOM='HOT_SWAP',
 SEC='1',
 CDS_LIB='mstr_discrete',
 CDS_PART_NAME='RES_0402-0.0,5%,1/16W,CHIP,G21A',
 PRIM_FILE='./archive_libs/mstr_discrete/res/chips/chips.prt';

PART_NAME
 R1D25 'RES_0402-0.0,5%,1/16W,CHIP,G21A':
 ROOM='HOT_SWAP';

SECTION_NUMBER 1
 '@BASEBOARD_FAB2_LIB.BASEBOARD_FAB2(SCH_1):PAGE199_I28@MSTR_DISCRETE.RES(CHIPS)':
 C_PATH='@baseboard_fab2_lib.baseboard_fab2(sch_1):page199_i28@mstr_discrete.res~
(chips)',
 P_PATH='@baseboard_fab2_lib.baseboard_fab2(sch_1):page199_i28@mstr_discrete.res~
(chips)',
 PATH='I28',
 DRAWING='@BASEBOARD_FAB2_LIB.BASEBOARD_FAB2(SCH_1):PAGE199',
 WATTAGE='1/16W',
 TOLERANCE='5%',
 SEC_TYPE='0402',
 MATERIAL='CHIP',
 PHYS_PAGE='199',
 XY='(-5600,2675)',
 ROT='0',
 VER='1',
 VALUE='0.0',
 PACK_TYPE='0402',
 PART_NUMBER='G21497-005',
 LOCATION='R1D25',
 ROOM='HOT_SWAP',
 SEC='1',
 CDS_LIB='mstr_discrete',
 CDS_PART_NAME='RES_0402-0.0,5%,1/16W,CHIP,G21A',
 PRIM_FILE='./archive_libs/mstr_discrete/res/chips/chips.prt';

PART_NAME
 R1D26 'RES_0402-33.2,1%,1/16W,CHIP,G2A':;

SECTION_NUMBER 1
 '@BASEBOARD_FAB2_LIB.BASEBOARD_FAB2(SCH_1):PAGE199_I109@MSTR_DISCRETE.RES(CHIPS)':
 C_PATH='@baseboard_fab2_lib.baseboard_fab2(sch_1):page199_i109@mstr_discrete.re~
s(chips)',
 P_PATH='@baseboard_fab2_lib.baseboard_fab2(sch_1):page199_i109@mstr_discrete.re~
s(chips)',
 PATH='I109',
 DRAWING='@BASEBOARD_FAB2_LIB.BASEBOARD_FAB2(SCH_1):PAGE199',
 WATTAGE='1/16W',
 TOLERANCE='1%',
 SEC_TYPE='0402',
 MATERIAL='CHIP',
 PHYS_PAGE='199',
 XY='(-1700,3950)',
 ROT='0',
 VER='1',
 VALUE='33.2',
 PACK_TYPE='0402',
 PART_NUMBER='G21796-074',
 LOCATION='R1D26',
 SEC='1',
 CDS_LIB='mstr_discrete',
 CDS_PART_NAME='RES_0402-33.2,1%,1/16W,CHIP,G2A',
 PRIM_FILE='./archive_libs/mstr_discrete/res/chips/chips.prt';

PART_NAME
 R1D27 'RES_0402-4.75K,1%,1/16W,EMPTY,A':
 ROOM='HOT_SWAP',
 NO_XNET_CONNECTION='1';

SECTION_NUMBER 1
 '@BASEBOARD_FAB2_LIB.BASEBOARD_FAB2(SCH_1):PAGE199_I38@MSTR_DISCRETE.RES(CHIPS)':
 C_PATH='@baseboard_fab2_lib.baseboard_fab2(sch_1):page199_i38@mstr_discrete.res~
(chips)',
 P_PATH='@baseboard_fab2_lib.baseboard_fab2(sch_1):page199_i38@mstr_discrete.res~
(chips)',
 PATH='I38',
 DRAWING='@BASEBOARD_FAB2_LIB.BASEBOARD_FAB2(SCH_1):PAGE199',
 WATTAGE='1/16W',
 TOLERANCE='1%',
 SEC_TYPE='0402',
 MATERIAL='EMPTY',
 NO_XNET_CONNECTION='1',
 PHYS_PAGE='199',
 XY='(-7675,2950)',
 ROT='0',
 VER='2',
 VALUE='4.75K',
 PACK_TYPE='0402',
 PART_NUMBER='G21796-072',
 LOCATION='R1D27',
 ROOM='HOT_SWAP',
 SEC='1',
 CDS_LIB='mstr_discrete',
 CDS_PART_NAME='RES_0402-4.75K,1%,1/16W,EMPTY,A',
 PRIM_FILE='./archive_libs/mstr_discrete/res/chips/chips.prt';

PART_NAME
 R1D28 'RES_0402-100.0,1%,1/16W,EMPTY,A':
 ROOM='HOT_SWAP';

SECTION_NUMBER 1
 '@BASEBOARD_FAB2_LIB.BASEBOARD_FAB2(SCH_1):PAGE199_I26@MSTR_DISCRETE.RES(CHIPS)':
 C_PATH='@baseboard_fab2_lib.baseboard_fab2(sch_1):page199_i26@mstr_discrete.res~
(chips)',
 P_PATH='@baseboard_fab2_lib.baseboard_fab2(sch_1):page199_i26@mstr_discrete.res~
(chips)',
 PATH='I26',
 DRAWING='@BASEBOARD_FAB2_LIB.BASEBOARD_FAB2(SCH_1):PAGE199',
 WATTAGE='1/16W',
 TOLERANCE='1%',
 SEC_TYPE='0402',
 MATERIAL='EMPTY',
 PHYS_PAGE='199',
 XY='(-4625,1025)',
 ROT='0',
 VER='2',
 VALUE='100.0',
 PACK_TYPE='0402',
 PART_NUMBER='G21796-017',
 LOCATION='R1D28',
 ROOM='HOT_SWAP',
 SEC='1',
 CDS_LIB='mstr_discrete',
 CDS_PART_NAME='RES_0402-100.0,1%,1/16W,EMPTY,A',
 PRIM_FILE='./archive_libs/mstr_discrete/res/chips/chips.prt';

PART_NAME
 R1D29 'RES_0402-4.75K,1%,1/16W,CHIP,GA':
 ROOM='CPU0';

SECTION_NUMBER 1
 '@BASEBOARD_FAB2_LIB.BASEBOARD_FAB2(SCH_1):PAGE199_I137@MSTR_DISCRETE.RES(CHIPS)':
 C_PATH='@baseboard_fab2_lib.baseboard_fab2(sch_1):page199_i137@mstr_discrete.re~
s(chips)',
 P_PATH='@baseboard_fab2_lib.baseboard_fab2(sch_1):page199_i137@mstr_discrete.re~
s(chips)',
 PATH='I137',
 DRAWING='@BASEBOARD_FAB2_LIB.BASEBOARD_FAB2(SCH_1):PAGE199',
 POP='NOPOP',
 WATTAGE='1/16W',
 TOLERANCE='1%',
 SEC_TYPE='0402',
 MATERIAL='CHIP',
 PHYS_PAGE='199',
 XY='(-8000,2950)',
 ROT='0',
 VER='2',
 VALUE='4.75K',
 PACK_TYPE='0402',
 PART_NUMBER='G21796-072',
 LOCATION='R1D29',
 ROOM='CPU0',
 SEC='1',
 CDS_LIB='mstr_discrete',
 CDS_PART_NAME='RES_0402-4.75K,1%,1/16W,CHIP,GA',
 PRIM_FILE='./archive_libs/mstr_discrete/res/chips/chips.prt';

PART_NAME
 R1D30 'RES_0402-33.2,1%,1/16W,CHIP,G2A':;

SECTION_NUMBER 1
 '@BASEBOARD_FAB2_LIB.BASEBOARD_FAB2(SCH_1):PAGE199_I110@MSTR_DISCRETE.RES(CHIPS)':
 C_PATH='@baseboard_fab2_lib.baseboard_fab2(sch_1):page199_i110@mstr_discrete.re~
s(chips)',
 P_PATH='@baseboard_fab2_lib.baseboard_fab2(sch_1):page199_i110@mstr_discrete.re~
s(chips)',
 PATH='I110',
 DRAWING='@BASEBOARD_FAB2_LIB.BASEBOARD_FAB2(SCH_1):PAGE199',
 WATTAGE='1/16W',
 TOLERANCE='1%',
 SEC_TYPE='0402',
 MATERIAL='CHIP',
 PHYS_PAGE='199',
 XY='(-2050,1375)',
 ROT='0',
 VER='1',
 VALUE='33.2',
 PACK_TYPE='0402',
 PART_NUMBER='G21796-074',
 LOCATION='R1D30',
 SEC='1',
 CDS_LIB='mstr_discrete',
 CDS_PART_NAME='RES_0402-33.2,1%,1/16W,CHIP,G2A',
 PRIM_FILE='./archive_libs/mstr_discrete/res/chips/chips.prt';

PART_NAME
 R1D31 'RES_0402-6.19K,1%,1/16W,CHIP,GA':
 ROOM='HOT_SWAP';

SECTION_NUMBER 1
 '@BASEBOARD_FAB2_LIB.BASEBOARD_FAB2(SCH_1):PAGE199_I43@MSTR_DISCRETE.RES(CHIPS)':
 C_PATH='@baseboard_fab2_lib.baseboard_fab2(sch_1):page199_i43@mstr_discrete.res~
(chips)',
 P_PATH='@baseboard_fab2_lib.baseboard_fab2(sch_1):page199_i43@mstr_discrete.res~
(chips)',
 PATH='I43',
 DRAWING='@BASEBOARD_FAB2_LIB.BASEBOARD_FAB2(SCH_1):PAGE199',
 WATTAGE='1/16W',
 TOLERANCE='1%',
 SEC_TYPE='0402',
 MATERIAL='CHIP',
 PHYS_PAGE='199',
 XY='(-2825,750)',
 ROT='2',
 VER='2',
 VALUE='6.19K',
 PACK_TYPE='0402',
 PART_NUMBER='G21796-161',
 LOCATION='R1D31',
 ROOM='HOT_SWAP',
 SEC='1',
 CDS_LIB='mstr_discrete',
 CDS_PART_NAME='RES_0402-6.19K,1%,1/16W,CHIP,GA',
 PRIM_FILE='./archive_libs/mstr_discrete/res/chips/chips.prt';

PART_NAME
 R1D32 'RES_0402-100.0K,1%,1/16W,CHIP,A':
 ROOM='HOT_SWAP',
 NO_XNET_CONNECTION='1';

SECTION_NUMBER 1
 '@BASEBOARD_FAB2_LIB.BASEBOARD_FAB2(SCH_1):PAGE199_I17@MSTR_DISCRETE.RES(CHIPS)':
 C_PATH='@baseboard_fab2_lib.baseboard_fab2(sch_1):page199_i17@mstr_discrete.res~
(chips)',
 P_PATH='@baseboard_fab2_lib.baseboard_fab2(sch_1):page199_i17@mstr_discrete.res~
(chips)',
 PATH='I17',
 DRAWING='@BASEBOARD_FAB2_LIB.BASEBOARD_FAB2(SCH_1):PAGE199',
 WATTAGE='1/16W',
 TOLERANCE='1%',
 SEC_TYPE='0402',
 MATERIAL='CHIP',
 NO_XNET_CONNECTION='1',
 PHYS_PAGE='199',
 XY='(-5600,1500)',
 ROT='0',
 VER='2',
 VALUE='100.0K',
 PACK_TYPE='0402',
 PART_NUMBER='G21796-010',
 LOCATION='R1D32',
 ROOM='HOT_SWAP',
 SEC='1',
 CDS_LIB='mstr_discrete',
 CDS_PART_NAME='RES_0402-100.0K,1%,1/16W,CHIP,A',
 PRIM_FILE='./archive_libs/mstr_discrete/res/chips/chips.prt';

PART_NAME
 R1D33 'RES_0402-33.2,1%,1/16W,CHIP,G2A':;

SECTION_NUMBER 1
 '@BASEBOARD_FAB2_LIB.BASEBOARD_FAB2(SCH_1):PAGE199_I108@MSTR_DISCRETE.RES(CHIPS)':
 C_PATH='@baseboard_fab2_lib.baseboard_fab2(sch_1):page199_i108@mstr_discrete.re~
s(chips)',
 P_PATH='@baseboard_fab2_lib.baseboard_fab2(sch_1):page199_i108@mstr_discrete.re~
s(chips)',
 PATH='I108',
 DRAWING='@BASEBOARD_FAB2_LIB.BASEBOARD_FAB2(SCH_1):PAGE199',
 WATTAGE='1/16W',
 TOLERANCE='1%',
 SEC_TYPE='0402',
 MATERIAL='CHIP',
 PHYS_PAGE='199',
 XY='(-2050,925)',
 ROT='0',
 VER='1',
 VALUE='33.2',
 PACK_TYPE='0402',
 PART_NUMBER='G21796-074',
 LOCATION='R1D33',
 SEC='1',
 CDS_LIB='mstr_discrete',
 CDS_PART_NAME='RES_0402-33.2,1%,1/16W,CHIP,G2A',
 PRIM_FILE='./archive_libs/mstr_discrete/res/chips/chips.prt';

PART_NAME
 R1D34 'RES_0402-16K,1.0%,1/16W,CHIP,GA':
 ROOM='HOT_SWAP';

SECTION_NUMBER 1
 '@BASEBOARD_FAB2_LIB.BASEBOARD_FAB2(SCH_1):PAGE199_I102@MSTR_DISCRETE.RES(CHIPS)':
 C_PATH='@baseboard_fab2_lib.baseboard_fab2(sch_1):page199_i102@mstr_discrete.re~
s(chips)',
 P_PATH='@baseboard_fab2_lib.baseboard_fab2(sch_1):page199_i102@mstr_discrete.re~
s(chips)',
 PATH='I102',
 DRAWING='@BASEBOARD_FAB2_LIB.BASEBOARD_FAB2(SCH_1):PAGE199',
 WATTAGE='1/16W',
 TOLERANCE='1.0%',
 SEC_TYPE='0402',
 MATERIAL='CHIP',
 PHYS_PAGE='199',
 XY='(-5600,750)',
 ROT='0',
 VER='2',
 VALUE='16K',
 PACK_TYPE='0402',
 PART_NUMBER='G21796-317',
 LOCATION='R1D34',
 ROOM='HOT_SWAP',
 SEC='1',
 CDS_LIB='mstr_discrete',
 CDS_PART_NAME='RES_0402-16K,1.0%,1/16W,CHIP,GA',
 PRIM_FILE='./archive_libs/mstr_discrete/res/chips/chips.prt';

PART_NAME
 R1D35 'RES_0402-4.75K,1%,1/16W,CHIP,GA':
 ROOM='BMC_MISC';

SECTION_NUMBER 1
 '@BASEBOARD_FAB2_LIB.BASEBOARD_FAB2(SCH_1):PAGE126_I12@MSTR_DISCRETE.RES(CHIPS)':
 C_PATH='@baseboard_fab2_lib.baseboard_fab2(sch_1):page126_i12@mstr_discrete.res~
(chips)',
 P_PATH='@baseboard_fab2_lib.baseboard_fab2(sch_1):page126_i12@mstr_discrete.res~
(chips)',
 PATH='I12',
 DRAWING='@BASEBOARD_FAB2_LIB.BASEBOARD_FAB2(SCH_1):PAGE126',
 WATTAGE='1/16W',
 TOLERANCE='1%',
 SEC_TYPE='0402',
 MATERIAL='CHIP',
 BOM_COST='SM_CONTROLLER',
 PHYS_PAGE='126',
 XY='(-6200,2775)',
 ROT='0',
 VER='2',
 VALUE='4.75K',
 PACK_TYPE='0402',
 PART_NUMBER='G21796-072',
 LOCATION='R1D35',
 ROOM='BMC_MISC',
 SEC='1',
 CDS_LIB='mstr_discrete',
 CDS_PART_NAME='RES_0402-4.75K,1%,1/16W,CHIP,GA',
 PRIM_FILE='./archive_libs/mstr_discrete/res/chips/chips.prt';

PART_NAME
 R1D36 'RES_0402-1.00K,1%,1/16W,CHIP,GA':
 ROOM='HOT_SWAP';

SECTION_NUMBER 1
 '@BASEBOARD_FAB2_LIB.BASEBOARD_FAB2(SCH_1):PAGE199_I65@MSTR_DISCRETE.RES(CHIPS)':
 C_PATH='@baseboard_fab2_lib.baseboard_fab2(sch_1):page199_i65@mstr_discrete.res~
(chips)',
 P_PATH='@baseboard_fab2_lib.baseboard_fab2(sch_1):page199_i65@mstr_discrete.res~
(chips)',
 PATH='I65',
 DRAWING='@BASEBOARD_FAB2_LIB.BASEBOARD_FAB2(SCH_1):PAGE199',
 WATTAGE='1/16W',
 TOLERANCE='1%',
 SEC_TYPE='0402',
 MATERIAL='CHIP',
 BOM_COST='MIO_USB',
 PHYS_PAGE='199',
 XY='(-400,3025)',
 ROT='0',
 VER='2',
 VALUE='1.00K',
 PACK_TYPE='0402',
 PART_NUMBER='G21796-026',
 LOCATION='R1D36',
 ROOM='HOT_SWAP',
 SEC='1',
 CDS_LIB='mstr_discrete',
 CDS_PART_NAME='RES_0402-1.00K,1%,1/16W,CHIP,GA',
 PRIM_FILE='./archive_libs/mstr_discrete/res/chips/chips.prt';

PART_NAME
 R1D37 'RES_0402-100.0K,1%,1/16W,CHIP,A':
 ROOM='HOT_SWAP',
 NO_XNET_CONNECTION='1';

SECTION_NUMBER 1
 '@BASEBOARD_FAB2_LIB.BASEBOARD_FAB2(SCH_1):PAGE199_I15@MSTR_DISCRETE.RES(CHIPS)':
 C_PATH='@baseboard_fab2_lib.baseboard_fab2(sch_1):page199_i15@mstr_discrete.res~
(chips)',
 P_PATH='@baseboard_fab2_lib.baseboard_fab2(sch_1):page199_i15@mstr_discrete.res~
(chips)',
 PATH='I15',
 DRAWING='@BASEBOARD_FAB2_LIB.BASEBOARD_FAB2(SCH_1):PAGE199',
 WATTAGE='1/16W',
 TOLERANCE='1%',
 SEC_TYPE='0402',
 MATERIAL='CHIP',
 NO_XNET_CONNECTION='1',
 PHYS_PAGE='199',
 XY='(-6600,1550)',
 ROT='0',
 VER='2',
 VALUE='100.0K',
 PACK_TYPE='0402',
 PART_NUMBER='G21796-010',
 LOCATION='R1D37',
 ROOM='HOT_SWAP',
 SEC='1',
 CDS_LIB='mstr_discrete',
 CDS_PART_NAME='RES_0402-100.0K,1%,1/16W,CHIP,A',
 PRIM_FILE='./archive_libs/mstr_discrete/res/chips/chips.prt';

PART_NAME
 R1D39 'RES_0402-100.0K,1%,1/16W,CHIP,A':
 ROOM='HOT_SWAP',
 NO_XNET_CONNECTION='1';

SECTION_NUMBER 1
 '@BASEBOARD_FAB2_LIB.BASEBOARD_FAB2(SCH_1):PAGE199_I16@MSTR_DISCRETE.RES(CHIPS)':
 C_PATH='@baseboard_fab2_lib.baseboard_fab2(sch_1):page199_i16@mstr_discrete.res~
(chips)',
 P_PATH='@baseboard_fab2_lib.baseboard_fab2(sch_1):page199_i16@mstr_discrete.res~
(chips)',
 PATH='I16',
 DRAWING='@BASEBOARD_FAB2_LIB.BASEBOARD_FAB2(SCH_1):PAGE199',
 WATTAGE='1/16W',
 TOLERANCE='1%',
 SEC_TYPE='0402',
 MATERIAL='CHIP',
 NO_XNET_CONNECTION='1',
 PHYS_PAGE='199',
 XY='(-5300,1500)',
 ROT='0',
 VER='2',
 VALUE='100.0K',
 PACK_TYPE='0402',
 PART_NUMBER='G21796-010',
 LOCATION='R1D39',
 ROOM='HOT_SWAP',
 SEC='1',
 CDS_LIB='mstr_discrete',
 CDS_PART_NAME='RES_0402-100.0K,1%,1/16W,CHIP,A',
 PRIM_FILE='./archive_libs/mstr_discrete/res/chips/chips.prt';

PART_NAME
 R1D40 'RES_0402-40.2K,1%,1/16W,CHIP,GA':
 ROOM='HOT_SWAP';

SECTION_NUMBER 1
 '@BASEBOARD_FAB2_LIB.BASEBOARD_FAB2(SCH_1):PAGE199_I100@MSTR_DISCRETE.RES(CHIPS)':
 C_PATH='@baseboard_fab2_lib.baseboard_fab2(sch_1):page199_i100@mstr_discrete.re~
s(chips)',
 P_PATH='@baseboard_fab2_lib.baseboard_fab2(sch_1):page199_i100@mstr_discrete.re~
s(chips)',
 PATH='I100',
 DRAWING='@BASEBOARD_FAB2_LIB.BASEBOARD_FAB2(SCH_1):PAGE199',
 WATTAGE='1/16W',
 TOLERANCE='1%',
 SEC_TYPE='0402',
 MATERIAL='CHIP',
 PHYS_PAGE='199',
 XY='(-5300,800)',
 ROT='0',
 VER='2',
 VALUE='40.2K',
 PACK_TYPE='0402',
 PART_NUMBER='G21796-133',
 LOCATION='R1D40',
 ROOM='HOT_SWAP',
 SEC='1',
 CDS_LIB='mstr_discrete',
 CDS_PART_NAME='RES_0402-40.2K,1%,1/16W,CHIP,GA',
 PRIM_FILE='./archive_libs/mstr_discrete/res/chips/chips.prt';

PART_NAME
 R1D41 'RES_0805-0.0,5%,1/8W,CHIP,G221A':
 ROOM='HOT_SWAP';

SECTION_NUMBER 1
 '@BASEBOARD_FAB2_LIB.BASEBOARD_FAB2(SCH_1):PAGE199_I19@MSTR_DISCRETE.RES(CHIPS)':
 C_PATH='@baseboard_fab2_lib.baseboard_fab2(sch_1):page199_i19@mstr_discrete.res~
(chips)',
 P_PATH='@baseboard_fab2_lib.baseboard_fab2(sch_1):page199_i19@mstr_discrete.res~
(chips)',
 PATH='I19',
 DRAWING='@BASEBOARD_FAB2_LIB.BASEBOARD_FAB2(SCH_1):PAGE199',
 WATTAGE='1/8W',
 TOLERANCE='5%',
 SEC_TYPE='0805',
 MATERIAL='CHIP',
 PHYS_PAGE='199',
 XY='(-1650,300)',
 ROT='0',
 VER='1',
 VALUE='0.0',
 PACK_TYPE='0805',
 PART_NUMBER='G22179-004',
 LOCATION='R1D41',
 ROOM='HOT_SWAP',
 SEC='1',
 CDS_LIB='mstr_discrete',
 CDS_PART_NAME='RES_0805-0.0,5%,1/8W,CHIP,G221A',
 PRIM_FILE='./archive_libs/mstr_discrete/res/chips/chips.prt';

PART_NAME
 R1D42 'RES_0402-11K,1%,1/16W,CHIP,G21A':
 ROOM='HOT_SWAP';

SECTION_NUMBER 1
 '@BASEBOARD_FAB2_LIB.BASEBOARD_FAB2(SCH_1):PAGE199_I13@MSTR_DISCRETE.RES(CHIPS)':
 C_PATH='@baseboard_fab2_lib.baseboard_fab2(sch_1):page199_i13@mstr_discrete.res~
(chips)',
 P_PATH='@baseboard_fab2_lib.baseboard_fab2(sch_1):page199_i13@mstr_discrete.res~
(chips)',
 PATH='I13',
 DRAWING='@BASEBOARD_FAB2_LIB.BASEBOARD_FAB2(SCH_1):PAGE199',
 WATTAGE='1/16W',
 TOLERANCE='1%',
 SEC_TYPE='0402',
 MATERIAL='CHIP',
 PHYS_PAGE='199',
 XY='(-6500,3600)',
 ROT='0',
 VER='2',
 VALUE='11K',
 PACK_TYPE='0402',
 PART_NUMBER='G21796-220',
 LOCATION='R1D42',
 ROOM='HOT_SWAP',
 SEC='1',
 CDS_LIB='mstr_discrete',
 CDS_PART_NAME='RES_0402-11K,1%,1/16W,CHIP,G21A',
 PRIM_FILE='./archive_libs/mstr_discrete/res/chips/chips.prt';

PART_NAME
 R1D43 'RES_0402-7.5K,1%,1/16W,CHIP,G2A':
 ROOM='HOT_SWAP';

SECTION_NUMBER 1
 '@BASEBOARD_FAB2_LIB.BASEBOARD_FAB2(SCH_1):PAGE199_I9@MSTR_DISCRETE.RES(CHIPS)':
 C_PATH='@baseboard_fab2_lib.baseboard_fab2(sch_1):page199_i9@mstr_discrete.res(~
chips)',
 P_PATH='@baseboard_fab2_lib.baseboard_fab2(sch_1):page199_i9@mstr_discrete.res(~
chips)',
 PATH='I9',
 DRAWING='@BASEBOARD_FAB2_LIB.BASEBOARD_FAB2(SCH_1):PAGE199',
 CONFIG='064.7501D.06DD',
 WATTAGE='1/16W',
 TOLERANCE='1%',
 SEC_TYPE='0402',
 MATERIAL='CHIP',
 PHYS_PAGE='199',
 XY='(-7200,3625)',
 ROT='0',
 VER='2',
 VALUE='7.5K',
 PACK_TYPE='0402',
 PART_NUMBER='G21796-177',
 LOCATION='R1D43',
 ROOM='HOT_SWAP',
 SEC='1',
 CDS_LIB='mstr_discrete',
 CDS_PART_NAME='RES_0402-7.5K,1%,1/16W,CHIP,G2A',
 PRIM_FILE='./archive_libs/mstr_discrete/res/chips/chips.prt';

PART_NAME
 R1D44 'RES_0402-0.0,5%,1/16W,CHIP,G21A':
 ROOM='HOT_SWAP';

SECTION_NUMBER 1
 '@BASEBOARD_FAB2_LIB.BASEBOARD_FAB2(SCH_1):PAGE200_I44@MSTR_DISCRETE.RES(CHIPS)':
 C_PATH='@baseboard_fab2_lib.baseboard_fab2(sch_1):page200_i44@mstr_discrete.res~
(chips)',
 P_PATH='@baseboard_fab2_lib.baseboard_fab2(sch_1):page200_i44@mstr_discrete.res~
(chips)',
 PATH='I44',
 DRAWING='@BASEBOARD_FAB2_LIB.BASEBOARD_FAB2(SCH_1):PAGE200',
 WATTAGE='1/16W',
 TOLERANCE='5%',
 MATERIAL='CHIP',
 PHYS_PAGE='200',
 XY='(225,3150)',
 ROT='0',
 VER='1',
 VALUE='0.0',
 PACK_TYPE='0402',
 PART_NUMBER='G21497-005',
 LOCATION='R1D44',
 ROOM='HOT_SWAP',
 CDS_LIB='mstr_discrete',
 CDS_PART_NAME='RES_0402-0.0,5%,1/16W,CHIP,G21A',
 PRIM_FILE='./archive_libs/mstr_discrete/res/chips/chips.prt';

PART_NAME
 R1D45 'RES_0402-0.0,5%,1/16W,CHIP,G21A':
 ROOM='HOT_SWAP';

SECTION_NUMBER 1
 '@BASEBOARD_FAB2_LIB.BASEBOARD_FAB2(SCH_1):PAGE200_I43@MSTR_DISCRETE.RES(CHIPS)':
 C_PATH='@baseboard_fab2_lib.baseboard_fab2(sch_1):page200_i43@mstr_discrete.res~
(chips)',
 P_PATH='@baseboard_fab2_lib.baseboard_fab2(sch_1):page200_i43@mstr_discrete.res~
(chips)',
 PATH='I43',
 DRAWING='@BASEBOARD_FAB2_LIB.BASEBOARD_FAB2(SCH_1):PAGE200',
 WATTAGE='1/16W',
 TOLERANCE='5%',
 MATERIAL='CHIP',
 PHYS_PAGE='200',
 XY='(250,3625)',
 ROT='0',
 VER='1',
 VALUE='0.0',
 PACK_TYPE='0402',
 PART_NUMBER='G21497-005',
 LOCATION='R1D45',
 ROOM='HOT_SWAP',
 CDS_LIB='mstr_discrete',
 CDS_PART_NAME='RES_0402-0.0,5%,1/16W,CHIP,G21A',
 PRIM_FILE='./archive_libs/mstr_discrete/res/chips/chips.prt';

PART_NAME
 R1D46 'RES_0402-10.0,1%,1/16W,CHIP,G2A':
 ROOM='HOT_SWAP';

SECTION_NUMBER 1
 '@BASEBOARD_FAB2_LIB.BASEBOARD_FAB2(SCH_1):PAGE200_I48@MSTR_DISCRETE.RES(CHIPS)':
 C_PATH='@baseboard_fab2_lib.baseboard_fab2(sch_1):page200_i48@mstr_discrete.res~
(chips)',
 P_PATH='@baseboard_fab2_lib.baseboard_fab2(sch_1):page200_i48@mstr_discrete.res~
(chips)',
 PATH='I48',
 DRAWING='@BASEBOARD_FAB2_LIB.BASEBOARD_FAB2(SCH_1):PAGE200',
 WATTAGE='1/16W',
 TOLERANCE='1%',
 MATERIAL='CHIP',
 PHYS_PAGE='200',
 XY='(750,2800)',
 ROT='2',
 VER='2',
 VALUE='10.0',
 PACK_TYPE='0402',
 PART_NUMBER='G21796-066',
 LOCATION='R1D46',
 ROOM='HOT_SWAP',
 CDS_LIB='mstr_discrete',
 CDS_PART_NAME='RES_0402-10.0,1%,1/16W,CHIP,G2A',
 PRIM_FILE='./archive_libs/mstr_discrete/res/chips/chips.prt';

PART_NAME
 R1D47 'RES_0402-10.0,1%,1/16W,CHIP,G2A':
 ROOM='HOT_SWAP';

SECTION_NUMBER 1
 '@BASEBOARD_FAB2_LIB.BASEBOARD_FAB2(SCH_1):PAGE200_I52@MSTR_DISCRETE.RES(CHIPS)':
 C_PATH='@baseboard_fab2_lib.baseboard_fab2(sch_1):page200_i52@mstr_discrete.res~
(chips)',
 P_PATH='@baseboard_fab2_lib.baseboard_fab2(sch_1):page200_i52@mstr_discrete.res~
(chips)',
 PATH='I52',
 DRAWING='@BASEBOARD_FAB2_LIB.BASEBOARD_FAB2(SCH_1):PAGE200',
 WATTAGE='1/16W',
 TOLERANCE='1%',
 MATERIAL='CHIP',
 PHYS_PAGE='200',
 XY='(1475,2800)',
 ROT='0',
 VER='2',
 VALUE='10.0',
 PACK_TYPE='0402',
 PART_NUMBER='G21796-066',
 LOCATION='R1D47',
 ROOM='HOT_SWAP',
 CDS_LIB='mstr_discrete',
 CDS_PART_NAME='RES_0402-10.0,1%,1/16W,CHIP,G2A',
 PRIM_FILE='./archive_libs/mstr_discrete/res/chips/chips.prt';

PART_NAME
 R1D48 'RES_0402-10.0,1%,1/16W,CHIP,G2A':
 ROOM='HOT_SWAP';

SECTION_NUMBER 1
 '@BASEBOARD_FAB2_LIB.BASEBOARD_FAB2(SCH_1):PAGE200_I60@MSTR_DISCRETE.RES(CHIPS)':
 C_PATH='@baseboard_fab2_lib.baseboard_fab2(sch_1):page200_i60@mstr_discrete.res~
(chips)',
 P_PATH='@baseboard_fab2_lib.baseboard_fab2(sch_1):page200_i60@mstr_discrete.res~
(chips)',
 PATH='I60',
 DRAWING='@BASEBOARD_FAB2_LIB.BASEBOARD_FAB2(SCH_1):PAGE200',
 WATTAGE='1/16W',
 TOLERANCE='1%',
 SEC_TYPE='0402',
 MATERIAL='CHIP',
 PHYS_PAGE='200',
 XY='(1950,1775)',
 ROT='0',
 VER='1',
 VALUE='10.0',
 PACK_TYPE='0402',
 PART_NUMBER='G21796-066',
 LOCATION='R1D48',
 ROOM='HOT_SWAP',
 SEC='1',
 CDS_LIB='mstr_discrete',
 CDS_PART_NAME='RES_0402-10.0,1%,1/16W,CHIP,G2A',
 PRIM_FILE='./archive_libs/mstr_discrete/res/chips/chips.prt';

PART_NAME
 R1D49 'RES_PWR_6PAD-0.001,1%,3W,CHIP,A':
 ROOM='HOT_SWAP';

SECTION_NUMBER 1
 '@BASEBOARD_FAB2_LIB.BASEBOARD_FAB2(SCH_1):PAGE200_I50@MSTR_DISCRETE.RES_PWR(CHIPS)':
 C_PATH='@baseboard_fab2_lib.baseboard_fab2(sch_1):page200_i50@mstr_discrete.res~
_pwr(chips)',
 P_PATH='@baseboard_fab2_lib.baseboard_fab2(sch_1):page200_i50@mstr_discrete.res~
_pwr(chips)',
 PATH='I50',
 DRAWING='@BASEBOARD_FAB2_LIB.BASEBOARD_FAB2(SCH_1):PAGE200',
 BOM_DS='064.0U505.0C71',
 WATTAGE='3W',
 TOLERANCE='1%',
 SEC_TYPE='6PAD',
 MATERIAL='CHIP',
 PHYS_PAGE='200',
 XY='(1125,3600)',
 ROT='0',
 VER='2',
 VALUE='0.001',
 PACK_TYPE='6PAD',
 PART_NUMBER='E74391-005',
 LOCATION='R1D49',
 ROOM='HOT_SWAP',
 SEC='1',
 CDS_LIB='mstr_discrete',
 CDS_PART_NAME='RES_PWR_6PAD-0.001,1%,3W,CHIP,A',
 PRIM_FILE='./archive_libs/mstr_discrete/res_pwr/chips/chips.prt';

PART_NAME
 R1D51 'RES_0402-10.0,1%,1/16W,CHIP,G2A':
 ROOM='HOT_SWAP';

SECTION_NUMBER 1
 '@BASEBOARD_FAB2_LIB.BASEBOARD_FAB2(SCH_1):PAGE200_I154@MSTR_DISCRETE.RES(CHIPS)':
 C_PATH='@baseboard_fab2_lib.baseboard_fab2(sch_1):page200_i154@mstr_discrete.re~
s(chips)',
 P_PATH='@baseboard_fab2_lib.baseboard_fab2(sch_1):page200_i154@mstr_discrete.re~
s(chips)',
 PATH='I154',
 DRAWING='@BASEBOARD_FAB2_LIB.BASEBOARD_FAB2(SCH_1):PAGE200',
 WATTAGE='1/16W',
 TOLERANCE='1%',
 SEC_TYPE='0402',
 MATERIAL='CHIP',
 PHYS_PAGE='200',
 XY='(1350,1875)',
 ROT='0',
 VER='1',
 VALUE='10.0',
 PACK_TYPE='0402',
 PART_NUMBER='G21796-066',
 LOCATION='R1D51',
 ROOM='HOT_SWAP',
 SEC='1',
 CDS_LIB='mstr_discrete',
 CDS_PART_NAME='RES_0402-10.0,1%,1/16W,CHIP,G2A',
 PRIM_FILE='./archive_libs/mstr_discrete/res/chips/chips.prt';

PART_NAME
 R1D52 'RES_0402-68.1K,1%,1/16W,EMPTY,A':;

SECTION_NUMBER 1
 '@BASEBOARD_FAB2_LIB.BASEBOARD_FAB2(SCH_1):PAGE209_I59@MSTR_DISCRETE.RES(CHIPS)':
 C_PATH='@baseboard_fab2_lib.baseboard_fab2(sch_1):page209_i59@mstr_discrete.res~
(chips)',
 P_PATH='@baseboard_fab2_lib.baseboard_fab2(sch_1):page209_i59@mstr_discrete.res~
(chips)',
 PATH='I59',
 DRAWING='@BASEBOARD_FAB2_LIB.BASEBOARD_FAB2(SCH_1):PAGE209',
 WATTAGE='1/16W',
 TOLERANCE='1%',
 MATERIAL='EMPTY',
 PHYS_PAGE='209',
 XY='(-1000,3925)',
 ROT='0',
 VER='2',
 VALUE='68.1K',
 PACK_TYPE='0402',
 PART_NUMBER='G21796-187',
 LOCATION='R1D52',
 CDS_LIB='mstr_discrete',
 CDS_PART_NAME='RES_0402-68.1K,1%,1/16W,EMPTY,A',
 PRIM_FILE='./archive_libs/mstr_discrete/res/chips/chips.prt';

PART_NAME
 R1D53 'RES_0402-2.26K,1.0%,1/16W,EMPTA':
 ROOM='PVCCIN_CPU1_VR';

SECTION_NUMBER 1
 '@BASEBOARD_FAB2_LIB.BASEBOARD_FAB2(SCH_1):PAGE206_I33@MSTR_DISCRETE.RES(CHIPS)':
 C_PATH='@baseboard_fab2_lib.baseboard_fab2(sch_1):page206_i33@mstr_discrete.res~
(chips)',
 P_PATH='@baseboard_fab2_lib.baseboard_fab2(sch_1):page206_i33@mstr_discrete.res~
(chips)',
 PATH='I33',
 DRAWING='@BASEBOARD_FAB2_LIB.BASEBOARD_FAB2(SCH_1):PAGE206',
 WATTAGE='1/16W',
 TOLERANCE='1.0%',
 SEC_TYPE='0402',
 MATERIAL='EMPTY',
 PHYS_PAGE='206',
 XY='(-2375,4125)',
 ROT='0',
 VER='2',
 VALUE='2.26K',
 PACK_TYPE='0402',
 PART_NUMBER='G21796-311',
 LOCATION='R1D53',
 ROOM='PVCCIN_CPU1_VR',
 SEC='1',
 CDS_LIB='mstr_discrete',
 CDS_PART_NAME='RES_0402-2.26K,1.0%,1/16W,EMPTA',
 PRIM_FILE='./archive_libs/mstr_discrete/res/chips/chips.prt';

PART_NAME
 R1D54 'RES_0402-68.1K,1%,1/16W,EMPTY,A':;

SECTION_NUMBER 1
 '@BASEBOARD_FAB2_LIB.BASEBOARD_FAB2(SCH_1):PAGE208_I75@MSTR_DISCRETE.RES(CHIPS)':
 C_PATH='@baseboard_fab2_lib.baseboard_fab2(sch_1):page208_i75@mstr_discrete.res~
(chips)',
 P_PATH='@baseboard_fab2_lib.baseboard_fab2(sch_1):page208_i75@mstr_discrete.res~
(chips)',
 PATH='I75',
 DRAWING='@BASEBOARD_FAB2_LIB.BASEBOARD_FAB2(SCH_1):PAGE208',
 WATTAGE='1/16W',
 TOLERANCE='1%',
 MATERIAL='EMPTY',
 PHYS_PAGE='208',
 XY='(-625,1450)',
 ROT='0',
 VER='2',
 VALUE='68.1K',
 PACK_TYPE='0402',
 PART_NUMBER='G21796-187',
 LOCATION='R1D54',
 CDS_LIB='mstr_discrete',
 CDS_PART_NAME='RES_0402-68.1K,1%,1/16W,EMPTY,A',
 PRIM_FILE='./archive_libs/mstr_discrete/res/chips/chips.prt';

PART_NAME
 R1D55 'RES_0402-68.1K,1%,1/16W,EMPTY,A':;

SECTION_NUMBER 1
 '@BASEBOARD_FAB2_LIB.BASEBOARD_FAB2(SCH_1):PAGE208_I76@MSTR_DISCRETE.RES(CHIPS)':
 C_PATH='@baseboard_fab2_lib.baseboard_fab2(sch_1):page208_i76@mstr_discrete.res~
(chips)',
 P_PATH='@baseboard_fab2_lib.baseboard_fab2(sch_1):page208_i76@mstr_discrete.res~
(chips)',
 PATH='I76',
 DRAWING='@BASEBOARD_FAB2_LIB.BASEBOARD_FAB2(SCH_1):PAGE208',
 WATTAGE='1/16W',
 TOLERANCE='1%',
 MATERIAL='EMPTY',
 PHYS_PAGE='208',
 XY='(-700,4075)',
 ROT='0',
 VER='2',
 VALUE='68.1K',
 PACK_TYPE='0402',
 PART_NUMBER='G21796-187',
 LOCATION='R1D55',
 CDS_LIB='mstr_discrete',
 CDS_PART_NAME='RES_0402-68.1K,1%,1/16W,EMPTY,A',
 PRIM_FILE='./archive_libs/mstr_discrete/res/chips/chips.prt';

PART_NAME
 R1E1 'RES_0402-10.0,1%,1/16W,CHIP,G2A':
 ROOM='HOT_SWAP';

SECTION_NUMBER 1
 '@BASEBOARD_FAB2_LIB.BASEBOARD_FAB2(SCH_1):PAGE200_I56@MSTR_DISCRETE.RES(CHIPS)':
 C_PATH='@baseboard_fab2_lib.baseboard_fab2(sch_1):page200_i56@mstr_discrete.res~
(chips)',
 P_PATH='@baseboard_fab2_lib.baseboard_fab2(sch_1):page200_i56@mstr_discrete.res~
(chips)',
 PATH='I56',
 DRAWING='@BASEBOARD_FAB2_LIB.BASEBOARD_FAB2(SCH_1):PAGE200',
 WATTAGE='1/16W',
 TOLERANCE='1%',
 SEC_TYPE='0402',
 MATERIAL='CHIP',
 PHYS_PAGE='200',
 XY='(2000,3075)',
 ROT='0',
 VER='1',
 VALUE='10.0',
 PACK_TYPE='0402',
 PART_NUMBER='G21796-066',
 LOCATION='R1E1',
 ROOM='HOT_SWAP',
 SEC='1',
 CDS_LIB='mstr_discrete',
 CDS_PART_NAME='RES_0402-10.0,1%,1/16W,CHIP,G2A',
 PRIM_FILE='./archive_libs/mstr_discrete/res/chips/chips.prt';

PART_NAME
 R1E3 'RES_0603-100.0,1%,1/10W,CHIP,GA':
 ROOM='PVCCIN_CPU1_DECAP_VR';

SECTION_NUMBER 1
 '@BASEBOARD_FAB2_LIB.BASEBOARD_FAB2(SCH_1):PAGE208_I7@MSTR_DISCRETE.RES(CHIPS)':
 C_PATH='@baseboard_fab2_lib.baseboard_fab2(sch_1):page208_i7@mstr_discrete.res(~
chips)',
 P_PATH='@baseboard_fab2_lib.baseboard_fab2(sch_1):page208_i7@mstr_discrete.res(~
chips)',
 PATH='I7',
 DRAWING='@BASEBOARD_FAB2_LIB.BASEBOARD_FAB2(SCH_1):PAGE208',
 WATTAGE='1/10W',
 TOLERANCE='1%',
 SEC_TYPE='0603',
 MATERIAL='CHIP',
 BOM_COST='PROC_VRD_VCCIN_CPU0',
 PHYS_PAGE='208',
 XY='(-1000,2575)',
 ROT='0',
 VER='2',
 VALUE='100.0',
 PACK_TYPE='0603',
 PART_NUMBER='G22026-038',
 LOCATION='R1E3',
 ROOM='PVCCIN_CPU1_DECAP_VR',
 SEC='1',
 CDS_LIB='mstr_discrete',
 CDS_PART_NAME='RES_0603-100.0,1%,1/10W,CHIP,GA',
 PRIM_FILE='./archive_libs/mstr_discrete/res/chips/chips.prt';

PART_NAME
 R1E4 'RES_0402-100.0,1%,1/16W,CHIP,GA':
 ROOM='PVCCIN_CPU1_VSENSE_VR';

SECTION_NUMBER 1
 '@BASEBOARD_FAB2_LIB.BASEBOARD_FAB2(SCH_1):PAGE209_I15@MSTR_DISCRETE.RES(CHIPS)':
 C_PATH='@baseboard_fab2_lib.baseboard_fab2(sch_1):page209_i15@mstr_discrete.res~
(chips)',
 P_PATH='@baseboard_fab2_lib.baseboard_fab2(sch_1):page209_i15@mstr_discrete.res~
(chips)',
 PATH='I15',
 DRAWING='@BASEBOARD_FAB2_LIB.BASEBOARD_FAB2(SCH_1):PAGE209',
 WATTAGE='1/16W',
 TOLERANCE='1%',
 MATERIAL='CHIP',
 BOM_COST='PROC_VRD_VCCIN_CPU0',
 PHYS_PAGE='209',
 XY='(-5500,2300)',
 ROT='0',
 VER='1',
 VALUE='100.0',
 PACK_TYPE='0402',
 PART_NUMBER='G21796-017',
 LOCATION='R1E4',
 ROOM='PVCCIN_CPU1_VSENSE_VR',
 CDS_LIB='mstr_discrete',
 CDS_PART_NAME='RES_0402-100.0,1%,1/16W,CHIP,GA',
 PRIM_FILE='./archive_libs/mstr_discrete/res/chips/chips.prt';

PART_NAME
 R1E5 'RES_0402-1.00K,1%,1/16W,EMPTY,A':
 ROOM='PVCCIN_CPU1_VSENSE_VR';

SECTION_NUMBER 1
 '@BASEBOARD_FAB2_LIB.BASEBOARD_FAB2(SCH_1):PAGE209_I3@MSTR_DISCRETE.RES(CHIPS)':
 C_PATH='@baseboard_fab2_lib.baseboard_fab2(sch_1):page209_i3@mstr_discrete.res(~
chips)',
 P_PATH='@baseboard_fab2_lib.baseboard_fab2(sch_1):page209_i3@mstr_discrete.res(~
chips)',
 PATH='I3',
 DRAWING='@BASEBOARD_FAB2_LIB.BASEBOARD_FAB2(SCH_1):PAGE209',
 WATTAGE='1/16W',
 TOLERANCE='1%',
 MATERIAL='EMPTY',
 BOM_COST='PROC_VRD_VCCIN_CPU0',
 PHYS_PAGE='209',
 XY='(-6300,1700)',
 ROT='0',
 VER='2',
 VALUE='1.00K',
 PACK_TYPE='0402',
 PART_NUMBER='G21796-026',
 LOCATION='R1E5',
 ROOM='PVCCIN_CPU1_VSENSE_VR',
 CDS_LIB='mstr_discrete',
 CDS_PART_NAME='RES_0402-1.00K,1%,1/16W,EMPTY,A',
 PRIM_FILE='./archive_libs/mstr_discrete/res/chips/chips.prt';

PART_NAME
 R1E6 'RES_0402-0.0,5%,1/16W,CHIP,G21A':
 ROOM='PVCCIN_CPU1_VSENSE_VR';

SECTION_NUMBER 1
 '@BASEBOARD_FAB2_LIB.BASEBOARD_FAB2(SCH_1):PAGE209_I11@MSTR_DISCRETE.RES(CHIPS)':
 C_PATH='@baseboard_fab2_lib.baseboard_fab2(sch_1):page209_i11@mstr_discrete.res~
(chips)',
 P_PATH='@baseboard_fab2_lib.baseboard_fab2(sch_1):page209_i11@mstr_discrete.res~
(chips)',
 PATH='I11',
 DRAWING='@BASEBOARD_FAB2_LIB.BASEBOARD_FAB2(SCH_1):PAGE209',
 WATTAGE='1/16W',
 TOLERANCE='5%',
 MATERIAL='CHIP',
 BOM_COST='PROC_VRD_VCCIN_CPU0',
 PHYS_PAGE='209',
 XY='(-5500,1900)',
 ROT='0',
 VER='1',
 VALUE='0.0',
 PACK_TYPE='0402',
 PART_NUMBER='G21497-005',
 LOCATION='R1E6',
 ROOM='PVCCIN_CPU1_VSENSE_VR',
 CDS_LIB='mstr_discrete',
 CDS_PART_NAME='RES_0402-0.0,5%,1/16W,CHIP,G21A',
 PRIM_FILE='./archive_libs/mstr_discrete/res/chips/chips.prt';

PART_NAME
 R1E7 'RES_0402-0.0,5%,1/16W,CHIP,G21A':
 ROOM='PVCCIN_CPU1_VSENSE_VR';

SECTION_NUMBER 1
 '@BASEBOARD_FAB2_LIB.BASEBOARD_FAB2(SCH_1):PAGE209_I10@MSTR_DISCRETE.RES(CHIPS)':
 C_PATH='@baseboard_fab2_lib.baseboard_fab2(sch_1):page209_i10@mstr_discrete.res~
(chips)',
 P_PATH='@baseboard_fab2_lib.baseboard_fab2(sch_1):page209_i10@mstr_discrete.res~
(chips)',
 PATH='I10',
 DRAWING='@BASEBOARD_FAB2_LIB.BASEBOARD_FAB2(SCH_1):PAGE209',
 WATTAGE='1/16W',
 TOLERANCE='5%',
 MATERIAL='CHIP',
 BOM_COST='PROC_VRD_VCCIN_CPU0',
 PHYS_PAGE='209',
 XY='(-5475,1450)',
 ROT='0',
 VER='1',
 VALUE='0.0',
 PACK_TYPE='0402',
 PART_NUMBER='G21497-005',
 LOCATION='R1E7',
 ROOM='PVCCIN_CPU1_VSENSE_VR',
 CDS_LIB='mstr_discrete',
 CDS_PART_NAME='RES_0402-0.0,5%,1/16W,CHIP,G21A',
 PRIM_FILE='./archive_libs/mstr_discrete/res/chips/chips.prt';

PART_NAME
 R1E8 'RES_0402-100.0,1%,1/16W,CHIP,GA':
 ROOM='PVCCIN_CPU1_VSENSE_VR';

SECTION_NUMBER 1
 '@BASEBOARD_FAB2_LIB.BASEBOARD_FAB2(SCH_1):PAGE209_I9@MSTR_DISCRETE.RES(CHIPS)':
 C_PATH='@baseboard_fab2_lib.baseboard_fab2(sch_1):page209_i9@mstr_discrete.res(~
chips)',
 P_PATH='@baseboard_fab2_lib.baseboard_fab2(sch_1):page209_i9@mstr_discrete.res(~
chips)',
 PATH='I9',
 DRAWING='@BASEBOARD_FAB2_LIB.BASEBOARD_FAB2(SCH_1):PAGE209',
 WATTAGE='1/16W',
 TOLERANCE='1%',
 MATERIAL='CHIP',
 BOM_COST='PROC_VRD_VCCIN_CPU0',
 PHYS_PAGE='209',
 XY='(-5475,1050)',
 ROT='0',
 VER='1',
 VALUE='100.0',
 PACK_TYPE='0402',
 PART_NUMBER='G21796-017',
 LOCATION='R1E8',
 ROOM='PVCCIN_CPU1_VSENSE_VR',
 CDS_LIB='mstr_discrete',
 CDS_PART_NAME='RES_0402-100.0,1%,1/16W,CHIP,GA',
 PRIM_FILE='./archive_libs/mstr_discrete/res/chips/chips.prt';

PART_NAME
 R1E9 'RES_0402-1.00K,1%,1/16W,CHIP,GA':
 ROOM='TEMP_SENSORS';

SECTION_NUMBER 1
 '@BASEBOARD_FAB2_LIB.BASEBOARD_FAB2(SCH_1):PAGE167_I34@MSTR_DISCRETE.RES(CHIPS)':
 C_PATH='@baseboard_fab2_lib.baseboard_fab2(sch_1):page167_i34@mstr_discrete.res~
(chips)',
 P_PATH='@baseboard_fab2_lib.baseboard_fab2(sch_1):page167_i34@mstr_discrete.res~
(chips)',
 PATH='I34',
 DRAWING='@BASEBOARD_FAB2_LIB.BASEBOARD_FAB2(SCH_1):PAGE167',
 WATTAGE='1/16W',
 TOLERANCE='1%',
 SEC_TYPE='0402',
 MATERIAL='CHIP',
 BOM_COST='SM_THERM',
 PHYS_PAGE='167',
 XY='(-5050,2850)',
 ROT='0',
 VER='1',
 VALUE='1.00K',
 PACK_TYPE='0402',
 PART_NUMBER='G21796-026',
 LOCATION='R1E9',
 ROOM='TEMP_SENSORS',
 SEC='1',
 CDS_LIB='mstr_discrete',
 CDS_PART_NAME='RES_0402-1.00K,1%,1/16W,CHIP,GA',
 PRIM_FILE='./archive_libs/mstr_discrete/res/chips/chips.prt';

PART_NAME
 R1E10 'RES_0402-1.00K,1%,1/16W,CHIP,GA':
 ROOM='TEMP_SENSORS';

SECTION_NUMBER 1
 '@BASEBOARD_FAB2_LIB.BASEBOARD_FAB2(SCH_1):PAGE167_I38@MSTR_DISCRETE.RES(CHIPS)':
 C_PATH='@baseboard_fab2_lib.baseboard_fab2(sch_1):page167_i38@mstr_discrete.res~
(chips)',
 P_PATH='@baseboard_fab2_lib.baseboard_fab2(sch_1):page167_i38@mstr_discrete.res~
(chips)',
 PATH='I38',
 DRAWING='@BASEBOARD_FAB2_LIB.BASEBOARD_FAB2(SCH_1):PAGE167',
 WATTAGE='1/16W',
 TOLERANCE='1%',
 SEC_TYPE='0402',
 MATERIAL='CHIP',
 BOM_COST='SM_THERM',
 PHYS_PAGE='167',
 XY='(-4650,2900)',
 ROT='0',
 VER='1',
 VALUE='1.00K',
 PACK_TYPE='0402',
 PART_NUMBER='G21796-026',
 LOCATION='R1E10',
 ROOM='TEMP_SENSORS',
 SEC='1',
 CDS_LIB='mstr_discrete',
 CDS_PART_NAME='RES_0402-1.00K,1%,1/16W,CHIP,GA',
 PRIM_FILE='./archive_libs/mstr_discrete/res/chips/chips.prt';

PART_NAME
 R1E11 'RES_0402-10.0K,1%,1/16W,EMPTY,A':
 ROOM='CPU_FANS';

SECTION_NUMBER 1
 '@BASEBOARD_FAB2_LIB.BASEBOARD_FAB2(SCH_1):PAGE161_I120@MSTR_DISCRETE.RES(CHIPS)':
 C_PATH='@baseboard_fab2_lib.baseboard_fab2(sch_1):page161_i120@mstr_discrete.re~
s(chips)',
 P_PATH='@baseboard_fab2_lib.baseboard_fab2(sch_1):page161_i120@mstr_discrete.re~
s(chips)',
 PATH='I120',
 DRAWING='@BASEBOARD_FAB2_LIB.BASEBOARD_FAB2(SCH_1):PAGE161',
 WATTAGE='1/16W',
 TOLERANCE='1%',
 SEC_TYPE='0402',
 MATERIAL='EMPTY',
 BOM_COST='SM_THERM',
 PHYS_PAGE='161',
 XY='(-5950,2800)',
 ROT='0',
 VER='2',
 VALUE='10.0K',
 PACK_TYPE='0402',
 PART_NUMBER='G21796-016',
 LOCATION='R1E11',
 ROOM='CPU_FANS',
 SEC='1',
 CDS_LIB='mstr_discrete',
 CDS_PART_NAME='RES_0402-10.0K,1%,1/16W,EMPTY,A',
 PRIM_FILE='./archive_libs/mstr_discrete/res/chips/chips.prt';

PART_NAME
 R1E12 'RES_0402-4.75K,1%,1/16W,CHIP,GA':
 ROOM='CPU_FANS';

SECTION_NUMBER 1
 '@BASEBOARD_FAB2_LIB.BASEBOARD_FAB2(SCH_1):PAGE161_I51@MSTR_DISCRETE.RES(CHIPS)':
 C_PATH='@baseboard_fab2_lib.baseboard_fab2(sch_1):page161_i51@mstr_discrete.res~
(chips)',
 P_PATH='@baseboard_fab2_lib.baseboard_fab2(sch_1):page161_i51@mstr_discrete.res~
(chips)',
 PATH='I51',
 DRAWING='@BASEBOARD_FAB2_LIB.BASEBOARD_FAB2(SCH_1):PAGE161',
 WATTAGE='1/16W',
 TOLERANCE='1%',
 SEC_TYPE='0402',
 MATERIAL='CHIP',
 BOM_COST='SM_THERM',
 PHYS_PAGE='161',
 XY='(-2175,3400)',
 ROT='2',
 VER='2',
 VALUE='4.75K',
 PACK_TYPE='0402',
 PART_NUMBER='G21796-072',
 LOCATION='R1E12',
 ROOM='CPU_FANS',
 SEC='1',
 CDS_LIB='mstr_discrete',
 CDS_PART_NAME='RES_0402-4.75K,1%,1/16W,CHIP,GA',
 PRIM_FILE='./archive_libs/mstr_discrete/res/chips/chips.prt';

PART_NAME
 R1E13 'RES_0402-68.1K,1%,1/16W,EMPTY,A':;

SECTION_NUMBER 1
 '@BASEBOARD_FAB2_LIB.BASEBOARD_FAB2(SCH_1):PAGE207_I67@MSTR_DISCRETE.RES(CHIPS)':
 C_PATH='@baseboard_fab2_lib.baseboard_fab2(sch_1):page207_i67@mstr_discrete.res~
(chips)',
 P_PATH='@baseboard_fab2_lib.baseboard_fab2(sch_1):page207_i67@mstr_discrete.res~
(chips)',
 PATH='I67',
 DRAWING='@BASEBOARD_FAB2_LIB.BASEBOARD_FAB2(SCH_1):PAGE207',
 WATTAGE='1/16W',
 TOLERANCE='1%',
 MATERIAL='EMPTY',
 PHYS_PAGE='207',
 XY='(-700,1425)',
 ROT='0',
 VER='2',
 VALUE='68.1K',
 PACK_TYPE='0402',
 PART_NUMBER='G21796-187',
 LOCATION='R1E13',
 CDS_LIB='mstr_discrete',
 CDS_PART_NAME='RES_0402-68.1K,1%,1/16W,EMPTY,A',
 PRIM_FILE='./archive_libs/mstr_discrete/res/chips/chips.prt';

PART_NAME
 R1E14 'RES_0402-68.1K,1%,1/16W,EMPTY,A':;

SECTION_NUMBER 1
 '@BASEBOARD_FAB2_LIB.BASEBOARD_FAB2(SCH_1):PAGE207_I68@MSTR_DISCRETE.RES(CHIPS)':
 C_PATH='@baseboard_fab2_lib.baseboard_fab2(sch_1):page207_i68@mstr_discrete.res~
(chips)',
 P_PATH='@baseboard_fab2_lib.baseboard_fab2(sch_1):page207_i68@mstr_discrete.res~
(chips)',
 PATH='I68',
 DRAWING='@BASEBOARD_FAB2_LIB.BASEBOARD_FAB2(SCH_1):PAGE207',
 WATTAGE='1/16W',
 TOLERANCE='1%',
 MATERIAL='EMPTY',
 PHYS_PAGE='207',
 XY='(-450,4050)',
 ROT='0',
 VER='2',
 VALUE='68.1K',
 PACK_TYPE='0402',
 PART_NUMBER='G21796-187',
 LOCATION='R1E14',
 CDS_LIB='mstr_discrete',
 CDS_PART_NAME='RES_0402-68.1K,1%,1/16W,EMPTY,A',
 PRIM_FILE='./archive_libs/mstr_discrete/res/chips/chips.prt';

PART_NAME
 R1F1 'RES_0402-4.75K,1%,1/16W,CHIP,GA':
 ROOM='CPU_FANS';

SECTION_NUMBER 1
 '@BASEBOARD_FAB2_LIB.BASEBOARD_FAB2(SCH_1):PAGE161_I45@MSTR_DISCRETE.RES(CHIPS)':
 C_PATH='@baseboard_fab2_lib.baseboard_fab2(sch_1):page161_i45@mstr_discrete.res~
(chips)',
 P_PATH='@baseboard_fab2_lib.baseboard_fab2(sch_1):page161_i45@mstr_discrete.res~
(chips)',
 PATH='I45',
 DRAWING='@BASEBOARD_FAB2_LIB.BASEBOARD_FAB2(SCH_1):PAGE161',
 WATTAGE='1/16W',
 TOLERANCE='1%',
 SEC_TYPE='0402',
 MATERIAL='CHIP',
 BOM_COST='SM_THERM',
 PHYS_PAGE='161',
 XY='(-2900,4025)',
 ROT='0',
 VER='2',
 VALUE='4.75K',
 PACK_TYPE='0402',
 PART_NUMBER='G21796-072',
 LOCATION='R1F1',
 ROOM='CPU_FANS',
 SEC='1',
 CDS_LIB='mstr_discrete',
 CDS_PART_NAME='RES_0402-4.75K,1%,1/16W,CHIP,GA',
 PRIM_FILE='./archive_libs/mstr_discrete/res/chips/chips.prt';

PART_NAME
 R1F2 'RES_0402-100.0,1%,1/16W,CHIP,GA':
 ROOM='CPU_FANS',
 NO_XNET_CONNECTION='1';

SECTION_NUMBER 1
 '@BASEBOARD_FAB2_LIB.BASEBOARD_FAB2(SCH_1):PAGE161_I43@MSTR_DISCRETE.RES(CHIPS)':
 C_PATH='@baseboard_fab2_lib.baseboard_fab2(sch_1):page161_i43@mstr_discrete.res~
(chips)',
 P_PATH='@baseboard_fab2_lib.baseboard_fab2(sch_1):page161_i43@mstr_discrete.res~
(chips)',
 PATH='I43',
 DRAWING='@BASEBOARD_FAB2_LIB.BASEBOARD_FAB2(SCH_1):PAGE161',
 WATTAGE='1/16W',
 TOLERANCE='1%',
 SEC_TYPE='0402',
 MATERIAL='CHIP',
 BOM_COST='SM_THERM',
 NO_XNET_CONNECTION='1',
 PHYS_PAGE='161',
 XY='(-2525,3825)',
 ROT='0',
 VER='1',
 VALUE='100.0',
 PACK_TYPE='0402',
 PART_NUMBER='G21796-017',
 LOCATION='R1F2',
 ROOM='CPU_FANS',
 SEC='1',
 CDS_LIB='mstr_discrete',
 CDS_PART_NAME='RES_0402-100.0,1%,1/16W,CHIP,GA',
 PRIM_FILE='./archive_libs/mstr_discrete/res/chips/chips.prt';

PART_NAME
 R1F3 'RES_1206-0.002,1%,1W,CHIP,G521A':
 ROOM='PVDDQ_ABC_PWR_VR';

SECTION_NUMBER 1
 '@BASEBOARD_FAB2_LIB.BASEBOARD_FAB2(SCH_1):PAGE197_I50@MSTR_DISCRETE.RES(CHIPS)':
 C_PATH='@baseboard_fab2_lib.baseboard_fab2(sch_1):page197_i50@mstr_discrete.res~
(chips)',
 P_PATH='@baseboard_fab2_lib.baseboard_fab2(sch_1):page197_i50@mstr_discrete.res~
(chips)',
 PATH='I50',
 DRAWING='@BASEBOARD_FAB2_LIB.BASEBOARD_FAB2(SCH_1):PAGE197',
 NEW_VALUE='0.004 OHM',
 CONFIG='064.R0045.0711',
 WATTAGE='1W',
 TOLERANCE='1%',
 SEC_TYPE='1206',
 MATERIAL='CHIP',
 BOM_COST='PVDDQ_ABC_VR',
 PHYS_PAGE='197',
 XY='(-1725,4800)',
 ROT='0',
 VER='1',
 VALUE='0.002',
 PACK_TYPE='1206',
 PART_NUMBER='G52199-004',
 LOCATION='R1F3',
 ROOM='PVDDQ_ABC_PWR_VR',
 SEC='1',
 CDS_LIB='mstr_discrete',
 CDS_PART_NAME='RES_1206-0.002,1%,1W,CHIP,G521A',
 PRIM_FILE='./archive_libs/mstr_discrete/res/chips/chips.prt';

PART_NAME
 R1F4 'RES_0402-2,1.0%,1/16W,CHIP,G21A':
 ROOM='PROC';

SECTION_NUMBER 1
 '@BASEBOARD_FAB2_LIB.BASEBOARD_FAB2(SCH_1):PAGE100_I7@MSTR_DISCRETE.RES(CHIPS)':
 C_PATH='@baseboard_fab2_lib.baseboard_fab2(sch_1):page100_i7@mstr_discrete.res(~
chips)',
 P_PATH='@baseboard_fab2_lib.baseboard_fab2(sch_1):page100_i7@mstr_discrete.res(~
chips)',
 PATH='I7',
 DRAWING='@BASEBOARD_FAB2_LIB.BASEBOARD_FAB2(SCH_1):PAGE100',
 WATTAGE='1/16W',
 TOLERANCE='1.0%',
 SEC_TYPE='0402',
 MATERIAL='CHIP',
 BOM_COST='PROC_SOCKET',
 PHYS_PAGE='100',
 XY='(-2125,3625)',
 ROT='0',
 VER='1',
 VALUE='2',
 PACK_TYPE='0402',
 PART_NUMBER='G21796-274',
 LOCATION='R1F4',
 ROOM='PROC',
 SEC='1',
 CDS_LIB='mstr_discrete',
 CDS_PART_NAME='RES_0402-2,1.0%,1/16W,CHIP,G21A',
 PRIM_FILE='./archive_libs/mstr_discrete/res/chips/chips.prt';

PART_NAME
 R1F5 'RES_0402-1.00K,1%,1/16W,CHIP,GA':
 ROOM='MEM';

SECTION_NUMBER 1
 '@BASEBOARD_FAB2_LIB.BASEBOARD_FAB2(SCH_1):PAGE100_I6@MSTR_DISCRETE.RES(CHIPS)':
 C_PATH='@baseboard_fab2_lib.baseboard_fab2(sch_1):page100_i6@mstr_discrete.res(~
chips)',
 P_PATH='@baseboard_fab2_lib.baseboard_fab2(sch_1):page100_i6@mstr_discrete.res(~
chips)',
 PATH='I6',
 DRAWING='@BASEBOARD_FAB2_LIB.BASEBOARD_FAB2(SCH_1):PAGE100',
 WATTAGE='1/16W',
 TOLERANCE='1%',
 SEC_TYPE='0402',
 MATERIAL='CHIP',
 BOM_COST='SM_CONTROLLER',
 PHYS_PAGE='100',
 XY='(-1900,3950)',
 ROT='2',
 VER='2',
 VALUE='1.00K',
 PACK_TYPE='0402',
 PART_NUMBER='G21796-026',
 LOCATION='R1F5',
 ROOM='MEM',
 SEC='1',
 CDS_LIB='mstr_discrete',
 CDS_PART_NAME='RES_0402-1.00K,1%,1/16W,CHIP,GA',
 PRIM_FILE='./archive_libs/mstr_discrete/res/chips/chips.prt';

PART_NAME
 R1F6 'RES_0402-1.00K,1%,1/16W,CHIP,GA':
 ROOM='MEM';

SECTION_NUMBER 1
 '@BASEBOARD_FAB2_LIB.BASEBOARD_FAB2(SCH_1):PAGE100_I2@MSTR_DISCRETE.RES(CHIPS)':
 C_PATH='@baseboard_fab2_lib.baseboard_fab2(sch_1):page100_i2@mstr_discrete.res(~
chips)',
 P_PATH='@baseboard_fab2_lib.baseboard_fab2(sch_1):page100_i2@mstr_discrete.res(~
chips)',
 PATH='I2',
 DRAWING='@BASEBOARD_FAB2_LIB.BASEBOARD_FAB2(SCH_1):PAGE100',
 WATTAGE='1/16W',
 TOLERANCE='1%',
 SEC_TYPE='0402',
 MATERIAL='CHIP',
 BOM_COST='SM_CONTROLLER',
 PHYS_PAGE='100',
 XY='(-1825,3300)',
 ROT='2',
 VER='2',
 VALUE='1.00K',
 PACK_TYPE='0402',
 PART_NUMBER='G21796-026',
 LOCATION='R1F6',
 ROOM='MEM',
 SEC='1',
 CDS_LIB='mstr_discrete',
 CDS_PART_NAME='RES_0402-1.00K,1%,1/16W,CHIP,GA',
 PRIM_FILE='./archive_libs/mstr_discrete/res/chips/chips.prt';

PART_NAME
 R1F8 'RES_0402-0.0,5%,1/16W,CHIP,G21A':;

SECTION_NUMBER 1
 '@BASEBOARD_FAB2_LIB.BASEBOARD_FAB2(SCH_1):PAGE181_I22@MSTR_DISCRETE.RES(CHIPS)':
 C_PATH='@baseboard_fab2_lib.baseboard_fab2(sch_1):page181_i22@mstr_discrete.res~
(chips)',
 P_PATH='@baseboard_fab2_lib.baseboard_fab2(sch_1):page181_i22@mstr_discrete.res~
(chips)',
 PATH='I22',
 DRAWING='@BASEBOARD_FAB2_LIB.BASEBOARD_FAB2(SCH_1):PAGE181',
 WATTAGE='1/16W',
 TOLERANCE='5%',
 SEC_TYPE='0402',
 MATERIAL='CHIP',
 PHYS_PAGE='181',
 XY='(-2225,2800)',
 ROT='0',
 VER='1',
 VALUE='0.0',
 PACK_TYPE='0402',
 PART_NUMBER='G21497-005',
 LOCATION='R1F8',
 SEC='1',
 CDS_LIB='mstr_discrete',
 CDS_PART_NAME='RES_0402-0.0,5%,1/16W,CHIP,G21A',
 PRIM_FILE='./archive_libs/mstr_discrete/res/chips/chips.prt';

PART_NAME
 R1F9 'RES_0402-0.0,5%,1/16W,EMPTY,G2A':
 ROOM='IO_SLOT',
 NO_XNET_CONNECTION='1';

SECTION_NUMBER 1
 '@BASEBOARD_FAB2_LIB.BASEBOARD_FAB2(SCH_1):PAGE182_I7@MSTR_DISCRETE.RES(CHIPS)':
 C_PATH='@baseboard_fab2_lib.baseboard_fab2(sch_1):page182_i7@mstr_discrete.res(~
chips)',
 P_PATH='@baseboard_fab2_lib.baseboard_fab2(sch_1):page182_i7@mstr_discrete.res(~
chips)',
 PATH='I7',
 DRAWING='@BASEBOARD_FAB2_LIB.BASEBOARD_FAB2(SCH_1):PAGE182',
 WATTAGE='1/16W',
 TOLERANCE='5%',
 SEC_TYPE='0402',
 MATERIAL='EMPTY',
 NO_XNET_CONNECTION='1',
 PHYS_PAGE='182',
 XY='(-7000,-25)',
 ROT='0',
 VER='1',
 VALUE='0.0',
 PACK_TYPE='0402',
 PART_NUMBER='G21497-005',
 LOCATION='R1F9',
 ROOM='IO_SLOT',
 SEC='1',
 CDS_LIB='mstr_discrete',
 CDS_PART_NAME='RES_0402-0.0,5%,1/16W,EMPTY,G2A',
 PRIM_FILE='./archive_libs/mstr_discrete/res/chips/chips.prt';

PART_NAME
 R1G1 'RES_0402-2,1.0%,1/16W,CHIP,G21A':
 ROOM='PROC';

SECTION_NUMBER 1
 '@BASEBOARD_FAB2_LIB.BASEBOARD_FAB2(SCH_1):PAGE100_I25@MSTR_DISCRETE.RES(CHIPS)':
 C_PATH='@baseboard_fab2_lib.baseboard_fab2(sch_1):page100_i25@mstr_discrete.res~
(chips)',
 P_PATH='@baseboard_fab2_lib.baseboard_fab2(sch_1):page100_i25@mstr_discrete.res~
(chips)',
 PATH='I25',
 DRAWING='@BASEBOARD_FAB2_LIB.BASEBOARD_FAB2(SCH_1):PAGE100',
 WATTAGE='1/16W',
 TOLERANCE='1.0%',
 SEC_TYPE='0402',
 MATERIAL='CHIP',
 BOM_COST='PROC_SOCKET',
 PHYS_PAGE='100',
 XY='(225,3625)',
 ROT='0',
 VER='1',
 VALUE='2',
 PACK_TYPE='0402',
 PART_NUMBER='G21796-274',
 LOCATION='R1G1',
 ROOM='PROC',
 SEC='1',
 CDS_LIB='mstr_discrete',
 CDS_PART_NAME='RES_0402-2,1.0%,1/16W,CHIP,G21A',
 PRIM_FILE='./archive_libs/mstr_discrete/res/chips/chips.prt';

PART_NAME
 R1G2 'RES_0402-1.00K,1%,1/16W,CHIP,GA':
 ROOM='MEM';

SECTION_NUMBER 1
 '@BASEBOARD_FAB2_LIB.BASEBOARD_FAB2(SCH_1):PAGE100_I19@MSTR_DISCRETE.RES(CHIPS)':
 C_PATH='@baseboard_fab2_lib.baseboard_fab2(sch_1):page100_i19@mstr_discrete.res~
(chips)',
 P_PATH='@baseboard_fab2_lib.baseboard_fab2(sch_1):page100_i19@mstr_discrete.res~
(chips)',
 PATH='I19',
 DRAWING='@BASEBOARD_FAB2_LIB.BASEBOARD_FAB2(SCH_1):PAGE100',
 WATTAGE='1/16W',
 TOLERANCE='1%',
 SEC_TYPE='0402',
 MATERIAL='CHIP',
 BOM_COST='SM_CONTROLLER',
 PHYS_PAGE='100',
 XY='(450,3950)',
 ROT='2',
 VER='2',
 VALUE='1.00K',
 PACK_TYPE='0402',
 PART_NUMBER='G21796-026',
 LOCATION='R1G2',
 ROOM='MEM',
 SEC='1',
 CDS_LIB='mstr_discrete',
 CDS_PART_NAME='RES_0402-1.00K,1%,1/16W,CHIP,GA',
 PRIM_FILE='./archive_libs/mstr_discrete/res/chips/chips.prt';

PART_NAME
 R1G3 'RES_0402-1.00K,1%,1/16W,CHIP,GA':
 ROOM='MEM';

SECTION_NUMBER 1
 '@BASEBOARD_FAB2_LIB.BASEBOARD_FAB2(SCH_1):PAGE100_I20@MSTR_DISCRETE.RES(CHIPS)':
 C_PATH='@baseboard_fab2_lib.baseboard_fab2(sch_1):page100_i20@mstr_discrete.res~
(chips)',
 P_PATH='@baseboard_fab2_lib.baseboard_fab2(sch_1):page100_i20@mstr_discrete.res~
(chips)',
 PATH='I20',
 DRAWING='@BASEBOARD_FAB2_LIB.BASEBOARD_FAB2(SCH_1):PAGE100',
 WATTAGE='1/16W',
 TOLERANCE='1%',
 SEC_TYPE='0402',
 MATERIAL='CHIP',
 BOM_COST='SM_CONTROLLER',
 PHYS_PAGE='100',
 XY='(525,3300)',
 ROT='2',
 VER='2',
 VALUE='1.00K',
 PACK_TYPE='0402',
 PART_NUMBER='G21796-026',
 LOCATION='R1G3',
 ROOM='MEM',
 SEC='1',
 CDS_LIB='mstr_discrete',
 CDS_PART_NAME='RES_0402-1.00K,1%,1/16W,CHIP,GA',
 PRIM_FILE='./archive_libs/mstr_discrete/res/chips/chips.prt';

PART_NAME
 R1G5 'RES_0402-10.0,1%,1/16W,CHIP,G2A':
 ROOM='VDDQ_GHJ_PWR_VR',
 NO_XNET_CONNECTION='1';

SECTION_NUMBER 1
 '@BASEBOARD_FAB2_LIB.BASEBOARD_FAB2(SCH_1):PAGE223_I13@MSTR_DISCRETE.RES(CHIPS)':
 C_PATH='@baseboard_fab2_lib.baseboard_fab2(sch_1):page223_i13@mstr_discrete.res~
(chips)',
 P_PATH='@baseboard_fab2_lib.baseboard_fab2(sch_1):page223_i13@mstr_discrete.res~
(chips)',
 PATH='I13',
 DRAWING='@BASEBOARD_FAB2_LIB.BASEBOARD_FAB2(SCH_1):PAGE223',
 WATTAGE='1/16W',
 TOLERANCE='1%',
 SEC_TYPE='0402',
 MATERIAL='CHIP',
 NO_XNET_CONNECTION='1',
 PHYS_PAGE='223',
 XY='(-1725,725)',
 ROT='0',
 VER='1',
 VALUE='10.0',
 PACK_TYPE='0402',
 PART_NUMBER='G21796-066',
 LOCATION='R1G5',
 ROOM='VDDQ_GHJ_PWR_VR',
 SEC='1',
 CDS_LIB='mstr_discrete',
 CDS_PART_NAME='RES_0402-10.0,1%,1/16W,CHIP,G2A',
 PRIM_FILE='./archive_libs/mstr_discrete/res/chips/chips.prt';

PART_NAME
 R1G6 'RES_0402-2.26K,1.0%,1/16W,CHIPA':
 ROOM='SMBUS';

SECTION_NUMBER 1
 '@BASEBOARD_FAB2_LIB.BASEBOARD_FAB2(SCH_1):PAGE223_I76@MSTR_DISCRETE.RES(CHIPS)':
 C_PATH='@baseboard_fab2_lib.baseboard_fab2(sch_1):page223_i76@mstr_discrete.res~
(chips)',
 P_PATH='@baseboard_fab2_lib.baseboard_fab2(sch_1):page223_i76@mstr_discrete.res~
(chips)',
 PATH='I76',
 DRAWING='@BASEBOARD_FAB2_LIB.BASEBOARD_FAB2(SCH_1):PAGE223',
 SKU='B',
 WATTAGE='1/16W',
 TOLERANCE='1.0%',
 SEC_TYPE='0402',
 MATERIAL='CHIP',
 BOM_COST='SM_CONTROLLER',
 PHYS_PAGE='223',
 XY='(3550,2750)',
 ROT='0',
 VER='2',
 VALUE='2.26K',
 PACK_TYPE='0402',
 PART_NUMBER='G21796-311',
 LOCATION='R1G6',
 ROOM='SMBUS',
 SEC='1',
 CDS_LIB='mstr_discrete',
 CDS_PART_NAME='RES_0402-2.26K,1.0%,1/16W,CHIPA',
 PRIM_FILE='./archive_libs/mstr_discrete/res/chips/chips.prt';

PART_NAME
 R1G7 'RES_0402-150.0,1%,1/16W,CHIP,GA':
 ROOM='VDDQ_GHJ_PWR_VR';

SECTION_NUMBER 1
 '@BASEBOARD_FAB2_LIB.BASEBOARD_FAB2(SCH_1):PAGE223_I18@MSTR_DISCRETE.RES(CHIPS)':
 C_PATH='@baseboard_fab2_lib.baseboard_fab2(sch_1):page223_i18@mstr_discrete.res~
(chips)',
 P_PATH='@baseboard_fab2_lib.baseboard_fab2(sch_1):page223_i18@mstr_discrete.res~
(chips)',
 PATH='I18',
 DRAWING='@BASEBOARD_FAB2_LIB.BASEBOARD_FAB2(SCH_1):PAGE223',
 WATTAGE='1/16W',
 TOLERANCE='1%',
 SEC_TYPE='0402',
 MATERIAL='CHIP',
 PHYS_PAGE='223',
 XY='(-225,2625)',
 ROT='0',
 VER='1',
 VALUE='150.0',
 PACK_TYPE='0402',
 PART_NUMBER='G21796-009',
 LOCATION='R1G7',
 ROOM='VDDQ_GHJ_PWR_VR',
 SEC='1',
 CDS_LIB='mstr_discrete',
 CDS_PART_NAME='RES_0402-150.0,1%,1/16W,CHIP,GA',
 PRIM_FILE='./archive_libs/mstr_discrete/res/chips/chips.prt';

PART_NAME
 R1G8 'RES_0402-33.2,1%,1/16W,CHIP,G2A':;

SECTION_NUMBER 1
 '@BASEBOARD_FAB2_LIB.BASEBOARD_FAB2(SCH_1):PAGE223_I55@MSTR_DISCRETE.RES(CHIPS)':
 C_PATH='@baseboard_fab2_lib.baseboard_fab2(sch_1):page223_i55@mstr_discrete.res~
(chips)',
 P_PATH='@baseboard_fab2_lib.baseboard_fab2(sch_1):page223_i55@mstr_discrete.res~
(chips)',
 PATH='I55',
 DRAWING='@BASEBOARD_FAB2_LIB.BASEBOARD_FAB2(SCH_1):PAGE223',
 WATTAGE='1/16W',
 TOLERANCE='1%',
 SEC_TYPE='0402',
 MATERIAL='CHIP',
 PHYS_PAGE='223',
 XY='(3175,2100)',
 ROT='0',
 VER='1',
 VALUE='33.2',
 PACK_TYPE='0402',
 PART_NUMBER='G21796-074',
 LOCATION='R1G8',
 SEC='1',
 CDS_LIB='mstr_discrete',
 CDS_PART_NAME='RES_0402-33.2,1%,1/16W,CHIP,G2A',
 PRIM_FILE='./archive_libs/mstr_discrete/res/chips/chips.prt';

PART_NAME
 R1G9 'RES_0402-0.0,5%,1/16W,CHIP,G21A':
 ROOM='VDDQ_GHJ_PWR_VR';

SECTION_NUMBER 1
 '@BASEBOARD_FAB2_LIB.BASEBOARD_FAB2(SCH_1):PAGE223_I50@MSTR_DISCRETE.RES(CHIPS)':
 C_PATH='@baseboard_fab2_lib.baseboard_fab2(sch_1):page223_i50@mstr_discrete.res~
(chips)',
 P_PATH='@baseboard_fab2_lib.baseboard_fab2(sch_1):page223_i50@mstr_discrete.res~
(chips)',
 PATH='I50',
 DRAWING='@BASEBOARD_FAB2_LIB.BASEBOARD_FAB2(SCH_1):PAGE223',
 WATTAGE='1/16W',
 TOLERANCE='5%',
 SEC_TYPE='0402',
 MATERIAL='CHIP',
 PHYS_PAGE='223',
 XY='(2875,2050)',
 ROT='0',
 VER='1',
 VALUE='0.0',
 PACK_TYPE='0402',
 PART_NUMBER='G21497-005',
 LOCATION='R1G9',
 ROOM='VDDQ_GHJ_PWR_VR',
 SEC='1',
 CDS_LIB='mstr_discrete',
 CDS_PART_NAME='RES_0402-0.0,5%,1/16W,CHIP,G21A',
 PRIM_FILE='./archive_libs/mstr_discrete/res/chips/chips.prt';

PART_NAME
 R1G10 'RES_0402-0.0,5%,1/16W,CHIP,G21A':
 ROOM='VDDQ_GHJ_PWR_VR';

SECTION_NUMBER 1
 '@BASEBOARD_FAB2_LIB.BASEBOARD_FAB2(SCH_1):PAGE223_I41@MSTR_DISCRETE.RES(CHIPS)':
 C_PATH='@baseboard_fab2_lib.baseboard_fab2(sch_1):page223_i41@mstr_discrete.res~
(chips)',
 P_PATH='@baseboard_fab2_lib.baseboard_fab2(sch_1):page223_i41@mstr_discrete.res~
(chips)',
 PATH='I41',
 DRAWING='@BASEBOARD_FAB2_LIB.BASEBOARD_FAB2(SCH_1):PAGE223',
 WATTAGE='1/16W',
 TOLERANCE='5%',
 SEC_TYPE='0402',
 MATERIAL='CHIP',
 PHYS_PAGE='223',
 XY='(2850,1350)',
 ROT='0',
 VER='1',
 VALUE='0.0',
 PACK_TYPE='0402',
 PART_NUMBER='G21497-005',
 LOCATION='R1G10',
 ROOM='VDDQ_GHJ_PWR_VR',
 SEC='1',
 CDS_LIB='mstr_discrete',
 CDS_PART_NAME='RES_0402-0.0,5%,1/16W,CHIP,G21A',
 PRIM_FILE='./archive_libs/mstr_discrete/res/chips/chips.prt';

PART_NAME
 R1G11 'RES_0402-1.00K,1%,1/16W,CHIP,GA':
 ROOM='RQ_PVDDQ_GHJ_VRHOT_LVT3_N';

SECTION_NUMBER 1
 '@BASEBOARD_FAB2_LIB.BASEBOARD_FAB2(SCH_1):PAGE223_I49@MSTR_DISCRETE.RES(CHIPS)':
 C_PATH='@baseboard_fab2_lib.baseboard_fab2(sch_1):page223_i49@mstr_discrete.res~
(chips)',
 P_PATH='@baseboard_fab2_lib.baseboard_fab2(sch_1):page223_i49@mstr_discrete.res~
(chips)',
 PATH='I49',
 DRAWING='@BASEBOARD_FAB2_LIB.BASEBOARD_FAB2(SCH_1):PAGE223',
 WATTAGE='1/16W',
 TOLERANCE='1%',
 SEC_TYPE='0402',
 MATERIAL='CHIP',
 PHYS_PAGE='223',
 XY='(2100,2750)',
 ROT='0',
 VER='2',
 VALUE='1.00K',
 PACK_TYPE='0402',
 PART_NUMBER='G21796-026',
 LOCATION='R1G11',
 ROOM='RQ_PVDDQ_GHJ_VRHOT_LVT3_N',
 SEC='1',
 CDS_LIB='mstr_discrete',
 CDS_PART_NAME='RES_0402-1.00K,1%,1/16W,CHIP,GA',
 PRIM_FILE='./archive_libs/mstr_discrete/res/chips/chips.prt';

PART_NAME
 R1G12 'RES_0402-22.1,1.0%,1/16W,CHIP,A':
 ROOM='VDDQ_GHJ_PWR_VR';

SECTION_NUMBER 1
 '@BASEBOARD_FAB2_LIB.BASEBOARD_FAB2(SCH_1):PAGE223_I54@MSTR_DISCRETE.RES(CHIPS)':
 C_PATH='@baseboard_fab2_lib.baseboard_fab2(sch_1):page223_i54@mstr_discrete.res~
(chips)',
 P_PATH='@baseboard_fab2_lib.baseboard_fab2(sch_1):page223_i54@mstr_discrete.res~
(chips)',
 PATH='I54',
 DRAWING='@BASEBOARD_FAB2_LIB.BASEBOARD_FAB2(SCH_1):PAGE223',
 POP='NOPOP',
 WATTAGE='1/16W',
 TOLERANCE='1.0%',
 SEC_TYPE='0402',
 MATERIAL='CHIP',
 PHYS_PAGE='223',
 XY='(3275,2200)',
 ROT='0',
 VER='1',
 VALUE='22.1',
 PACK_TYPE='0402',
 PART_NUMBER='G21796-250',
 LOCATION='R1G12',
 ROOM='VDDQ_GHJ_PWR_VR',
 SEC='1',
 CDS_LIB='mstr_discrete',
 CDS_PART_NAME='RES_0402-22.1,1.0%,1/16W,CHIP,A',
 PRIM_FILE='./archive_libs/mstr_discrete/res/chips/chips.prt';

PART_NAME
 R1G14 'RES_0402-2,1.0%,1/16W,CHIP,G21A':
 ROOM='PROC';

SECTION_NUMBER 1
 '@BASEBOARD_FAB2_LIB.BASEBOARD_FAB2(SCH_1):PAGE100_I41@MSTR_DISCRETE.RES(CHIPS)':
 C_PATH='@baseboard_fab2_lib.baseboard_fab2(sch_1):page100_i41@mstr_discrete.res~
(chips)',
 P_PATH='@baseboard_fab2_lib.baseboard_fab2(sch_1):page100_i41@mstr_discrete.res~
(chips)',
 PATH='I41',
 DRAWING='@BASEBOARD_FAB2_LIB.BASEBOARD_FAB2(SCH_1):PAGE100',
 WATTAGE='1/16W',
 TOLERANCE='1.0%',
 SEC_TYPE='0402',
 MATERIAL='CHIP',
 BOM_COST='PROC_SOCKET',
 PHYS_PAGE='100',
 XY='(2675,3625)',
 ROT='0',
 VER='1',
 VALUE='2',
 PACK_TYPE='0402',
 PART_NUMBER='G21796-274',
 LOCATION='R1G14',
 ROOM='PROC',
 SEC='1',
 CDS_LIB='mstr_discrete',
 CDS_PART_NAME='RES_0402-2,1.0%,1/16W,CHIP,G21A',
 PRIM_FILE='./archive_libs/mstr_discrete/res/chips/chips.prt';

PART_NAME
 R1G15 'RES_0402-1.00K,1%,1/16W,CHIP,GA':
 ROOM='MEM';

SECTION_NUMBER 1
 '@BASEBOARD_FAB2_LIB.BASEBOARD_FAB2(SCH_1):PAGE100_I35@MSTR_DISCRETE.RES(CHIPS)':
 C_PATH='@baseboard_fab2_lib.baseboard_fab2(sch_1):page100_i35@mstr_discrete.res~
(chips)',
 P_PATH='@baseboard_fab2_lib.baseboard_fab2(sch_1):page100_i35@mstr_discrete.res~
(chips)',
 PATH='I35',
 DRAWING='@BASEBOARD_FAB2_LIB.BASEBOARD_FAB2(SCH_1):PAGE100',
 WATTAGE='1/16W',
 TOLERANCE='1%',
 SEC_TYPE='0402',
 MATERIAL='CHIP',
 BOM_COST='SM_CONTROLLER',
 PHYS_PAGE='100',
 XY='(2900,3950)',
 ROT='2',
 VER='2',
 VALUE='1.00K',
 PACK_TYPE='0402',
 PART_NUMBER='G21796-026',
 LOCATION='R1G15',
 ROOM='MEM',
 SEC='1',
 CDS_LIB='mstr_discrete',
 CDS_PART_NAME='RES_0402-1.00K,1%,1/16W,CHIP,GA',
 PRIM_FILE='./archive_libs/mstr_discrete/res/chips/chips.prt';

PART_NAME
 R1G16 'RES_0402-1.00K,1%,1/16W,CHIP,GA':
 ROOM='VDDQ_GHJ_PWR_VR';

SECTION_NUMBER 1
 '@BASEBOARD_FAB2_LIB.BASEBOARD_FAB2(SCH_1):PAGE223_I48@MSTR_DISCRETE.RES(CHIPS)':
 C_PATH='@baseboard_fab2_lib.baseboard_fab2(sch_1):page223_i48@mstr_discrete.res~
(chips)',
 P_PATH='@baseboard_fab2_lib.baseboard_fab2(sch_1):page223_i48@mstr_discrete.res~
(chips)',
 PATH='I48',
 DRAWING='@BASEBOARD_FAB2_LIB.BASEBOARD_FAB2(SCH_1):PAGE223',
 WATTAGE='1/16W',
 TOLERANCE='1%',
 SEC_TYPE='0402',
 MATERIAL='CHIP',
 PHYS_PAGE='223',
 XY='(2400,2750)',
 ROT='0',
 VER='2',
 VALUE='1.00K',
 PACK_TYPE='0402',
 PART_NUMBER='G21796-026',
 LOCATION='R1G16',
 ROOM='VDDQ_GHJ_PWR_VR',
 SEC='1',
 CDS_LIB='mstr_discrete',
 CDS_PART_NAME='RES_0402-1.00K,1%,1/16W,CHIP,GA',
 PRIM_FILE='./archive_libs/mstr_discrete/res/chips/chips.prt';

PART_NAME
 R1G17 'RES_0402-1.00K,1%,1/16W,CHIP,GA':
 ROOM='MEM';

SECTION_NUMBER 1
 '@BASEBOARD_FAB2_LIB.BASEBOARD_FAB2(SCH_1):PAGE100_I36@MSTR_DISCRETE.RES(CHIPS)':
 C_PATH='@baseboard_fab2_lib.baseboard_fab2(sch_1):page100_i36@mstr_discrete.res~
(chips)',
 P_PATH='@baseboard_fab2_lib.baseboard_fab2(sch_1):page100_i36@mstr_discrete.res~
(chips)',
 PATH='I36',
 DRAWING='@BASEBOARD_FAB2_LIB.BASEBOARD_FAB2(SCH_1):PAGE100',
 WATTAGE='1/16W',
 TOLERANCE='1%',
 SEC_TYPE='0402',
 MATERIAL='CHIP',
 BOM_COST='SM_CONTROLLER',
 PHYS_PAGE='100',
 XY='(2975,3300)',
 ROT='2',
 VER='2',
 VALUE='1.00K',
 PACK_TYPE='0402',
 PART_NUMBER='G21796-026',
 LOCATION='R1G17',
 ROOM='MEM',
 SEC='1',
 CDS_LIB='mstr_discrete',
 CDS_PART_NAME='RES_0402-1.00K,1%,1/16W,CHIP,GA',
 PRIM_FILE='./archive_libs/mstr_discrete/res/chips/chips.prt';

PART_NAME
 R1G20 'RES_0603-120.0,1%,1/10W,CHIP,GA':
 ROOM='VDDQ_GHJ_PWR_VR';

SECTION_NUMBER 1
 '@BASEBOARD_FAB2_LIB.BASEBOARD_FAB2(SCH_1):PAGE225_I58@MSTR_DISCRETE.RES(CHIPS)':
 C_PATH='@baseboard_fab2_lib.baseboard_fab2(sch_1):page225_i58@mstr_discrete.res~
(chips)',
 P_PATH='@baseboard_fab2_lib.baseboard_fab2(sch_1):page225_i58@mstr_discrete.res~
(chips)',
 PATH='I58',
 DRAWING='@BASEBOARD_FAB2_LIB.BASEBOARD_FAB2(SCH_1):PAGE225',
 WATTAGE='1/10W',
 TOLERANCE='1%',
 MATERIAL='CHIP',
 BOM_COST='MEM_VRD_PVPP_AB',
 PHYS_PAGE='225',
 XY='(4450,-25)',
 ROT='0',
 VER='2',
 VALUE='120.0',
 PACK_TYPE='0603',
 PART_NUMBER='G22026-003',
 LOCATION='R1G20',
 ROOM='VDDQ_GHJ_PWR_VR',
 CDS_LIB='mstr_discrete',
 CDS_PART_NAME='RES_0603-120.0,1%,1/10W,CHIP,GA',
 PRIM_FILE='./archive_libs/mstr_discrete/res/chips/chips.prt';

PART_NAME
 R1G22 'RES_0402-3.16K,1%,1/16W,CHIP,GA':
 ROOM='PVCCIN_CPU1_VR';

SECTION_NUMBER 1
 '@BASEBOARD_FAB2_LIB.BASEBOARD_FAB2(SCH_1):PAGE223_I74@MSTR_DISCRETE.RES(CHIPS)':
 C_PATH='@baseboard_fab2_lib.baseboard_fab2(sch_1):page223_i74@mstr_discrete.res~
(chips)',
 P_PATH='@baseboard_fab2_lib.baseboard_fab2(sch_1):page223_i74@mstr_discrete.res~
(chips)',
 PATH='I74',
 DRAWING='@BASEBOARD_FAB2_LIB.BASEBOARD_FAB2(SCH_1):PAGE223',
 WATTAGE='1/16W',
 TOLERANCE='1%',
 SEC_TYPE='0402',
 MATERIAL='CHIP',
 PHYS_PAGE='223',
 XY='(625,-250)',
 ROT='0',
 VER='2',
 VALUE='3.16K',
 PACK_TYPE='0402',
 PART_NUMBER='G21796-043',
 LOCATION='R1G22',
 ROOM='PVCCIN_CPU1_VR',
 SEC='1',
 CDS_LIB='mstr_discrete',
 CDS_PART_NAME='RES_0402-3.16K,1%,1/16W,CHIP,GA',
 PRIM_FILE='./archive_libs/mstr_discrete/res/chips/chips.prt';

PART_NAME
 R1G23 'RES_0402-5.36K,1.0%,1/16W,CHIPA':
 ROOM='VDDQ_GHJ_PWR_VR';

SECTION_NUMBER 1
 '@BASEBOARD_FAB2_LIB.BASEBOARD_FAB2(SCH_1):PAGE223_I73@MSTR_DISCRETE.RES(CHIPS)':
 C_PATH='@baseboard_fab2_lib.baseboard_fab2(sch_1):page223_i73@mstr_discrete.res~
(chips)',
 P_PATH='@baseboard_fab2_lib.baseboard_fab2(sch_1):page223_i73@mstr_discrete.res~
(chips)',
 PATH='I73',
 DRAWING='@BASEBOARD_FAB2_LIB.BASEBOARD_FAB2(SCH_1):PAGE223',
 POP='NOPOP',
 WATTAGE='1/16W',
 TOLERANCE='1.0%',
 SEC_TYPE='0402',
 MATERIAL='CHIP',
 PHYS_PAGE='223',
 XY='(275,-250)',
 ROT='0',
 VER='2',
 VALUE='5.36K',
 PACK_TYPE='0402',
 PART_NUMBER='G21796-297',
 LOCATION='R1G23',
 ROOM='VDDQ_GHJ_PWR_VR',
 SEC='1',
 CDS_LIB='mstr_discrete',
 CDS_PART_NAME='RES_0402-5.36K,1.0%,1/16W,CHIPA',
 PRIM_FILE='./archive_libs/mstr_discrete/res/chips/chips.prt';

PART_NAME
 R1G25 'RES_0402-68.1K,1%,1/16W,EMPTY,A':;

SECTION_NUMBER 1
 '@BASEBOARD_FAB2_LIB.BASEBOARD_FAB2(SCH_1):PAGE224_I114@MSTR_DISCRETE.RES(CHIPS)':
 C_PATH='@baseboard_fab2_lib.baseboard_fab2(sch_1):page224_i114@mstr_discrete.re~
s(chips)',
 P_PATH='@baseboard_fab2_lib.baseboard_fab2(sch_1):page224_i114@mstr_discrete.re~
s(chips)',
 PATH='I114',
 DRAWING='@BASEBOARD_FAB2_LIB.BASEBOARD_FAB2(SCH_1):PAGE224',
 BOM_SS='NOPOP',
 WATTAGE='1/16W',
 TOLERANCE='1%',
 SEC_TYPE='0402',
 MATERIAL='EMPTY',
 PHYS_PAGE='224',
 XY='(4650,25)',
 ROT='0',
 VER='2',
 VALUE='68.1K',
 PACK_TYPE='0402',
 PART_NUMBER='G21796-187',
 LOCATION='R1G25',
 SEC='1',
 CDS_LIB='mstr_discrete',
 CDS_PART_NAME='RES_0402-68.1K,1%,1/16W,EMPTY,A',
 PRIM_FILE='./archive_libs/mstr_discrete/res/chips/chips.prt';

PART_NAME
 R1G26 'RES_0402-68.1K,1%,1/16W,EMPTY,A':;

SECTION_NUMBER 1
 '@BASEBOARD_FAB2_LIB.BASEBOARD_FAB2(SCH_1):PAGE224_I112@MSTR_DISCRETE.RES(CHIPS)':
 C_PATH='@baseboard_fab2_lib.baseboard_fab2(sch_1):page224_i112@mstr_discrete.re~
s(chips)',
 P_PATH='@baseboard_fab2_lib.baseboard_fab2(sch_1):page224_i112@mstr_discrete.re~
s(chips)',
 PATH='I112',
 DRAWING='@BASEBOARD_FAB2_LIB.BASEBOARD_FAB2(SCH_1):PAGE224',
 WATTAGE='1/16W',
 TOLERANCE='1%',
 SEC_TYPE='0402',
 MATERIAL='EMPTY',
 PHYS_PAGE='224',
 XY='(4625,2400)',
 ROT='0',
 VER='2',
 VALUE='68.1K',
 PACK_TYPE='0402',
 PART_NUMBER='G21796-187',
 LOCATION='R1G26',
 SEC='1',
 CDS_LIB='mstr_discrete',
 CDS_PART_NAME='RES_0402-68.1K,1%,1/16W,EMPTY,A',
 PRIM_FILE='./archive_libs/mstr_discrete/res/chips/chips.prt';

PART_NAME
 R1L2 'RES_0402-10.0,1%,1/16W,CHIP,G2A':
 ROOM='BMC_DEBUG_HEADER';

SECTION_NUMBER 1
 '@BASEBOARD_FAB2_LIB.BASEBOARD_FAB2(SCH_1):PAGE155_I186@MSTR_DISCRETE.RES(CHIPS)':
 C_PATH='@baseboard_fab2_lib.baseboard_fab2(sch_1):page155_i186@mstr_discrete.re~
s(chips)',
 P_PATH='@baseboard_fab2_lib.baseboard_fab2(sch_1):page155_i186@mstr_discrete.re~
s(chips)',
 PATH='I186',
 DRAWING='@BASEBOARD_FAB2_LIB.BASEBOARD_FAB2(SCH_1):PAGE155',
 WATTAGE='1/16W',
 TOLERANCE='1%',
 MATERIAL='CHIP',
 BOM_COST='DEBUG',
 PHYS_PAGE='155',
 XY='(-7050,2000)',
 ROT='0',
 VER='1',
 VALUE='10.0',
 PACK_TYPE='0402',
 PART_NUMBER='G21796-066',
 LOCATION='R1L2',
 ROOM='BMC_DEBUG_HEADER',
 CDS_LIB='mstr_discrete',
 CDS_PART_NAME='RES_0402-10.0,1%,1/16W,CHIP,G2A',
 PRIM_FILE='./archive_libs/mstr_discrete/res/chips/chips.prt';

PART_NAME
 R1L6 'RES_0402-0.0,5%,1/16W,CHIP,G21A':
 ROOM='UART_MUX';

SECTION_NUMBER 1
 '@BASEBOARD_FAB2_LIB.BASEBOARD_FAB2(SCH_1):PAGE168_I6@MSTR_DISCRETE.RES(CHIPS)':
 C_PATH='@baseboard_fab2_lib.baseboard_fab2(sch_1):page168_i6@mstr_discrete.res(~
chips)',
 P_PATH='@baseboard_fab2_lib.baseboard_fab2(sch_1):page168_i6@mstr_discrete.res(~
chips)',
 PATH='I6',
 DRAWING='@BASEBOARD_FAB2_LIB.BASEBOARD_FAB2(SCH_1):PAGE168',
 WATTAGE='1/16W',
 TOLERANCE='5%',
 SEC_TYPE='0402',
 MATERIAL='CHIP',
 BOM_COST='DEBUG',
 PHYS_PAGE='168',
 XY='(-6975,2750)',
 ROT='0',
 VER='1',
 VALUE='0.0',
 PACK_TYPE='0402',
 PART_NUMBER='G21497-005',
 LOCATION='R1L6',
 ROOM='UART_MUX',
 SEC='1',
 CDS_LIB='mstr_discrete',
 CDS_PART_NAME='RES_0402-0.0,5%,1/16W,CHIP,G21A',
 PRIM_FILE='./archive_libs/mstr_discrete/res/chips/chips.prt';

PART_NAME
 R1L7 'RES_0402-4.75K,1%,1/16W,CHIP,GA':
 ROOM='BMC_MISC';

SECTION_NUMBER 1
 '@BASEBOARD_FAB2_LIB.BASEBOARD_FAB2(SCH_1):PAGE157_I382@MSTR_DISCRETE.RES(CHIPS)':
 C_PATH='@baseboard_fab2_lib.baseboard_fab2(sch_1):page157_i382@mstr_discrete.re~
s(chips)',
 P_PATH='@baseboard_fab2_lib.baseboard_fab2(sch_1):page157_i382@mstr_discrete.re~
s(chips)',
 PATH='I382',
 DRAWING='@BASEBOARD_FAB2_LIB.BASEBOARD_FAB2(SCH_1):PAGE157',
 WATTAGE='1/16W',
 TOLERANCE='1%',
 SEC_TYPE='0402',
 MATERIAL='CHIP',
 BOM_COST='SM_CONTROLLER',
 PHYS_PAGE='157',
 XY='(-7175,3425)',
 ROT='0',
 VER='1',
 VALUE='4.75K',
 PACK_TYPE='0402',
 PART_NUMBER='G21796-072',
 LOCATION='R1L7',
 ROOM='BMC_MISC',
 SEC='1',
 CDS_LIB='mstr_discrete',
 CDS_PART_NAME='RES_0402-4.75K,1%,1/16W,CHIP,GA',
 PRIM_FILE='./archive_libs/mstr_discrete/res/chips/chips.prt';

PART_NAME
 R1L8 'RES_0402-470.0,5%,1/16W,CHIP,GA':
 ROOM='MIO_CHASSIS';

SECTION_NUMBER 1
 '@BASEBOARD_FAB2_LIB.BASEBOARD_FAB2(SCH_1):PAGE175_I58@MSTR_DISCRETE.RES(CHIPS)':
 C_PATH='@baseboard_fab2_lib.baseboard_fab2(sch_1):page175_i58@mstr_discrete.res~
(chips)',
 P_PATH='@baseboard_fab2_lib.baseboard_fab2(sch_1):page175_i58@mstr_discrete.res~
(chips)',
 PATH='I58',
 DRAWING='@BASEBOARD_FAB2_LIB.BASEBOARD_FAB2(SCH_1):PAGE175',
 WATTAGE='1/16W',
 TOLERANCE='5%',
 SEC_TYPE='0402',
 MATERIAL='CHIP',
 BOM_COST='MIO_CHASSIS',
 PHYS_PAGE='175',
 XY='(-1175,1350)',
 ROT='0',
 VER='2',
 VALUE='470.0',
 PACK_TYPE='0402',
 PART_NUMBER='G21497-024',
 LOCATION='R1L8',
 ROOM='MIO_CHASSIS',
 SEC='1',
 CDS_LIB='mstr_discrete',
 CDS_PART_NAME='RES_0402-470.0,5%,1/16W,CHIP,GA',
 PRIM_FILE='./archive_libs/mstr_discrete/res/chips/chips.prt';

PART_NAME
 R1L9 'RES_0402-100.0K,1%,1/16W,CHIP,A':
 ROOM='BMC_DEBUG_HEADER';

SECTION_NUMBER 1
 '@BASEBOARD_FAB2_LIB.BASEBOARD_FAB2(SCH_1):PAGE155_I130@MSTR_DISCRETE.RES(CHIPS)':
 C_PATH='@baseboard_fab2_lib.baseboard_fab2(sch_1):page155_i130@mstr_discrete.re~
s(chips)',
 P_PATH='@baseboard_fab2_lib.baseboard_fab2(sch_1):page155_i130@mstr_discrete.re~
s(chips)',
 PATH='I130',
 DRAWING='@BASEBOARD_FAB2_LIB.BASEBOARD_FAB2(SCH_1):PAGE155',
 WATTAGE='1/16W',
 TOLERANCE='1%',
 SEC_TYPE='0402',
 MATERIAL='CHIP',
 BOM_COST='DEBUG',
 PHYS_PAGE='155',
 XY='(-5950,2575)',
 ROT='0',
 VER='2',
 VALUE='100.0K',
 PACK_TYPE='0402',
 PART_NUMBER='G21796-010',
 LOCATION='R1L9',
 ROOM='BMC_DEBUG_HEADER',
 SEC='1',
 CDS_LIB='mstr_discrete',
 CDS_PART_NAME='RES_0402-100.0K,1%,1/16W,CHIP,A',
 PRIM_FILE='./archive_libs/mstr_discrete/res/chips/chips.prt';

PART_NAME
 R1L11 'RES_0402-10.0,1%,1/16W,CHIP,G2A':
 ROOM='BMC_DEBUG_HEADER';

SECTION_NUMBER 1
 '@BASEBOARD_FAB2_LIB.BASEBOARD_FAB2(SCH_1):PAGE155_I76@MSTR_DISCRETE.RES(CHIPS)':
 C_PATH='@baseboard_fab2_lib.baseboard_fab2(sch_1):page155_i76@mstr_discrete.res~
(chips)',
 P_PATH='@baseboard_fab2_lib.baseboard_fab2(sch_1):page155_i76@mstr_discrete.res~
(chips)',
 PATH='I76',
 DRAWING='@BASEBOARD_FAB2_LIB.BASEBOARD_FAB2(SCH_1):PAGE155',
 WATTAGE='1/16W',
 TOLERANCE='1%',
 MATERIAL='CHIP',
 BOM_COST='DEBUG',
 PHYS_PAGE='155',
 XY='(-6900,3600)',
 ROT='0',
 VER='1',
 VALUE='10.0',
 PACK_TYPE='0402',
 PART_NUMBER='G21796-066',
 LOCATION='R1L11',
 ROOM='BMC_DEBUG_HEADER',
 CDS_LIB='mstr_discrete',
 CDS_PART_NAME='RES_0402-10.0,1%,1/16W,CHIP,G2A',
 PRIM_FILE='./archive_libs/mstr_discrete/res/chips/chips.prt';

PART_NAME
 R1L12 'RES_0402-0.0,5%,1/16W,CHIP,G21A':
 ROOM='MIO_CHASSIS';

SECTION_NUMBER 1
 '@BASEBOARD_FAB2_LIB.BASEBOARD_FAB2(SCH_1):PAGE175_I63@MSTR_DISCRETE.RES(CHIPS)':
 C_PATH='@baseboard_fab2_lib.baseboard_fab2(sch_1):page175_i63@mstr_discrete.res~
(chips)',
 P_PATH='@baseboard_fab2_lib.baseboard_fab2(sch_1):page175_i63@mstr_discrete.res~
(chips)',
 PATH='I63',
 DRAWING='@BASEBOARD_FAB2_LIB.BASEBOARD_FAB2(SCH_1):PAGE175',
 WATTAGE='1/16W',
 TOLERANCE='5%',
 SEC_TYPE='0402',
 MATERIAL='CHIP',
 BOM_COST='MIO_CHASSIS',
 PHYS_PAGE='175',
 XY='(-3525,1075)',
 ROT='0',
 VER='1',
 VALUE='0.0',
 PACK_TYPE='0402',
 PART_NUMBER='G21497-005',
 LOCATION='R1L12',
 ROOM='MIO_CHASSIS',
 SEC='1',
 CDS_LIB='mstr_discrete',
 CDS_PART_NAME='RES_0402-0.0,5%,1/16W,CHIP,G21A',
 PRIM_FILE='./archive_libs/mstr_discrete/res/chips/chips.prt';

PART_NAME
 R1L13 'RES_0402-1.00K,1%,1/16W,CHIP,GA':
 ROOM='DEBUG';

SECTION_NUMBER 1
 '@BASEBOARD_FAB2_LIB.BASEBOARD_FAB2(SCH_1):PAGE111_I6@MSTR_DISCRETE.RES(CHIPS)':
 C_PATH='@baseboard_fab2_lib.baseboard_fab2(sch_1):page111_i6@mstr_discrete.res(~
chips)',
 P_PATH='@baseboard_fab2_lib.baseboard_fab2(sch_1):page111_i6@mstr_discrete.res(~
chips)',
 PATH='I6',
 DRAWING='@BASEBOARD_FAB2_LIB.BASEBOARD_FAB2(SCH_1):PAGE111',
 WATTAGE='1/16W',
 TOLERANCE='1%',
 SEC_TYPE='0402',
 MATERIAL='CHIP',
 BOM_COST='DEBUG',
 PHYS_PAGE='111',
 XY='(2725,2150)',
 ROT='0',
 VER='1',
 VALUE='1.00K',
 PACK_TYPE='0402',
 PART_NUMBER='G21796-026',
 LOCATION='R1L13',
 ROOM='DEBUG',
 SEC='1',
 CDS_LIB='mstr_discrete',
 CDS_PART_NAME='RES_0402-1.00K,1%,1/16W,CHIP,GA',
 PRIM_FILE='./archive_libs/mstr_discrete/res/chips/chips.prt';

PART_NAME
 R1L14 'RES_0402-10.0,1%,1/16W,CHIP,G2A':
 ROOM='BMC_DEBUG_HEADER';

SECTION_NUMBER 1
 '@BASEBOARD_FAB2_LIB.BASEBOARD_FAB2(SCH_1):PAGE155_I75@MSTR_DISCRETE.RES(CHIPS)':
 C_PATH='@baseboard_fab2_lib.baseboard_fab2(sch_1):page155_i75@mstr_discrete.res~
(chips)',
 P_PATH='@baseboard_fab2_lib.baseboard_fab2(sch_1):page155_i75@mstr_discrete.res~
(chips)',
 PATH='I75',
 DRAWING='@BASEBOARD_FAB2_LIB.BASEBOARD_FAB2(SCH_1):PAGE155',
 WATTAGE='1/16W',
 TOLERANCE='1%',
 MATERIAL='CHIP',
 BOM_COST='DEBUG',
 PHYS_PAGE='155',
 XY='(-6900,3750)',
 ROT='0',
 VER='1',
 VALUE='10.0',
 PACK_TYPE='0402',
 PART_NUMBER='G21796-066',
 LOCATION='R1L14',
 ROOM='BMC_DEBUG_HEADER',
 CDS_LIB='mstr_discrete',
 CDS_PART_NAME='RES_0402-10.0,1%,1/16W,CHIP,G2A',
 PRIM_FILE='./archive_libs/mstr_discrete/res/chips/chips.prt';

PART_NAME
 R1L15 'RES_0402-150.0,1%,1/16W,CHIP,GA':
 ROOM='DEBUG';

SECTION_NUMBER 1
 '@BASEBOARD_FAB2_LIB.BASEBOARD_FAB2(SCH_1):PAGE112_I60@MSTR_DISCRETE.RES(CHIPS)':
 C_PATH='@baseboard_fab2_lib.baseboard_fab2(sch_1):page112_i60@mstr_discrete.res~
(chips)',
 P_PATH='@baseboard_fab2_lib.baseboard_fab2(sch_1):page112_i60@mstr_discrete.res~
(chips)',
 PATH='I60',
 DRAWING='@BASEBOARD_FAB2_LIB.BASEBOARD_FAB2(SCH_1):PAGE112',
 WATTAGE='1/16W',
 TOLERANCE='1%',
 SEC_TYPE='0402',
 MATERIAL='CHIP',
 PHYS_PAGE='112',
 XY='(500,2400)',
 ROT='0',
 VER='2',
 VALUE='150.0',
 PACK_TYPE='0402',
 PART_NUMBER='G21796-009',
 LOCATION='R1L15',
 ROOM='DEBUG',
 SEC='1',
 CDS_LIB='mstr_discrete',
 CDS_PART_NAME='RES_0402-150.0,1%,1/16W,CHIP,GA',
 PRIM_FILE='./archive_libs/mstr_discrete/res/chips/chips.prt';

PART_NAME
 R1L16 'RES_0402-49.9,1%,1/16W,CHIP,G2A':
 ROOM='V_SUPER';

SECTION_NUMBER 1
 '@BASEBOARD_FAB2_LIB.BASEBOARD_FAB2(SCH_1):PAGE196_I68@MSTR_DISCRETE.RES(CHIPS)':
 C_PATH='@baseboard_fab2_lib.baseboard_fab2(sch_1):page196_i68@mstr_discrete.res~
(chips)',
 P_PATH='@baseboard_fab2_lib.baseboard_fab2(sch_1):page196_i68@mstr_discrete.res~
(chips)',
 PATH='I68',
 DRAWING='@BASEBOARD_FAB2_LIB.BASEBOARD_FAB2(SCH_1):PAGE196',
 WATTAGE='1/16W',
 TOLERANCE='1%',
 SEC_TYPE='0402',
 MATERIAL='CHIP',
 PHYS_PAGE='196',
 XY='(1300,1250)',
 ROT='0',
 VER='1',
 VALUE='49.9',
 PACK_TYPE='0402',
 PART_NUMBER='G21796-047',
 LOCATION='R1L16',
 ROOM='V_SUPER',
 SEC='1',
 CDS_LIB='mstr_discrete',
 CDS_PART_NAME='RES_0402-49.9,1%,1/16W,CHIP,G2A',
 PRIM_FILE='./archive_libs/mstr_discrete/res/chips/chips.prt';

PART_NAME
 R1L17 'RES_0402-150.0,1%,1/16W,CHIP,GA':
 ROOM='DEBUG';

SECTION_NUMBER 1
 '@BASEBOARD_FAB2_LIB.BASEBOARD_FAB2(SCH_1):PAGE111_I56@MSTR_DISCRETE.RES(CHIPS)':
 C_PATH='@baseboard_fab2_lib.baseboard_fab2(sch_1):page111_i56@mstr_discrete.res~
(chips)',
 P_PATH='@baseboard_fab2_lib.baseboard_fab2(sch_1):page111_i56@mstr_discrete.res~
(chips)',
 PATH='I56',
 DRAWING='@BASEBOARD_FAB2_LIB.BASEBOARD_FAB2(SCH_1):PAGE111',
 WATTAGE='1/16W',
 TOLERANCE='1%',
 SEC_TYPE='0402',
 MATERIAL='CHIP',
 BOM_COST='DEBUG',
 PHYS_PAGE='111',
 XY='(-1400,1100)',
 ROT='0',
 VER='1',
 VALUE='150.0',
 PACK_TYPE='0402',
 PART_NUMBER='G21796-009',
 LOCATION='R1L17',
 ROOM='DEBUG',
 SEC='1',
 CDS_LIB='mstr_discrete',
 CDS_PART_NAME='RES_0402-150.0,1%,1/16W,CHIP,GA',
 PRIM_FILE='./archive_libs/mstr_discrete/res/chips/chips.prt';

PART_NAME
 R1L18 'RES_0402-10.0,1%,1/16W,CHIP,G2A':
 ROOM='BMC_DEBUG_HEADER';

SECTION_NUMBER 1
 '@BASEBOARD_FAB2_LIB.BASEBOARD_FAB2(SCH_1):PAGE155_I74@MSTR_DISCRETE.RES(CHIPS)':
 C_PATH='@baseboard_fab2_lib.baseboard_fab2(sch_1):page155_i74@mstr_discrete.res~
(chips)',
 P_PATH='@baseboard_fab2_lib.baseboard_fab2(sch_1):page155_i74@mstr_discrete.res~
(chips)',
 PATH='I74',
 DRAWING='@BASEBOARD_FAB2_LIB.BASEBOARD_FAB2(SCH_1):PAGE155',
 WATTAGE='1/16W',
 TOLERANCE='1%',
 MATERIAL='CHIP',
 BOM_COST='DEBUG',
 PHYS_PAGE='155',
 XY='(-6900,3900)',
 ROT='0',
 VER='1',
 VALUE='10.0',
 PACK_TYPE='0402',
 PART_NUMBER='G21796-066',
 LOCATION='R1L18',
 ROOM='BMC_DEBUG_HEADER',
 CDS_LIB='mstr_discrete',
 CDS_PART_NAME='RES_0402-10.0,1%,1/16W,CHIP,G2A',
 PRIM_FILE='./archive_libs/mstr_discrete/res/chips/chips.prt';

PART_NAME
 R1L19 'RES_0402-4.75K,1%,1/16W,CHIP,GA':
 ROOM='M-SATA';

SECTION_NUMBER 1
 '@BASEBOARD_FAB2_LIB.BASEBOARD_FAB2(SCH_1):PAGE175_I99@MSTR_DISCRETE.RES(CHIPS)':
 C_PATH='@baseboard_fab2_lib.baseboard_fab2(sch_1):page175_i99@mstr_discrete.res~
(chips)',
 P_PATH='@baseboard_fab2_lib.baseboard_fab2(sch_1):page175_i99@mstr_discrete.res~
(chips)',
 PATH='I99',
 DRAWING='@BASEBOARD_FAB2_LIB.BASEBOARD_FAB2(SCH_1):PAGE175',
 WATTAGE='1/16W',
 TOLERANCE='1%',
 SEC_TYPE='0402',
 MATERIAL='CHIP',
 BOM_COST='M-SATA',
 PHYS_PAGE='175',
 XY='(-5875,3075)',
 ROT='0',
 VER='2',
 VALUE='4.75K',
 PACK_TYPE='0402',
 PART_NUMBER='G21796-072',
 LOCATION='R1L19',
 ROOM='M-SATA',
 SEC='1',
 CDS_LIB='mstr_discrete',
 CDS_PART_NAME='RES_0402-4.75K,1%,1/16W,CHIP,GA',
 PRIM_FILE='./archive_libs/mstr_discrete/res/chips/chips.prt';

PART_NAME
 R1L20 'RES_0402-10.0,1%,1/16W,CHIP,G2A':
 ROOM='BMC_DEBUG_HEADER';

SECTION_NUMBER 1
 '@BASEBOARD_FAB2_LIB.BASEBOARD_FAB2(SCH_1):PAGE155_I73@MSTR_DISCRETE.RES(CHIPS)':
 C_PATH='@baseboard_fab2_lib.baseboard_fab2(sch_1):page155_i73@mstr_discrete.res~
(chips)',
 P_PATH='@baseboard_fab2_lib.baseboard_fab2(sch_1):page155_i73@mstr_discrete.res~
(chips)',
 PATH='I73',
 DRAWING='@BASEBOARD_FAB2_LIB.BASEBOARD_FAB2(SCH_1):PAGE155',
 WATTAGE='1/16W',
 TOLERANCE='1%',
 MATERIAL='CHIP',
 BOM_COST='DEBUG',
 PHYS_PAGE='155',
 XY='(-6900,4050)',
 ROT='0',
 VER='1',
 VALUE='10.0',
 PACK_TYPE='0402',
 PART_NUMBER='G21796-066',
 LOCATION='R1L20',
 ROOM='BMC_DEBUG_HEADER',
 CDS_LIB='mstr_discrete',
 CDS_PART_NAME='RES_0402-10.0,1%,1/16W,CHIP,G2A',
 PRIM_FILE='./archive_libs/mstr_discrete/res/chips/chips.prt';

PART_NAME
 R1L21 'RES_0402-64.9,1.0%,1/16W,CHIP,A':
 ROOM='MIO_CHASSIS';

SECTION_NUMBER 1
 '@BASEBOARD_FAB2_LIB.BASEBOARD_FAB2(SCH_1):PAGE177_I43@MSTR_DISCRETE.RES(CHIPS)':
 C_PATH='@baseboard_fab2_lib.baseboard_fab2(sch_1):page177_i43@mstr_discrete.res~
(chips)',
 P_PATH='@baseboard_fab2_lib.baseboard_fab2(sch_1):page177_i43@mstr_discrete.res~
(chips)',
 PATH='I43',
 DRAWING='@BASEBOARD_FAB2_LIB.BASEBOARD_FAB2(SCH_1):PAGE177',
 CONFIG='64.12005.6DL',
 WATTAGE='1/16W',
 TOLERANCE='1.0%',
 SEC_TYPE='0402',
 MATERIAL='CHIP',
 PHYS_PAGE='177',
 XY='(-4675,6600)',
 ROT='0',
 VER='2',
 VALUE='64.9',
 PACK_TYPE='0402',
 PART_NUMBER='G21796-298',
 LOCATION='R1L21',
 ROOM='MIO_CHASSIS',
 SEC='1',
 CDS_LIB='mstr_discrete',
 CDS_PART_NAME='RES_0402-64.9,1.0%,1/16W,CHIP,A',
 PRIM_FILE='./archive_libs/mstr_discrete/res/chips/chips.prt';

PART_NAME
 R1L22 'RES_0402-200.0,1%,1/16W,CHIP,GA':
 ROOM='MIO_CHASSIS';

SECTION_NUMBER 1
 '@BASEBOARD_FAB2_LIB.BASEBOARD_FAB2(SCH_1):PAGE175_I22@MSTR_DISCRETE.RES(CHIPS)':
 C_PATH='@baseboard_fab2_lib.baseboard_fab2(sch_1):page175_i22@mstr_discrete.res~
(chips)',
 P_PATH='@baseboard_fab2_lib.baseboard_fab2(sch_1):page175_i22@mstr_discrete.res~
(chips)',
 PATH='I22',
 DRAWING='@BASEBOARD_FAB2_LIB.BASEBOARD_FAB2(SCH_1):PAGE175',
 WATTAGE='1/16W',
 TOLERANCE='1%',
 SEC_TYPE='0402',
 MATERIAL='CHIP',
 BOM_COST='MIO_CHASSIS',
 PHYS_PAGE='175',
 XY='(-5600,2775)',
 ROT='0',
 VER='1',
 VALUE='200.0',
 PACK_TYPE='0402',
 PART_NUMBER='G21796-004',
 LOCATION='R1L22',
 ROOM='MIO_CHASSIS',
 SEC='1',
 CDS_LIB='mstr_discrete',
 CDS_PART_NAME='RES_0402-200.0,1%,1/16W,CHIP,GA',
 PRIM_FILE='./archive_libs/mstr_discrete/res/chips/chips.prt';

PART_NAME
 R1L23 'RES_0402-1.00K,1%,1/16W,CHIP,GA':
 ROOM='DEBUG';

SECTION_NUMBER 1
 '@BASEBOARD_FAB2_LIB.BASEBOARD_FAB2(SCH_1):PAGE111_I13@MSTR_DISCRETE.RES(CHIPS)':
 C_PATH='@baseboard_fab2_lib.baseboard_fab2(sch_1):page111_i13@mstr_discrete.res~
(chips)',
 P_PATH='@baseboard_fab2_lib.baseboard_fab2(sch_1):page111_i13@mstr_discrete.res~
(chips)',
 PATH='I13',
 DRAWING='@BASEBOARD_FAB2_LIB.BASEBOARD_FAB2(SCH_1):PAGE111',
 WATTAGE='1/16W',
 TOLERANCE='1%',
 SEC_TYPE='0402',
 MATERIAL='CHIP',
 BOM_COST='DEBUG',
 PHYS_PAGE='111',
 XY='(2725,1150)',
 ROT='0',
 VER='1',
 VALUE='1.00K',
 PACK_TYPE='0402',
 PART_NUMBER='G21796-026',
 LOCATION='R1L23',
 ROOM='DEBUG',
 SEC='1',
 CDS_LIB='mstr_discrete',
 CDS_PART_NAME='RES_0402-1.00K,1%,1/16W,CHIP,GA',
 PRIM_FILE='./archive_libs/mstr_discrete/res/chips/chips.prt';

PART_NAME
 R1L24 'RES_0402-10.0,1%,1/16W,CHIP,G2A':
 ROOM='BMC_DEBUG_HEADER';

SECTION_NUMBER 1
 '@BASEBOARD_FAB2_LIB.BASEBOARD_FAB2(SCH_1):PAGE155_I68@MSTR_DISCRETE.RES(CHIPS)':
 C_PATH='@baseboard_fab2_lib.baseboard_fab2(sch_1):page155_i68@mstr_discrete.res~
(chips)',
 P_PATH='@baseboard_fab2_lib.baseboard_fab2(sch_1):page155_i68@mstr_discrete.res~
(chips)',
 PATH='I68',
 DRAWING='@BASEBOARD_FAB2_LIB.BASEBOARD_FAB2(SCH_1):PAGE155',
 WATTAGE='1/16W',
 TOLERANCE='1%',
 MATERIAL='CHIP',
 BOM_COST='DEBUG',
 PHYS_PAGE='155',
 XY='(-6900,4200)',
 ROT='0',
 VER='1',
 VALUE='10.0',
 PACK_TYPE='0402',
 PART_NUMBER='G21796-066',
 LOCATION='R1L24',
 ROOM='BMC_DEBUG_HEADER',
 CDS_LIB='mstr_discrete',
 CDS_PART_NAME='RES_0402-10.0,1%,1/16W,CHIP,G2A',
 PRIM_FILE='./archive_libs/mstr_discrete/res/chips/chips.prt';

PART_NAME
 R1L25 'RES_0402-10.0,1%,1/16W,CHIP,G2A':
 ROOM='BMC_DEBUG_HEADER';

SECTION_NUMBER 1
 '@BASEBOARD_FAB2_LIB.BASEBOARD_FAB2(SCH_1):PAGE155_I67@MSTR_DISCRETE.RES(CHIPS)':
 C_PATH='@baseboard_fab2_lib.baseboard_fab2(sch_1):page155_i67@mstr_discrete.res~
(chips)',
 P_PATH='@baseboard_fab2_lib.baseboard_fab2(sch_1):page155_i67@mstr_discrete.res~
(chips)',
 PATH='I67',
 DRAWING='@BASEBOARD_FAB2_LIB.BASEBOARD_FAB2(SCH_1):PAGE155',
 WATTAGE='1/16W',
 TOLERANCE='1%',
 MATERIAL='CHIP',
 BOM_COST='DEBUG',
 PHYS_PAGE='155',
 XY='(-6900,4350)',
 ROT='0',
 VER='1',
 VALUE='10.0',
 PACK_TYPE='0402',
 PART_NUMBER='G21796-066',
 LOCATION='R1L25',
 ROOM='BMC_DEBUG_HEADER',
 CDS_LIB='mstr_discrete',
 CDS_PART_NAME='RES_0402-10.0,1%,1/16W,CHIP,G2A',
 PRIM_FILE='./archive_libs/mstr_discrete/res/chips/chips.prt';

PART_NAME
 R1L26 'RES_0402-33.2,1%,1/16W,CHIP,G2A':
 ROOM='MIO_CHASSIS';

SECTION_NUMBER 1
 '@BASEBOARD_FAB2_LIB.BASEBOARD_FAB2(SCH_1):PAGE175_I13@MSTR_DISCRETE.RES(CHIPS)':
 C_PATH='@baseboard_fab2_lib.baseboard_fab2(sch_1):page175_i13@mstr_discrete.res~
(chips)',
 P_PATH='@baseboard_fab2_lib.baseboard_fab2(sch_1):page175_i13@mstr_discrete.res~
(chips)',
 PATH='I13',
 DRAWING='@BASEBOARD_FAB2_LIB.BASEBOARD_FAB2(SCH_1):PAGE175',
 WATTAGE='1/16W',
 TOLERANCE='1%',
 SEC_TYPE='0402',
 MATERIAL='CHIP',
 BOM_COST='MIO_CHASSIS',
 PHYS_PAGE='175',
 XY='(-2275,4075)',
 ROT='0',
 VER='1',
 VALUE='33.2',
 PACK_TYPE='0402',
 PART_NUMBER='G21796-074',
 LOCATION='R1L26',
 ROOM='MIO_CHASSIS',
 SEC='1',
 CDS_LIB='mstr_discrete',
 CDS_PART_NAME='RES_0402-33.2,1%,1/16W,CHIP,G2A',
 PRIM_FILE='./archive_libs/mstr_discrete/res/chips/chips.prt';

PART_NAME
 R1L27 'RES_0402-4.75K,1%,1/16W,CHIP,GA':
 ROOM='MIO_CHASSIS';

SECTION_NUMBER 1
 '@BASEBOARD_FAB2_LIB.BASEBOARD_FAB2(SCH_1):PAGE175_I5@MSTR_DISCRETE.RES(CHIPS)':
 C_PATH='@baseboard_fab2_lib.baseboard_fab2(sch_1):page175_i5@mstr_discrete.res(~
chips)',
 P_PATH='@baseboard_fab2_lib.baseboard_fab2(sch_1):page175_i5@mstr_discrete.res(~
chips)',
 PATH='I5',
 DRAWING='@BASEBOARD_FAB2_LIB.BASEBOARD_FAB2(SCH_1):PAGE175',
 WATTAGE='1/16W',
 TOLERANCE='1%',
 SEC_TYPE='0402',
 MATERIAL='CHIP',
 BOM_COST='MIO_CHASSIS',
 PHYS_PAGE='175',
 XY='(-5925,4475)',
 ROT='0',
 VER='2',
 VALUE='4.75K',
 PACK_TYPE='0402',
 PART_NUMBER='G21796-072',
 LOCATION='R1L27',
 ROOM='MIO_CHASSIS',
 SEC='1',
 CDS_LIB='mstr_discrete',
 CDS_PART_NAME='RES_0402-4.75K,1%,1/16W,CHIP,GA',
 PRIM_FILE='./archive_libs/mstr_discrete/res/chips/chips.prt';

PART_NAME
 R1L28 'RES_0402-4.75K,1%,1/16W,EMPTY,A':
 ROOM='MIO_CHASSIS';

SECTION_NUMBER 1
 '@BASEBOARD_FAB2_LIB.BASEBOARD_FAB2(SCH_1):PAGE111_I97@MSTR_DISCRETE.RES(CHIPS)':
 C_PATH='@baseboard_fab2_lib.baseboard_fab2(sch_1):page111_i97@mstr_discrete.res~
(chips)',
 P_PATH='@baseboard_fab2_lib.baseboard_fab2(sch_1):page111_i97@mstr_discrete.res~
(chips)',
 PATH='I97',
 DRAWING='@BASEBOARD_FAB2_LIB.BASEBOARD_FAB2(SCH_1):PAGE111',
 WATTAGE='1/16W',
 TOLERANCE='1%',
 SEC_TYPE='0402',
 MATERIAL='EMPTY',
 BOM_COST='MIO_CHASSIS',
 PHYS_PAGE='111',
 XY='(2175,2800)',
 ROT='0',
 VER='2',
 VALUE='4.75K',
 PACK_TYPE='0402',
 PART_NUMBER='G21796-072',
 LOCATION='R1L28',
 ROOM='MIO_CHASSIS',
 SEC='1',
 CDS_LIB='mstr_discrete',
 CDS_PART_NAME='RES_0402-4.75K,1%,1/16W,EMPTY,A',
 PRIM_FILE='./archive_libs/mstr_discrete/res/chips/chips.prt';

PART_NAME
 R1L29 'RES_0402-33.2,1%,1/16W,CHIP,G2A':
 ROOM='M-SATA';

SECTION_NUMBER 1
 '@BASEBOARD_FAB2_LIB.BASEBOARD_FAB2(SCH_1):PAGE111_I68@MSTR_DISCRETE.RES(CHIPS)':
 C_PATH='@baseboard_fab2_lib.baseboard_fab2(sch_1):page111_i68@mstr_discrete.res~
(chips)',
 P_PATH='@baseboard_fab2_lib.baseboard_fab2(sch_1):page111_i68@mstr_discrete.res~
(chips)',
 PATH='I68',
 DRAWING='@BASEBOARD_FAB2_LIB.BASEBOARD_FAB2(SCH_1):PAGE111',
 WATTAGE='1/16W',
 TOLERANCE='1%',
 SEC_TYPE='0402',
 MATERIAL='CHIP',
 PHYS_PAGE='111',
 XY='(2950,2600)',
 ROT='0',
 VER='1',
 VALUE='33.2',
 PACK_TYPE='0402',
 PART_NUMBER='G21796-074',
 LOCATION='R1L29',
 ROOM='M-SATA',
 SEC='1',
 CDS_LIB='mstr_discrete',
 CDS_PART_NAME='RES_0402-33.2,1%,1/16W,CHIP,G2A',
 PRIM_FILE='./archive_libs/mstr_discrete/res/chips/chips.prt';

PART_NAME
 R1L30 'RES_0402-10.0,1%,1/16W,CHIP,G2A':
 ROOM='BMC_DEBUG_HEADER';

SECTION_NUMBER 1
 '@BASEBOARD_FAB2_LIB.BASEBOARD_FAB2(SCH_1):PAGE155_I66@MSTR_DISCRETE.RES(CHIPS)':
 C_PATH='@baseboard_fab2_lib.baseboard_fab2(sch_1):page155_i66@mstr_discrete.res~
(chips)',
 P_PATH='@baseboard_fab2_lib.baseboard_fab2(sch_1):page155_i66@mstr_discrete.res~
(chips)',
 PATH='I66',
 DRAWING='@BASEBOARD_FAB2_LIB.BASEBOARD_FAB2(SCH_1):PAGE155',
 WATTAGE='1/16W',
 TOLERANCE='1%',
 MATERIAL='CHIP',
 BOM_COST='DEBUG',
 PHYS_PAGE='155',
 XY='(-6900,4500)',
 ROT='0',
 VER='1',
 VALUE='10.0',
 PACK_TYPE='0402',
 PART_NUMBER='G21796-066',
 LOCATION='R1L30',
 ROOM='BMC_DEBUG_HEADER',
 CDS_LIB='mstr_discrete',
 CDS_PART_NAME='RES_0402-10.0,1%,1/16W,CHIP,G2A',
 PRIM_FILE='./archive_libs/mstr_discrete/res/chips/chips.prt';

PART_NAME
 R1L31 'RES_0402-200.0,1%,1/16W,CHIP,GA':
 ROOM='MIO_CHASSIS';

SECTION_NUMBER 1
 '@BASEBOARD_FAB2_LIB.BASEBOARD_FAB2(SCH_1):PAGE175_I4@MSTR_DISCRETE.RES(CHIPS)':
 C_PATH='@baseboard_fab2_lib.baseboard_fab2(sch_1):page175_i4@mstr_discrete.res(~
chips)',
 P_PATH='@baseboard_fab2_lib.baseboard_fab2(sch_1):page175_i4@mstr_discrete.res(~
chips)',
 PATH='I4',
 DRAWING='@BASEBOARD_FAB2_LIB.BASEBOARD_FAB2(SCH_1):PAGE175',
 WATTAGE='1/16W',
 TOLERANCE='1%',
 SEC_TYPE='0402',
 MATERIAL='CHIP',
 BOM_COST='MIO_CHASSIS',
 PHYS_PAGE='175',
 XY='(-5650,4175)',
 ROT='0',
 VER='1',
 VALUE='200.0',
 PACK_TYPE='0402',
 PART_NUMBER='G21796-004',
 LOCATION='R1L31',
 ROOM='MIO_CHASSIS',
 SEC='1',
 CDS_LIB='mstr_discrete',
 CDS_PART_NAME='RES_0402-200.0,1%,1/16W,CHIP,GA',
 PRIM_FILE='./archive_libs/mstr_discrete/res/chips/chips.prt';

PART_NAME
 R1L32 'RES_0402-10.0,1%,1/16W,CHIP,G2A':
 ROOM='BMC_DEBUG_HEADER';

SECTION_NUMBER 1
 '@BASEBOARD_FAB2_LIB.BASEBOARD_FAB2(SCH_1):PAGE155_I65@MSTR_DISCRETE.RES(CHIPS)':
 C_PATH='@baseboard_fab2_lib.baseboard_fab2(sch_1):page155_i65@mstr_discrete.res~
(chips)',
 P_PATH='@baseboard_fab2_lib.baseboard_fab2(sch_1):page155_i65@mstr_discrete.res~
(chips)',
 PATH='I65',
 DRAWING='@BASEBOARD_FAB2_LIB.BASEBOARD_FAB2(SCH_1):PAGE155',
 WATTAGE='1/16W',
 TOLERANCE='1%',
 MATERIAL='CHIP',
 BOM_COST='DEBUG',
 PHYS_PAGE='155',
 XY='(-6900,4650)',
 ROT='0',
 VER='1',
 VALUE='10.0',
 PACK_TYPE='0402',
 PART_NUMBER='G21796-066',
 LOCATION='R1L32',
 ROOM='BMC_DEBUG_HEADER',
 CDS_LIB='mstr_discrete',
 CDS_PART_NAME='RES_0402-10.0,1%,1/16W,CHIP,G2A',
 PRIM_FILE='./archive_libs/mstr_discrete/res/chips/chips.prt';

PART_NAME
 R1L33 'RES_0402-221,1.0%,1/16W,CHIP,GA':
 ROOM='MIO_CHASSIS';

SECTION_NUMBER 1
 '@BASEBOARD_FAB2_LIB.BASEBOARD_FAB2(SCH_1):PAGE175_I45@MSTR_DISCRETE.RES(CHIPS)':
 C_PATH='@baseboard_fab2_lib.baseboard_fab2(sch_1):page175_i45@mstr_discrete.res~
(chips)',
 P_PATH='@baseboard_fab2_lib.baseboard_fab2(sch_1):page175_i45@mstr_discrete.res~
(chips)',
 PATH='I45',
 DRAWING='@BASEBOARD_FAB2_LIB.BASEBOARD_FAB2(SCH_1):PAGE175',
 WATTAGE='1/16W',
 TOLERANCE='1.0%',
 SEC_TYPE='0402',
 MATERIAL='CHIP',
 BOM_COST='MIO_CHASSIS',
 PHYS_PAGE='175',
 XY='(-4000,1550)',
 ROT='0',
 VER='1',
 VALUE='221',
 PACK_TYPE='0402',
 PART_NUMBER='G21796-271',
 LOCATION='R1L33',
 ROOM='MIO_CHASSIS',
 SEC='1',
 CDS_LIB='mstr_discrete',
 CDS_PART_NAME='RES_0402-221,1.0%,1/16W,CHIP,GA',
 PRIM_FILE='./archive_libs/mstr_discrete/res/chips/chips.prt';

PART_NAME
 R1L36 'RES_0402-1.00K,1%,1/16W,CHIP,GA':
 ROOM='UART_MUX';

SECTION_NUMBER 1
 '@BASEBOARD_FAB2_LIB.BASEBOARD_FAB2(SCH_1):PAGE168_I11@MSTR_DISCRETE.RES(CHIPS)':
 C_PATH='@baseboard_fab2_lib.baseboard_fab2(sch_1):page168_i11@mstr_discrete.res~
(chips)',
 P_PATH='@baseboard_fab2_lib.baseboard_fab2(sch_1):page168_i11@mstr_discrete.res~
(chips)',
 PATH='I11',
 DRAWING='@BASEBOARD_FAB2_LIB.BASEBOARD_FAB2(SCH_1):PAGE168',
 WATTAGE='1/16W',
 TOLERANCE='1%',
 SEC_TYPE='0402',
 MATERIAL='CHIP',
 BOM_COST='DEBUG',
 PHYS_PAGE='168',
 XY='(-3400,3050)',
 ROT='0',
 VER='2',
 VALUE='1.00K',
 PACK_TYPE='0402',
 PART_NUMBER='G21796-026',
 LOCATION='R1L36',
 ROOM='UART_MUX',
 SEC='1',
 CDS_LIB='mstr_discrete',
 CDS_PART_NAME='RES_0402-1.00K,1%,1/16W,CHIP,GA',
 PRIM_FILE='./archive_libs/mstr_discrete/res/chips/chips.prt';

PART_NAME
 R1L37 'RES_0402-301.0,1%,1/16W,CHIP,GA':
 ROOM='MIO_CHASSIS',
 SIGNAL_MODEL='DEFAULT_RESISTOR_332OHM_2_1';

SECTION_NUMBER 1
 '@BASEBOARD_FAB2_LIB.BASEBOARD_FAB2(SCH_1):PAGE177_I33@MSTR_DISCRETE.RES(CHIPS)':
 C_PATH='@baseboard_fab2_lib.baseboard_fab2(sch_1):page177_i33@mstr_discrete.res~
(chips)',
 P_PATH='@baseboard_fab2_lib.baseboard_fab2(sch_1):page177_i33@mstr_discrete.res~
(chips)',
 PATH='I33',
 DRAWING='@BASEBOARD_FAB2_LIB.BASEBOARD_FAB2(SCH_1):PAGE177',
 WATTAGE='1/16W',
 TOLERANCE='1%',
 MATERIAL='CHIP',
 PHYS_PAGE='177',
 XY='(-3825,8850)',
 ROT='0',
 VER='2',
 VALUE='301.0',
 PACK_TYPE='0402',
 PART_NUMBER='G21796-076',
 LOCATION='R1L37',
 SIGNAL_MODEL='DEFAULT_RESISTOR_332OHM_2_1',
 ROOM='MIO_CHASSIS',
 CDS_LIB='mstr_discrete',
 CDS_PART_NAME='RES_0402-301.0,1%,1/16W,CHIP,GA',
 PRIM_FILE='./archive_libs/mstr_discrete/res/chips/chips.prt';

PART_NAME
 R1L38 'RES_0402-1.00K,1%,1/16W,CHIP,GA':
 ROOM='UART_MUX';

SECTION_NUMBER 1
 '@BASEBOARD_FAB2_LIB.BASEBOARD_FAB2(SCH_1):PAGE168_I22@MSTR_DISCRETE.RES(CHIPS)':
 C_PATH='@baseboard_fab2_lib.baseboard_fab2(sch_1):page168_i22@mstr_discrete.res~
(chips)',
 P_PATH='@baseboard_fab2_lib.baseboard_fab2(sch_1):page168_i22@mstr_discrete.res~
(chips)',
 PATH='I22',
 DRAWING='@BASEBOARD_FAB2_LIB.BASEBOARD_FAB2(SCH_1):PAGE168',
 WATTAGE='1/16W',
 TOLERANCE='1%',
 SEC_TYPE='0402',
 MATERIAL='CHIP',
 BOM_COST='DEBUG',
 PHYS_PAGE='168',
 XY='(-2425,3425)',
 ROT='0',
 VER='2',
 VALUE='1.00K',
 PACK_TYPE='0402',
 PART_NUMBER='G21796-026',
 LOCATION='R1L38',
 ROOM='UART_MUX',
 SEC='1',
 CDS_LIB='mstr_discrete',
 CDS_PART_NAME='RES_0402-1.00K,1%,1/16W,CHIP,GA',
 PRIM_FILE='./archive_libs/mstr_discrete/res/chips/chips.prt';

PART_NAME
 R1L39 'RES_0402-100.0,1%,1/16W,CHIP,GA':
 ROOM='DEBUG';

SECTION_NUMBER 1
 '@BASEBOARD_FAB2_LIB.BASEBOARD_FAB2(SCH_1):PAGE112_I76@MSTR_DISCRETE.RES(CHIPS)':
 C_PATH='@baseboard_fab2_lib.baseboard_fab2(sch_1):page112_i76@mstr_discrete.res~
(chips)',
 P_PATH='@baseboard_fab2_lib.baseboard_fab2(sch_1):page112_i76@mstr_discrete.res~
(chips)',
 PATH='I76',
 DRAWING='@BASEBOARD_FAB2_LIB.BASEBOARD_FAB2(SCH_1):PAGE112',
 WATTAGE='1/16W',
 TOLERANCE='1%',
 SEC_TYPE='0402',
 MATERIAL='CHIP',
 PHYS_PAGE='112',
 XY='(-1200,4425)',
 ROT='0',
 VER='2',
 VALUE='100.0',
 PACK_TYPE='0402',
 PART_NUMBER='G21796-017',
 LOCATION='R1L39',
 ROOM='DEBUG',
 SEC='1',
 CDS_LIB='mstr_discrete',
 CDS_PART_NAME='RES_0402-100.0,1%,1/16W,CHIP,GA',
 PRIM_FILE='./archive_libs/mstr_discrete/res/chips/chips.prt';

PART_NAME
 R1L41 'RES_0402-100.0,1%,1/16W,CHIP,GA':
 ROOM='DEBUG';

SECTION_NUMBER 1
 '@BASEBOARD_FAB2_LIB.BASEBOARD_FAB2(SCH_1):PAGE112_I77@MSTR_DISCRETE.RES(CHIPS)':
 C_PATH='@baseboard_fab2_lib.baseboard_fab2(sch_1):page112_i77@mstr_discrete.res~
(chips)',
 P_PATH='@baseboard_fab2_lib.baseboard_fab2(sch_1):page112_i77@mstr_discrete.res~
(chips)',
 PATH='I77',
 DRAWING='@BASEBOARD_FAB2_LIB.BASEBOARD_FAB2(SCH_1):PAGE112',
 WATTAGE='1/16W',
 TOLERANCE='1%',
 SEC_TYPE='0402',
 MATERIAL='CHIP',
 PHYS_PAGE='112',
 XY='(-1575,4425)',
 ROT='0',
 VER='2',
 VALUE='100.0',
 PACK_TYPE='0402',
 PART_NUMBER='G21796-017',
 LOCATION='R1L41',
 ROOM='DEBUG',
 SEC='1',
 CDS_LIB='mstr_discrete',
 CDS_PART_NAME='RES_0402-100.0,1%,1/16W,CHIP,GA',
 PRIM_FILE='./archive_libs/mstr_discrete/res/chips/chips.prt';

PART_NAME
 R1L43 'RES_0402-330,5%,1/16W,CHIP,G21A':
 ROOM='UART_MUX';

SECTION_NUMBER 1
 '@BASEBOARD_FAB2_LIB.BASEBOARD_FAB2(SCH_1):PAGE158_I131@MSTR_DISCRETE.RES(CHIPS)':
 C_PATH='@baseboard_fab2_lib.baseboard_fab2(sch_1):page158_i131@mstr_discrete.re~
s(chips)',
 P_PATH='@baseboard_fab2_lib.baseboard_fab2(sch_1):page158_i131@mstr_discrete.re~
s(chips)',
 PATH='I131',
 DRAWING='@BASEBOARD_FAB2_LIB.BASEBOARD_FAB2(SCH_1):PAGE158',
 WATTAGE='1/16W',
 TOLERANCE='5%',
 SEC_TYPE='0402',
 MATERIAL='CHIP',
 BOM_COST='DEBUG',
 PHYS_PAGE='158',
 XY='(-4875,3200)',
 ROT='0',
 VER='1',
 VALUE='330',
 PACK_TYPE='0402',
 PART_NUMBER='G21497-028',
 LOCATION='R1L43',
 ROOM='UART_MUX',
 SEC='1',
 CDS_LIB='mstr_discrete',
 CDS_PART_NAME='RES_0402-330,5%,1/16W,CHIP,G21A',
 PRIM_FILE='./archive_libs/mstr_discrete/res/chips/chips.prt';

PART_NAME
 R1L44 'RES_0402-330,5%,1/16W,CHIP,G21A':
 ROOM='UART_MUX';

SECTION_NUMBER 1
 '@BASEBOARD_FAB2_LIB.BASEBOARD_FAB2(SCH_1):PAGE158_I136@MSTR_DISCRETE.RES(CHIPS)':
 C_PATH='@baseboard_fab2_lib.baseboard_fab2(sch_1):page158_i136@mstr_discrete.re~
s(chips)',
 P_PATH='@baseboard_fab2_lib.baseboard_fab2(sch_1):page158_i136@mstr_discrete.re~
s(chips)',
 PATH='I136',
 DRAWING='@BASEBOARD_FAB2_LIB.BASEBOARD_FAB2(SCH_1):PAGE158',
 WATTAGE='1/16W',
 TOLERANCE='5%',
 SEC_TYPE='0402',
 MATERIAL='CHIP',
 BOM_COST='DEBUG',
 PHYS_PAGE='158',
 XY='(-4875,3600)',
 ROT='0',
 VER='1',
 VALUE='330',
 PACK_TYPE='0402',
 PART_NUMBER='G21497-028',
 LOCATION='R1L44',
 ROOM='UART_MUX',
 SEC='1',
 CDS_LIB='mstr_discrete',
 CDS_PART_NAME='RES_0402-330,5%,1/16W,CHIP,G21A',
 PRIM_FILE='./archive_libs/mstr_discrete/res/chips/chips.prt';

PART_NAME
 R1M3 'RES_0402-100.0,1%,1/16W,CHIP,GA':
 ROOM='DEBUG';

SECTION_NUMBER 1
 '@BASEBOARD_FAB2_LIB.BASEBOARD_FAB2(SCH_1):PAGE112_I51@MSTR_DISCRETE.RES(CHIPS)':
 C_PATH='@baseboard_fab2_lib.baseboard_fab2(sch_1):page112_i51@mstr_discrete.res~
(chips)',
 P_PATH='@baseboard_fab2_lib.baseboard_fab2(sch_1):page112_i51@mstr_discrete.res~
(chips)',
 PATH='I51',
 DRAWING='@BASEBOARD_FAB2_LIB.BASEBOARD_FAB2(SCH_1):PAGE112',
 WATTAGE='1/16W',
 TOLERANCE='1%',
 SEC_TYPE='0402',
 MATERIAL='CHIP',
 PHYS_PAGE='112',
 XY='(1950,2400)',
 ROT='0',
 VER='2',
 VALUE='100.0',
 PACK_TYPE='0402',
 PART_NUMBER='G21796-017',
 LOCATION='R1M3',
 ROOM='DEBUG',
 SEC='1',
 CDS_LIB='mstr_discrete',
 CDS_PART_NAME='RES_0402-100.0,1%,1/16W,CHIP,GA',
 PRIM_FILE='./archive_libs/mstr_discrete/res/chips/chips.prt';

PART_NAME
 R1M4 'RES_0402-100.0,1%,1/16W,CHIP,GA':
 ROOM='DEBUG';

SECTION_NUMBER 1
 '@BASEBOARD_FAB2_LIB.BASEBOARD_FAB2(SCH_1):PAGE112_I54@MSTR_DISCRETE.RES(CHIPS)':
 C_PATH='@baseboard_fab2_lib.baseboard_fab2(sch_1):page112_i54@mstr_discrete.res~
(chips)',
 P_PATH='@baseboard_fab2_lib.baseboard_fab2(sch_1):page112_i54@mstr_discrete.res~
(chips)',
 PATH='I54',
 DRAWING='@BASEBOARD_FAB2_LIB.BASEBOARD_FAB2(SCH_1):PAGE112',
 WATTAGE='1/16W',
 TOLERANCE='1%',
 SEC_TYPE='0402',
 MATERIAL='CHIP',
 PHYS_PAGE='112',
 XY='(1600,2400)',
 ROT='0',
 VER='2',
 VALUE='100.0',
 PACK_TYPE='0402',
 PART_NUMBER='G21796-017',
 LOCATION='R1M4',
 ROOM='DEBUG',
 SEC='1',
 CDS_LIB='mstr_discrete',
 CDS_PART_NAME='RES_0402-100.0,1%,1/16W,CHIP,GA',
 PRIM_FILE='./archive_libs/mstr_discrete/res/chips/chips.prt';

PART_NAME
 R1M5 'RES_0402-0.0,5%,1/16W,CHIP,G21A':
 ROOM='USB_REAR';

SECTION_NUMBER 1
 '@BASEBOARD_FAB2_LIB.BASEBOARD_FAB2(SCH_1):PAGE176_I16@MSTR_DISCRETE.RES(CHIPS)':
 C_PATH='@baseboard_fab2_lib.baseboard_fab2(sch_1):page176_i16@mstr_discrete.res~
(chips)',
 P_PATH='@baseboard_fab2_lib.baseboard_fab2(sch_1):page176_i16@mstr_discrete.res~
(chips)',
 PATH='I16',
 DRAWING='@BASEBOARD_FAB2_LIB.BASEBOARD_FAB2(SCH_1):PAGE176',
 POP='NOPOP',
 WATTAGE='1/16W',
 TOLERANCE='5%',
 SEC_TYPE='0402',
 MATERIAL='CHIP',
 BOM_COST='MIO_USB',
 PHYS_PAGE='176',
 XY='(-5650,4600)',
 ROT='0',
 VER='1',
 VALUE='0.0',
 PACK_TYPE='0402',
 PART_NUMBER='G21497-005',
 LOCATION='R1M5',
 ROOM='USB_REAR',
 SEC='1',
 CDS_LIB='mstr_discrete',
 CDS_PART_NAME='RES_0402-0.0,5%,1/16W,CHIP,G21A',
 PRIM_FILE='./archive_libs/mstr_discrete/res/chips/chips.prt';

PART_NAME
 R1M6 'RES_0402-0.0,5%,1/16W,CHIP,G21A':
 ROOM='USB';

SECTION_NUMBER 1
 '@BASEBOARD_FAB2_LIB.BASEBOARD_FAB2(SCH_1):PAGE176_I31@MSTR_DISCRETE.RES(CHIPS)':
 C_PATH='@baseboard_fab2_lib.baseboard_fab2(sch_1):page176_i31@mstr_discrete.res~
(chips)',
 P_PATH='@baseboard_fab2_lib.baseboard_fab2(sch_1):page176_i31@mstr_discrete.res~
(chips)',
 PATH='I31',
 DRAWING='@BASEBOARD_FAB2_LIB.BASEBOARD_FAB2(SCH_1):PAGE176',
 POP='NOPOP',
 WATTAGE='1/16W',
 TOLERANCE='5%',
 SEC_TYPE='0402',
 MATERIAL='CHIP',
 BOM_COST='MIO_USB',
 PHYS_PAGE='176',
 XY='(-5650,5550)',
 ROT='0',
 VER='1',
 VALUE='0.0',
 PACK_TYPE='0402',
 PART_NUMBER='G21497-005',
 LOCATION='R1M6',
 ROOM='USB',
 SEC='1',
 CDS_LIB='mstr_discrete',
 CDS_PART_NAME='RES_0402-0.0,5%,1/16W,CHIP,G21A',
 PRIM_FILE='./archive_libs/mstr_discrete/res/chips/chips.prt';

PART_NAME
 R1M8 'RES_0402-20.0,1%,1/16W,CHIP,G2A':
 ROOM='TEMP_SENSORS';

SECTION_NUMBER 1
 '@BASEBOARD_FAB2_LIB.BASEBOARD_FAB2(SCH_1):PAGE167_I74@MSTR_DISCRETE.RES(CHIPS)':
 C_PATH='@baseboard_fab2_lib.baseboard_fab2(sch_1):page167_i74@mstr_discrete.res~
(chips)',
 P_PATH='@baseboard_fab2_lib.baseboard_fab2(sch_1):page167_i74@mstr_discrete.res~
(chips)',
 PATH='I74',
 DRAWING='@BASEBOARD_FAB2_LIB.BASEBOARD_FAB2(SCH_1):PAGE167',
 WATTAGE='1/16W',
 TOLERANCE='1%',
 SEC_TYPE='0402',
 MATERIAL='CHIP',
 BOM_COST='SM_THERM',
 PHYS_PAGE='167',
 XY='(-2650,4450)',
 ROT='0',
 VER='1',
 VALUE='20.0',
 PACK_TYPE='0402',
 PART_NUMBER='G21796-173',
 LOCATION='R1M8',
 ROOM='TEMP_SENSORS',
 SEC='1',
 CDS_LIB='mstr_discrete',
 CDS_PART_NAME='RES_0402-20.0,1%,1/16W,CHIP,G2A',
 PRIM_FILE='./archive_libs/mstr_discrete/res/chips/chips.prt';

PART_NAME
 R1M9 'RES_0402-20.0,1%,1/16W,CHIP,G2A':
 ROOM='TEMP_SENSORS';

SECTION_NUMBER 1
 '@BASEBOARD_FAB2_LIB.BASEBOARD_FAB2(SCH_1):PAGE167_I8@MSTR_DISCRETE.RES(CHIPS)':
 C_PATH='@baseboard_fab2_lib.baseboard_fab2(sch_1):page167_i8@mstr_discrete.res(~
chips)',
 P_PATH='@baseboard_fab2_lib.baseboard_fab2(sch_1):page167_i8@mstr_discrete.res(~
chips)',
 PATH='I8',
 DRAWING='@BASEBOARD_FAB2_LIB.BASEBOARD_FAB2(SCH_1):PAGE167',
 WATTAGE='1/16W',
 TOLERANCE='1%',
 SEC_TYPE='0402',
 MATERIAL='CHIP',
 BOM_COST='SM_THERM',
 PHYS_PAGE='167',
 XY='(-2950,4500)',
 ROT='0',
 VER='1',
 VALUE='20.0',
 PACK_TYPE='0402',
 PART_NUMBER='G21796-173',
 LOCATION='R1M9',
 ROOM='TEMP_SENSORS',
 SEC='1',
 CDS_LIB='mstr_discrete',
 CDS_PART_NAME='RES_0402-20.0,1%,1/16W,CHIP,G2A',
 PRIM_FILE='./archive_libs/mstr_discrete/res/chips/chips.prt';

PART_NAME
 R1M10 'RES_0402-0.0,5%,1/16W,CHIP,G21A':
 ROOM='MIO_CHASSIS';

SECTION_NUMBER 1
 '@BASEBOARD_FAB2_LIB.BASEBOARD_FAB2(SCH_1):PAGE177_I6@MSTR_DISCRETE.RES(CHIPS)':
 C_PATH='@baseboard_fab2_lib.baseboard_fab2(sch_1):page177_i6@mstr_discrete.res(~
chips)',
 P_PATH='@baseboard_fab2_lib.baseboard_fab2(sch_1):page177_i6@mstr_discrete.res(~
chips)',
 PATH='I6',
 DRAWING='@BASEBOARD_FAB2_LIB.BASEBOARD_FAB2(SCH_1):PAGE177',
 WATTAGE='1/16W',
 TOLERANCE='5%',
 MATERIAL='CHIP',
 PHYS_PAGE='177',
 XY='(-8100,6325)',
 ROT='0',
 VER='1',
 VALUE='0.0',
 PACK_TYPE='0402',
 PART_NUMBER='G21497-005',
 LOCATION='R1M10',
 ROOM='MIO_CHASSIS',
 CDS_LIB='mstr_discrete',
 CDS_PART_NAME='RES_0402-0.0,5%,1/16W,CHIP,G21A',
 PRIM_FILE='./archive_libs/mstr_discrete/res/chips/chips.prt';

PART_NAME
 R1M11 'RES_0402-10.0K,1%,1/16W,CHIP,GA':
 ROOM='MIO_CHASSIS';

SECTION_NUMBER 1
 '@BASEBOARD_FAB2_LIB.BASEBOARD_FAB2(SCH_1):PAGE177_I9@MSTR_DISCRETE.RES(CHIPS)':
 C_PATH='@baseboard_fab2_lib.baseboard_fab2(sch_1):page177_i9@mstr_discrete.res(~
chips)',
 P_PATH='@baseboard_fab2_lib.baseboard_fab2(sch_1):page177_i9@mstr_discrete.res(~
chips)',
 PATH='I9',
 DRAWING='@BASEBOARD_FAB2_LIB.BASEBOARD_FAB2(SCH_1):PAGE177',
 WATTAGE='1/16W',
 TOLERANCE='1%',
 SEC_TYPE='0402',
 MATERIAL='CHIP',
 PHYS_PAGE='177',
 XY='(-7025,6550)',
 ROT='2',
 VER='2',
 VALUE='10.0K',
 PACK_TYPE='0402',
 PART_NUMBER='G21796-016',
 LOCATION='R1M11',
 ROOM='MIO_CHASSIS',
 SEC='1',
 CDS_LIB='mstr_discrete',
 CDS_PART_NAME='RES_0402-10.0K,1%,1/16W,CHIP,GA',
 PRIM_FILE='./archive_libs/mstr_discrete/res/chips/chips.prt';

PART_NAME
 R1M12 'RES_0402-10.0K,1%,1/16W,CHIP,GA':
 ROOM='MIO_CHASSIS';

SECTION_NUMBER 1
 '@BASEBOARD_FAB2_LIB.BASEBOARD_FAB2(SCH_1):PAGE177_I8@MSTR_DISCRETE.RES(CHIPS)':
 C_PATH='@baseboard_fab2_lib.baseboard_fab2(sch_1):page177_i8@mstr_discrete.res(~
chips)',
 P_PATH='@baseboard_fab2_lib.baseboard_fab2(sch_1):page177_i8@mstr_discrete.res(~
chips)',
 PATH='I8',
 DRAWING='@BASEBOARD_FAB2_LIB.BASEBOARD_FAB2(SCH_1):PAGE177',
 WATTAGE='1/16W',
 TOLERANCE='1%',
 SEC_TYPE='0402',
 MATERIAL='CHIP',
 PHYS_PAGE='177',
 XY='(-6975,6550)',
 ROT='0',
 VER='2',
 VALUE='10.0K',
 PACK_TYPE='0402',
 PART_NUMBER='G21796-016',
 LOCATION='R1M12',
 ROOM='MIO_CHASSIS',
 SEC='1',
 CDS_LIB='mstr_discrete',
 CDS_PART_NAME='RES_0402-10.0K,1%,1/16W,CHIP,GA',
 PRIM_FILE='./archive_libs/mstr_discrete/res/chips/chips.prt';

PART_NAME
 R1M13 'RES_0402-0.0,5%,1/16W,CHIP,G21A':
 ROOM='MIO_CHASSIS';

SECTION_NUMBER 1
 '@BASEBOARD_FAB2_LIB.BASEBOARD_FAB2(SCH_1):PAGE177_I3@MSTR_DISCRETE.RES(CHIPS)':
 C_PATH='@baseboard_fab2_lib.baseboard_fab2(sch_1):page177_i3@mstr_discrete.res(~
chips)',
 P_PATH='@baseboard_fab2_lib.baseboard_fab2(sch_1):page177_i3@mstr_discrete.res(~
chips)',
 PATH='I3',
 DRAWING='@BASEBOARD_FAB2_LIB.BASEBOARD_FAB2(SCH_1):PAGE177',
 WATTAGE='1/16W',
 TOLERANCE='5%',
 MATERIAL='CHIP',
 PHYS_PAGE='177',
 XY='(-7900,6225)',
 ROT='0',
 VER='1',
 VALUE='0.0',
 PACK_TYPE='0402',
 PART_NUMBER='G21497-005',
 LOCATION='R1M13',
 ROOM='MIO_CHASSIS',
 CDS_LIB='mstr_discrete',
 CDS_PART_NAME='RES_0402-0.0,5%,1/16W,CHIP,G21A',
 PRIM_FILE='./archive_libs/mstr_discrete/res/chips/chips.prt';

PART_NAME
 R1M14 'RES_0402-200.0,1%,1/16W,CHIP,GA':
 ROOM='IO_SLOT';

SECTION_NUMBER 1
 '@BASEBOARD_FAB2_LIB.BASEBOARD_FAB2(SCH_1):PAGE186_I220@MSTR_DISCRETE.RES(CHIPS)':
 C_PATH='@baseboard_fab2_lib.baseboard_fab2(sch_1):page186_i220@mstr_discrete.re~
s(chips)',
 P_PATH='@baseboard_fab2_lib.baseboard_fab2(sch_1):page186_i220@mstr_discrete.re~
s(chips)',
 PATH='I220',
 DRAWING='@BASEBOARD_FAB2_LIB.BASEBOARD_FAB2(SCH_1):PAGE186',
 WATTAGE='1/16W',
 TOLERANCE='1%',
 SEC_TYPE='0402',
 MATERIAL='CHIP',
 PHYS_PAGE='186',
 XY='(6000,3050)',
 ROT='0',
 VER='1',
 VALUE='200.0',
 PACK_TYPE='0402',
 PART_NUMBER='G21796-004',
 LOCATION='R1M14',
 ROOM='IO_SLOT',
 SEC='1',
 CDS_LIB='mstr_discrete',
 CDS_PART_NAME='RES_0402-200.0,1%,1/16W,CHIP,GA',
 PRIM_FILE='./archive_libs/mstr_discrete/res/chips/chips.prt';

PART_NAME
 R1M15 'RES_0402-0.0,5%,1/16W,CHIP,G21A':
 ROOM='IO_SLOT';

SECTION_NUMBER 1
 '@BASEBOARD_FAB2_LIB.BASEBOARD_FAB2(SCH_1):PAGE186_I339@MSTR_DISCRETE.RES(CHIPS)':
 C_PATH='@baseboard_fab2_lib.baseboard_fab2(sch_1):page186_i339@mstr_discrete.re~
s(chips)',
 P_PATH='@baseboard_fab2_lib.baseboard_fab2(sch_1):page186_i339@mstr_discrete.re~
s(chips)',
 PATH='I339',
 DRAWING='@BASEBOARD_FAB2_LIB.BASEBOARD_FAB2(SCH_1):PAGE186',
 WATTAGE='1/16W',
 TOLERANCE='5%',
 SEC_TYPE='0402',
 MATERIAL='CHIP',
 PHYS_PAGE='186',
 XY='(6375,3200)',
 ROT='0',
 VER='1',
 VALUE='0.0',
 PACK_TYPE='0402',
 PART_NUMBER='G21497-005',
 LOCATION='R1M15',
 ROOM='IO_SLOT',
 SEC='1',
 CDS_LIB='mstr_discrete',
 CDS_PART_NAME='RES_0402-0.0,5%,1/16W,CHIP,G21A',
 PRIM_FILE='./archive_libs/mstr_discrete/res/chips/chips.prt';

PART_NAME
 R1M16 'RES_0402-0.0,5%,1/16W,CHIP,G21A':
 ROOM='IO_SLOT';

SECTION_NUMBER 1
 '@BASEBOARD_FAB2_LIB.BASEBOARD_FAB2(SCH_1):PAGE186_I337@MSTR_DISCRETE.RES(CHIPS)':
 C_PATH='@baseboard_fab2_lib.baseboard_fab2(sch_1):page186_i337@mstr_discrete.re~
s(chips)',
 P_PATH='@baseboard_fab2_lib.baseboard_fab2(sch_1):page186_i337@mstr_discrete.re~
s(chips)',
 PATH='I337',
 DRAWING='@BASEBOARD_FAB2_LIB.BASEBOARD_FAB2(SCH_1):PAGE186',
 WATTAGE='1/16W',
 TOLERANCE='5%',
 SEC_TYPE='0402',
 MATERIAL='CHIP',
 PHYS_PAGE='186',
 XY='(6700,2750)',
 ROT='0',
 VER='1',
 VALUE='0.0',
 PACK_TYPE='0402',
 PART_NUMBER='G21497-005',
 LOCATION='R1M16',
 ROOM='IO_SLOT',
 SEC='1',
 CDS_LIB='mstr_discrete',
 CDS_PART_NAME='RES_0402-0.0,5%,1/16W,CHIP,G21A',
 PRIM_FILE='./archive_libs/mstr_discrete/res/chips/chips.prt';

PART_NAME
 R1M17 'RES_0402-0.0,5%,1/16W,CHIP,G21A':
 ROOM='IO_SLOT';

SECTION_NUMBER 1
 '@BASEBOARD_FAB2_LIB.BASEBOARD_FAB2(SCH_1):PAGE186_I338@MSTR_DISCRETE.RES(CHIPS)':
 C_PATH='@baseboard_fab2_lib.baseboard_fab2(sch_1):page186_i338@mstr_discrete.re~
s(chips)',
 P_PATH='@baseboard_fab2_lib.baseboard_fab2(sch_1):page186_i338@mstr_discrete.re~
s(chips)',
 PATH='I338',
 DRAWING='@BASEBOARD_FAB2_LIB.BASEBOARD_FAB2(SCH_1):PAGE186',
 WATTAGE='1/16W',
 TOLERANCE='5%',
 SEC_TYPE='0402',
 MATERIAL='CHIP',
 PHYS_PAGE='186',
 XY='(6375,2800)',
 ROT='0',
 VER='1',
 VALUE='0.0',
 PACK_TYPE='0402',
 PART_NUMBER='G21497-005',
 LOCATION='R1M17',
 ROOM='IO_SLOT',
 SEC='1',
 CDS_LIB='mstr_discrete',
 CDS_PART_NAME='RES_0402-0.0,5%,1/16W,CHIP,G21A',
 PRIM_FILE='./archive_libs/mstr_discrete/res/chips/chips.prt';

PART_NAME
 R1M18 'RES_0402-0.0,5%,1/16W,CHIP,G21A':
 ROOM='IO_SLOT';

SECTION_NUMBER 1
 '@BASEBOARD_FAB2_LIB.BASEBOARD_FAB2(SCH_1):PAGE186_I340@MSTR_DISCRETE.RES(CHIPS)':
 C_PATH='@baseboard_fab2_lib.baseboard_fab2(sch_1):page186_i340@mstr_discrete.re~
s(chips)',
 P_PATH='@baseboard_fab2_lib.baseboard_fab2(sch_1):page186_i340@mstr_discrete.re~
s(chips)',
 PATH='I340',
 DRAWING='@BASEBOARD_FAB2_LIB.BASEBOARD_FAB2(SCH_1):PAGE186',
 WATTAGE='1/16W',
 TOLERANCE='5%',
 SEC_TYPE='0402',
 MATERIAL='CHIP',
 PHYS_PAGE='186',
 XY='(10250,3000)',
 ROT='0',
 VER='1',
 VALUE='0.0',
 PACK_TYPE='0402',
 PART_NUMBER='G21497-005',
 LOCATION='R1M18',
 ROOM='IO_SLOT',
 SEC='1',
 CDS_LIB='mstr_discrete',
 CDS_PART_NAME='RES_0402-0.0,5%,1/16W,CHIP,G21A',
 PRIM_FILE='./archive_libs/mstr_discrete/res/chips/chips.prt';

PART_NAME
 R1M19 'RES_0402-1.00K,1%,1/16W,CHIP,GA':
 GROUP='MCP',
 ROOM='DEBUG';

SECTION_NUMBER 1
 '@BASEBOARD_FAB2_LIB.BASEBOARD_FAB2(SCH_1):PAGE113_I202@MSTR_DISCRETE.RES(CHIPS)':
 C_PATH='@baseboard_fab2_lib.baseboard_fab2(sch_1):page113_i202@mstr_discrete.re~
s(chips)',
 P_PATH='@baseboard_fab2_lib.baseboard_fab2(sch_1):page113_i202@mstr_discrete.re~
s(chips)',
 PATH='I202',
 DRAWING='@BASEBOARD_FAB2_LIB.BASEBOARD_FAB2(SCH_1):PAGE113',
 WATTAGE='1/16W',
 TOLERANCE='1%',
 SEC_TYPE='0402',
 MATERIAL='CHIP',
 BOM_COST='DEBUG',
 PHYS_PAGE='113',
 XY='(3175,1025)',
 ROT='0',
 VER='2',
 VALUE='1.00K',
 PACK_TYPE='0402',
 PART_NUMBER='G21796-026',
 LOCATION='R1M19',
 ROOM='DEBUG',
 GROUP='MCP',
 SEC='1',
 CDS_LIB='mstr_discrete',
 CDS_PART_NAME='RES_0402-1.00K,1%,1/16W,CHIP,GA',
 PRIM_FILE='./archive_libs/mstr_discrete/res/chips/chips.prt';

PART_NAME
 R1M20 'RES_0402-1.00K,1%,1/16W,CHIP,GA':
 ROOM='DEBUG';

SECTION_NUMBER 1
 '@BASEBOARD_FAB2_LIB.BASEBOARD_FAB2(SCH_1):PAGE113_I204@MSTR_DISCRETE.RES(CHIPS)':
 C_PATH='@baseboard_fab2_lib.baseboard_fab2(sch_1):page113_i204@mstr_discrete.re~
s(chips)',
 P_PATH='@baseboard_fab2_lib.baseboard_fab2(sch_1):page113_i204@mstr_discrete.re~
s(chips)',
 PATH='I204',
 DRAWING='@BASEBOARD_FAB2_LIB.BASEBOARD_FAB2(SCH_1):PAGE113',
 POP='NOPOP',
 WATTAGE='1/16W',
 TOLERANCE='1%',
 SEC_TYPE='0402',
 MATERIAL='CHIP',
 BOM_COST='DEBUG',
 PHYS_PAGE='113',
 XY='(2925,1025)',
 ROT='0',
 VER='2',
 VALUE='1.00K',
 PACK_TYPE='0402',
 PART_NUMBER='G21796-026',
 LOCATION='R1M20',
 ROOM='DEBUG',
 SEC='1',
 CDS_LIB='mstr_discrete',
 CDS_PART_NAME='RES_0402-1.00K,1%,1/16W,CHIP,GA',
 PRIM_FILE='./archive_libs/mstr_discrete/res/chips/chips.prt';

PART_NAME
 R1M21 'RES_0402-1.00K,1%,1/16W,CHIP,GA':
 GROUP='MCP',
 ROOM='DEBUG';

SECTION_NUMBER 1
 '@BASEBOARD_FAB2_LIB.BASEBOARD_FAB2(SCH_1):PAGE113_I205@MSTR_DISCRETE.RES(CHIPS)':
 C_PATH='@baseboard_fab2_lib.baseboard_fab2(sch_1):page113_i205@mstr_discrete.re~
s(chips)',
 P_PATH='@baseboard_fab2_lib.baseboard_fab2(sch_1):page113_i205@mstr_discrete.re~
s(chips)',
 PATH='I205',
 DRAWING='@BASEBOARD_FAB2_LIB.BASEBOARD_FAB2(SCH_1):PAGE113',
 WATTAGE='1/16W',
 TOLERANCE='1%',
 SEC_TYPE='0402',
 MATERIAL='CHIP',
 BOM_COST='DEBUG',
 PHYS_PAGE='113',
 XY='(3675,1025)',
 ROT='0',
 VER='2',
 VALUE='1.00K',
 PACK_TYPE='0402',
 PART_NUMBER='G21796-026',
 LOCATION='R1M21',
 ROOM='DEBUG',
 GROUP='MCP',
 SEC='1',
 CDS_LIB='mstr_discrete',
 CDS_PART_NAME='RES_0402-1.00K,1%,1/16W,CHIP,GA',
 PRIM_FILE='./archive_libs/mstr_discrete/res/chips/chips.prt';

PART_NAME
 R1M22 'RES_0402-49.9,1%,1/16W,CHIP,G2A':
 ROOM='DEBUG';

SECTION_NUMBER 1
 '@BASEBOARD_FAB2_LIB.BASEBOARD_FAB2(SCH_1):PAGE113_I195@MSTR_DISCRETE.RES(CHIPS)':
 C_PATH='@baseboard_fab2_lib.baseboard_fab2(sch_1):page113_i195@mstr_discrete.re~
s(chips)',
 P_PATH='@baseboard_fab2_lib.baseboard_fab2(sch_1):page113_i195@mstr_discrete.re~
s(chips)',
 PATH='I195',
 DRAWING='@BASEBOARD_FAB2_LIB.BASEBOARD_FAB2(SCH_1):PAGE113',
 POP='NOPOP',
 WATTAGE='1/16W',
 TOLERANCE='1%',
 SEC_TYPE='0402',
 MATERIAL='CHIP',
 PHYS_PAGE='113',
 XY='(2450,2650)',
 ROT='2',
 VER='2',
 VALUE='49.9',
 PACK_TYPE='0402',
 PART_NUMBER='G21796-047',
 LOCATION='R1M22',
 ROOM='DEBUG',
 SEC='1',
 CDS_LIB='mstr_discrete',
 CDS_PART_NAME='RES_0402-49.9,1%,1/16W,CHIP,G2A',
 PRIM_FILE='./archive_libs/mstr_discrete/res/chips/chips.prt';

PART_NAME
 R1M23 'RES_0402-1.00K,1%,1/16W,EMPTY,A':
 ROOM='DEBUG';

SECTION_NUMBER 1
 '@BASEBOARD_FAB2_LIB.BASEBOARD_FAB2(SCH_1):PAGE113_I199@MSTR_DISCRETE.RES(CHIPS)':
 C_PATH='@baseboard_fab2_lib.baseboard_fab2(sch_1):page113_i199@mstr_discrete.re~
s(chips)',
 P_PATH='@baseboard_fab2_lib.baseboard_fab2(sch_1):page113_i199@mstr_discrete.re~
s(chips)',
 PATH='I199',
 DRAWING='@BASEBOARD_FAB2_LIB.BASEBOARD_FAB2(SCH_1):PAGE113',
 WATTAGE='1/16W',
 TOLERANCE='1%',
 SEC_TYPE='0402',
 MATERIAL='EMPTY',
 BOM_COST='DEBUG',
 PHYS_PAGE='113',
 XY='(1400,4225)',
 ROT='0',
 VER='2',
 VALUE='1.00K',
 PACK_TYPE='0402',
 PART_NUMBER='G21796-026',
 LOCATION='R1M23',
 ROOM='DEBUG',
 SEC='1',
 CDS_LIB='mstr_discrete',
 CDS_PART_NAME='RES_0402-1.00K,1%,1/16W,EMPTY,A',
 PRIM_FILE='./archive_libs/mstr_discrete/res/chips/chips.prt';

PART_NAME
 R1M24 'RES_0402-10.0K,1%,1/16W,CHIP,GA':
 ROOM='USB_REAR';

SECTION_NUMBER 1
 '@BASEBOARD_FAB2_LIB.BASEBOARD_FAB2(SCH_1):PAGE176_I105@MSTR_DISCRETE.RES(CHIPS)':
 C_PATH='@baseboard_fab2_lib.baseboard_fab2(sch_1):page176_i105@mstr_discrete.re~
s(chips)',
 P_PATH='@baseboard_fab2_lib.baseboard_fab2(sch_1):page176_i105@mstr_discrete.re~
s(chips)',
 PATH='I105',
 DRAWING='@BASEBOARD_FAB2_LIB.BASEBOARD_FAB2(SCH_1):PAGE176',
 WATTAGE='1/16W',
 TOLERANCE='1%',
 SEC_TYPE='0402',
 MATERIAL='CHIP',
 BOM_COST='MIO_USB',
 PHYS_PAGE='176',
 XY='(-3700,3675)',
 ROT='0',
 VER='2',
 VALUE='10.0K',
 PACK_TYPE='0402',
 PART_NUMBER='G21796-016',
 LOCATION='R1M24',
 ROOM='USB_REAR',
 SEC='1',
 CDS_LIB='mstr_discrete',
 CDS_PART_NAME='RES_0402-10.0K,1%,1/16W,CHIP,GA',
 PRIM_FILE='./archive_libs/mstr_discrete/res/chips/chips.prt';

PART_NAME
 R1M25 'RES_0402-10.0K,1%,1/16W,CHIP,GA':
 ROOM='USB_REAR';

SECTION_NUMBER 1
 '@BASEBOARD_FAB2_LIB.BASEBOARD_FAB2(SCH_1):PAGE176_I111@MSTR_DISCRETE.RES(CHIPS)':
 C_PATH='@baseboard_fab2_lib.baseboard_fab2(sch_1):page176_i111@mstr_discrete.re~
s(chips)',
 P_PATH='@baseboard_fab2_lib.baseboard_fab2(sch_1):page176_i111@mstr_discrete.re~
s(chips)',
 PATH='I111',
 DRAWING='@BASEBOARD_FAB2_LIB.BASEBOARD_FAB2(SCH_1):PAGE176',
 WATTAGE='1/16W',
 TOLERANCE='1%',
 SEC_TYPE='0402',
 MATERIAL='CHIP',
 BOM_COST='MIO_USB',
 PHYS_PAGE='176',
 XY='(-5200,3000)',
 ROT='0',
 VER='2',
 VALUE='10.0K',
 PACK_TYPE='0402',
 PART_NUMBER='G21796-016',
 LOCATION='R1M25',
 ROOM='USB_REAR',
 SEC='1',
 CDS_LIB='mstr_discrete',
 CDS_PART_NAME='RES_0402-10.0K,1%,1/16W,CHIP,GA',
 PRIM_FILE='./archive_libs/mstr_discrete/res/chips/chips.prt';

PART_NAME
 R1R1 'RES_0402-0.0,5%,1/16W,CHIP,G21A':
 ROOM='NIC_SPRV';

SECTION_NUMBER 1
 '@BASEBOARD_FAB2_LIB.BASEBOARD_FAB2(SCH_1):PAGE139_I195@MSTR_DISCRETE.RES(CHIPS)':
 C_PATH='@baseboard_fab2_lib.baseboard_fab2(sch_1):page139_i195@mstr_discrete.re~
s(chips)',
 P_PATH='@baseboard_fab2_lib.baseboard_fab2(sch_1):page139_i195@mstr_discrete.re~
s(chips)',
 PATH='I195',
 DRAWING='@BASEBOARD_FAB2_LIB.BASEBOARD_FAB2(SCH_1):PAGE139',
 WATTAGE='1/16W',
 TOLERANCE='5%',
 SEC_TYPE='0402',
 MATERIAL='CHIP',
 BOM_COST='NT_GBE_BASE',
 PHYS_PAGE='139',
 XY='(-7075,350)',
 ROT='0',
 VER='1',
 VALUE='0.0',
 PACK_TYPE='0402',
 PART_NUMBER='G21497-005',
 LOCATION='R1R1',
 ROOM='NIC_SPRV',
 SEC='1',
 CDS_LIB='mstr_discrete',
 CDS_PART_NAME='RES_0402-0.0,5%,1/16W,CHIP,G21A',
 PRIM_FILE='./archive_libs/mstr_discrete/res/chips/chips.prt';

PART_NAME
 R1R3 'RES_0402-3.32K,1%,1/16W,CHIP,GA':
 GROUP='NI_I210&RJ45',
 ROOM='NIC_SPRV';

SECTION_NUMBER 1
 '@BASEBOARD_FAB2_LIB.BASEBOARD_FAB2(SCH_1):PAGE140_I11@MSTR_DISCRETE.RES(CHIPS)':
 C_PATH='@baseboard_fab2_lib.baseboard_fab2(sch_1):page140_i11@mstr_discrete.res~
(chips)',
 P_PATH='@baseboard_fab2_lib.baseboard_fab2(sch_1):page140_i11@mstr_discrete.res~
(chips)',
 PATH='I11',
 DRAWING='@BASEBOARD_FAB2_LIB.BASEBOARD_FAB2(SCH_1):PAGE140',
 WATTAGE='1/16W',
 TOLERANCE='1%',
 SEC_TYPE='0402',
 MATERIAL='CHIP',
 BOM_COST='NT_GBE_BASE',
 PHYS_PAGE='140',
 XY='(-3550,3300)',
 ROT='0',
 VER='2',
 VALUE='3.32K',
 PACK_TYPE='0402',
 PART_NUMBER='G21796-027',
 LOCATION='R1R3',
 ROOM='NIC_SPRV',
 GROUP='NI_I210&RJ45',
 SEC='1',
 CDS_LIB='mstr_discrete',
 CDS_PART_NAME='RES_0402-3.32K,1%,1/16W,CHIP,GA',
 PRIM_FILE='./archive_libs/mstr_discrete/res/chips/chips.prt';

PART_NAME
 R1R5 'RES_0402-4.75K,1%,1/16W,CHIP,GA':
 ROOM='FAST_PROCHOT';

SECTION_NUMBER 1
 '@BASEBOARD_FAB2_LIB.BASEBOARD_FAB2(SCH_1):PAGE170_I73@MSTR_DISCRETE.RES(CHIPS)':
 C_PATH='@baseboard_fab2_lib.baseboard_fab2(sch_1):page170_i73@mstr_discrete.res~
(chips)',
 P_PATH='@baseboard_fab2_lib.baseboard_fab2(sch_1):page170_i73@mstr_discrete.res~
(chips)',
 PATH='I73',
 DRAWING='@BASEBOARD_FAB2_LIB.BASEBOARD_FAB2(SCH_1):PAGE170',
 WATTAGE='1/16W',
 TOLERANCE='1%',
 SEC_TYPE='0402',
 MATERIAL='CHIP',
 BOM_COST='FAST_PROCHOT',
 PHYS_PAGE='170',
 XY='(-2025,2850)',
 ROT='0',
 VER='2',
 VALUE='4.75K',
 PACK_TYPE='0402',
 PART_NUMBER='G21796-072',
 LOCATION='R1R5',
 ROOM='FAST_PROCHOT',
 SEC='1',
 CDS_LIB='mstr_discrete',
 CDS_PART_NAME='RES_0402-4.75K,1%,1/16W,CHIP,GA',
 PRIM_FILE='./archive_libs/mstr_discrete/res/chips/chips.prt';

PART_NAME
 R1R6 'RES_0402-3.32K,1%,1/16W,EMPTY,A':
 GROUP='NI_I210&RJ45',
 ROOM='NIC_SPRV';

SECTION_NUMBER 1
 '@BASEBOARD_FAB2_LIB.BASEBOARD_FAB2(SCH_1):PAGE140_I14@MSTR_DISCRETE.RES(CHIPS)':
 C_PATH='@baseboard_fab2_lib.baseboard_fab2(sch_1):page140_i14@mstr_discrete.res~
(chips)',
 P_PATH='@baseboard_fab2_lib.baseboard_fab2(sch_1):page140_i14@mstr_discrete.res~
(chips)',
 PATH='I14',
 DRAWING='@BASEBOARD_FAB2_LIB.BASEBOARD_FAB2(SCH_1):PAGE140',
 WATTAGE='1/16W',
 TOLERANCE='1%',
 SEC_TYPE='0402',
 MATERIAL='EMPTY',
 BOM_COST='NT_GBE_BASE',
 PHYS_PAGE='140',
 XY='(-3825,2350)',
 ROT='0',
 VER='2',
 VALUE='3.32K',
 PACK_TYPE='0402',
 PART_NUMBER='G21796-027',
 LOCATION='R1R6',
 ROOM='NIC_SPRV',
 GROUP='NI_I210&RJ45',
 SEC='1',
 CDS_LIB='mstr_discrete',
 CDS_PART_NAME='RES_0402-3.32K,1%,1/16W,EMPTY,A',
 PRIM_FILE='./archive_libs/mstr_discrete/res/chips/chips.prt';

PART_NAME
 R1R7 'RES_0402-20.0K,1%,1/16W,CHIP,GA':
 GROUP='NI_I210&RJ45',
 ROOM='NIC_SPRV';

SECTION_NUMBER 1
 '@BASEBOARD_FAB2_LIB.BASEBOARD_FAB2(SCH_1):PAGE140_I12@MSTR_DISCRETE.RES(CHIPS)':
 C_PATH='@baseboard_fab2_lib.baseboard_fab2(sch_1):page140_i12@mstr_discrete.res~
(chips)',
 P_PATH='@baseboard_fab2_lib.baseboard_fab2(sch_1):page140_i12@mstr_discrete.res~
(chips)',
 PATH='I12',
 DRAWING='@BASEBOARD_FAB2_LIB.BASEBOARD_FAB2(SCH_1):PAGE140',
 WATTAGE='1/16W',
 TOLERANCE='1%',
 SEC_TYPE='0402',
 MATERIAL='CHIP',
 BOM_COST='NT_GBE_BASE',
 PHYS_PAGE='140',
 XY='(-3950,3300)',
 ROT='0',
 VER='2',
 VALUE='20.0K',
 PACK_TYPE='0402',
 PART_NUMBER='G21796-040',
 LOCATION='R1R7',
 ROOM='NIC_SPRV',
 GROUP='NI_I210&RJ45',
 SEC='1',
 CDS_LIB='mstr_discrete',
 CDS_PART_NAME='RES_0402-20.0K,1%,1/16W,CHIP,GA',
 PRIM_FILE='./archive_libs/mstr_discrete/res/chips/chips.prt';

PART_NAME
 R1R8 'RES_0402-0.0,5%,1/16W,CHIP,G21A':
 ROOM='PROC_SIDEBAND';

SECTION_NUMBER 1
 '@BASEBOARD_FAB2_LIB.BASEBOARD_FAB2(SCH_1):PAGE170_I51@MSTR_DISCRETE.RES(CHIPS)':
 C_PATH='@baseboard_fab2_lib.baseboard_fab2(sch_1):page170_i51@mstr_discrete.res~
(chips)',
 P_PATH='@baseboard_fab2_lib.baseboard_fab2(sch_1):page170_i51@mstr_discrete.res~
(chips)',
 PATH='I51',
 DRAWING='@BASEBOARD_FAB2_LIB.BASEBOARD_FAB2(SCH_1):PAGE170',
 WATTAGE='1/16W',
 TOLERANCE='5%',
 SEC_TYPE='0402',
 MATERIAL='CHIP',
 BOM_COST='PROC_SIDEBAND',
 PHYS_PAGE='170',
 XY='(-475,2525)',
 ROT='0',
 VER='1',
 VALUE='0.0',
 PACK_TYPE='0402',
 PART_NUMBER='G21497-005',
 LOCATION='R1R8',
 ROOM='PROC_SIDEBAND',
 SEC='1',
 CDS_LIB='mstr_discrete',
 CDS_PART_NAME='RES_0402-0.0,5%,1/16W,CHIP,G21A',
 PRIM_FILE='./archive_libs/mstr_discrete/res/chips/chips.prt';

PART_NAME
 R1R9 'RES_0402-3.32K,1%,1/16W,CHIP,GA':
 GROUP='NI_I210&RJ45',
 ROOM='NIC_SPRV';

SECTION_NUMBER 1
 '@BASEBOARD_FAB2_LIB.BASEBOARD_FAB2(SCH_1):PAGE140_I10@MSTR_DISCRETE.RES(CHIPS)':
 C_PATH='@baseboard_fab2_lib.baseboard_fab2(sch_1):page140_i10@mstr_discrete.res~
(chips)',
 P_PATH='@baseboard_fab2_lib.baseboard_fab2(sch_1):page140_i10@mstr_discrete.res~
(chips)',
 PATH='I10',
 DRAWING='@BASEBOARD_FAB2_LIB.BASEBOARD_FAB2(SCH_1):PAGE140',
 WATTAGE='1/16W',
 TOLERANCE='1%',
 SEC_TYPE='0402',
 MATERIAL='CHIP',
 BOM_COST='NT_GBE_BASE',
 PHYS_PAGE='140',
 XY='(-3200,3300)',
 ROT='0',
 VER='2',
 VALUE='3.32K',
 PACK_TYPE='0402',
 PART_NUMBER='G21796-027',
 LOCATION='R1R9',
 ROOM='NIC_SPRV',
 GROUP='NI_I210&RJ45',
 SEC='1',
 CDS_LIB='mstr_discrete',
 CDS_PART_NAME='RES_0402-3.32K,1%,1/16W,CHIP,GA',
 PRIM_FILE='./archive_libs/mstr_discrete/res/chips/chips.prt';

PART_NAME
 R1R12 'RES_0402-10.0K,1%,1/16W,CHIP,GA':
 GROUP='NI_I210&RJ45',
 ROOM='NIC_SPRV';

SECTION_NUMBER 1
 '@BASEBOARD_FAB2_LIB.BASEBOARD_FAB2(SCH_1):PAGE139_I213@MSTR_DISCRETE.RES(CHIPS)':
 C_PATH='@baseboard_fab2_lib.baseboard_fab2(sch_1):page139_i213@mstr_discrete.re~
s(chips)',
 P_PATH='@baseboard_fab2_lib.baseboard_fab2(sch_1):page139_i213@mstr_discrete.re~
s(chips)',
 PATH='I213',
 DRAWING='@BASEBOARD_FAB2_LIB.BASEBOARD_FAB2(SCH_1):PAGE139',
 WATTAGE='1/16W',
 TOLERANCE='1%',
 MATERIAL='CHIP',
 BOM_COST='NT_GBE_BASE',
 PHYS_PAGE='139',
 XY='(-3050,1500)',
 ROT='0',
 VER='2',
 VALUE='10.0K',
 PACK_TYPE='0402',
 PART_NUMBER='G21796-016',
 LOCATION='R1R12',
 ROOM='NIC_SPRV',
 GROUP='NI_I210&RJ45',
 CDS_LIB='mstr_discrete',
 CDS_PART_NAME='RES_0402-10.0K,1%,1/16W,CHIP,GA',
 PRIM_FILE='./archive_libs/mstr_discrete/res/chips/chips.prt';

PART_NAME
 R1R15 'RES_0603-0,5.0%,1/10W,CHIP,G22A':
 GROUP='NI_I210&RJ45',
 ROOM='NIC_SPRV';

SECTION_NUMBER 1
 '@BASEBOARD_FAB2_LIB.BASEBOARD_FAB2(SCH_1):PAGE139_I237@MSTR_DISCRETE.RES(CHIPS)':
 C_PATH='@baseboard_fab2_lib.baseboard_fab2(sch_1):page139_i237@mstr_discrete.re~
s(chips)',
 P_PATH='@baseboard_fab2_lib.baseboard_fab2(sch_1):page139_i237@mstr_discrete.re~
s(chips)',
 PATH='I237',
 DRAWING='@BASEBOARD_FAB2_LIB.BASEBOARD_FAB2(SCH_1):PAGE139',
 WATTAGE='1/10W',
 TOLERANCE='5.0%',
 SEC_TYPE='0603',
 MATERIAL='CHIP',
 BOM_COST='NT_GBE_BASE',
 PHYS_PAGE='139',
 XY='(-5600,4025)',
 ROT='0',
 VER='1',
 VALUE='0',
 PACK_TYPE='0603',
 PART_NUMBER='G22178-002',
 LOCATION='R1R15',
 ROOM='NIC_SPRV',
 GROUP='NI_I210&RJ45',
 SEC='1',
 CDS_LIB='mstr_discrete',
 CDS_PART_NAME='RES_0603-0,5.0%,1/10W,CHIP,G22A',
 PRIM_FILE='./archive_libs/mstr_discrete/res/chips/chips.prt';

PART_NAME
 R1R16 'RES_0402-2.21K,1%,1/16W,CHIP,GA':;

SECTION_NUMBER 1
 '@BASEBOARD_FAB2_LIB.BASEBOARD_FAB2(SCH_1):PAGE188_I93@MSTR_DISCRETE.RES(CHIPS)':
 C_PATH='@baseboard_fab2_lib.baseboard_fab2(sch_1):page188_i93@mstr_discrete.res~
(chips)',
 P_PATH='@baseboard_fab2_lib.baseboard_fab2(sch_1):page188_i93@mstr_discrete.res~
(chips)',
 PATH='I93',
 DRAWING='@BASEBOARD_FAB2_LIB.BASEBOARD_FAB2(SCH_1):PAGE188',
 WATTAGE='1/16W',
 TOLERANCE='1%',
 SEC_TYPE='0402',
 MATERIAL='CHIP',
 PHYS_PAGE='188',
 XY='(-3250,3350)',
 ROT='0',
 VER='1',
 VALUE='2.21K',
 PACK_TYPE='0402',
 PART_NUMBER='G21796-112',
 LOCATION='R1R16',
 SEC='1',
 CDS_LIB='mstr_discrete',
 CDS_PART_NAME='RES_0402-2.21K,1%,1/16W,CHIP,GA',
 PRIM_FILE='./archive_libs/mstr_discrete/res/chips/chips.prt';

PART_NAME
 R1R17 'RES_0402-2.21K,1%,1/16W,CHIP,GA':;

SECTION_NUMBER 1
 '@BASEBOARD_FAB2_LIB.BASEBOARD_FAB2(SCH_1):PAGE188_I94@MSTR_DISCRETE.RES(CHIPS)':
 C_PATH='@baseboard_fab2_lib.baseboard_fab2(sch_1):page188_i94@mstr_discrete.res~
(chips)',
 P_PATH='@baseboard_fab2_lib.baseboard_fab2(sch_1):page188_i94@mstr_discrete.res~
(chips)',
 PATH='I94',
 DRAWING='@BASEBOARD_FAB2_LIB.BASEBOARD_FAB2(SCH_1):PAGE188',
 WATTAGE='1/16W',
 TOLERANCE='1%',
 SEC_TYPE='0402',
 MATERIAL='CHIP',
 PHYS_PAGE='188',
 XY='(-3250,3200)',
 ROT='0',
 VER='1',
 VALUE='2.21K',
 PACK_TYPE='0402',
 PART_NUMBER='G21796-112',
 LOCATION='R1R17',
 SEC='1',
 CDS_LIB='mstr_discrete',
 CDS_PART_NAME='RES_0402-2.21K,1%,1/16W,CHIP,GA',
 PRIM_FILE='./archive_libs/mstr_discrete/res/chips/chips.prt';

PART_NAME
 R1R18 'RES_0402-2.21K,1%,1/16W,CHIP,GA':;

SECTION_NUMBER 1
 '@BASEBOARD_FAB2_LIB.BASEBOARD_FAB2(SCH_1):PAGE188_I88@MSTR_DISCRETE.RES(CHIPS)':
 C_PATH='@baseboard_fab2_lib.baseboard_fab2(sch_1):page188_i88@mstr_discrete.res~
(chips)',
 P_PATH='@baseboard_fab2_lib.baseboard_fab2(sch_1):page188_i88@mstr_discrete.res~
(chips)',
 PATH='I88',
 DRAWING='@BASEBOARD_FAB2_LIB.BASEBOARD_FAB2(SCH_1):PAGE188',
 WATTAGE='1/16W',
 TOLERANCE='1%',
 SEC_TYPE='0402',
 MATERIAL='CHIP',
 PHYS_PAGE='188',
 XY='(-3250,3950)',
 ROT='0',
 VER='1',
 VALUE='2.21K',
 PACK_TYPE='0402',
 PART_NUMBER='G21796-112',
 LOCATION='R1R18',
 SEC='1',
 CDS_LIB='mstr_discrete',
 CDS_PART_NAME='RES_0402-2.21K,1%,1/16W,CHIP,GA',
 PRIM_FILE='./archive_libs/mstr_discrete/res/chips/chips.prt';

PART_NAME
 R1R19 'RES_0402-2.21K,1%,1/16W,CHIP,GA':;

SECTION_NUMBER 1
 '@BASEBOARD_FAB2_LIB.BASEBOARD_FAB2(SCH_1):PAGE188_I89@MSTR_DISCRETE.RES(CHIPS)':
 C_PATH='@baseboard_fab2_lib.baseboard_fab2(sch_1):page188_i89@mstr_discrete.res~
(chips)',
 P_PATH='@baseboard_fab2_lib.baseboard_fab2(sch_1):page188_i89@mstr_discrete.res~
(chips)',
 PATH='I89',
 DRAWING='@BASEBOARD_FAB2_LIB.BASEBOARD_FAB2(SCH_1):PAGE188',
 WATTAGE='1/16W',
 TOLERANCE='1%',
 SEC_TYPE='0402',
 MATERIAL='CHIP',
 PHYS_PAGE='188',
 XY='(-3250,3800)',
 ROT='0',
 VER='1',
 VALUE='2.21K',
 PACK_TYPE='0402',
 PART_NUMBER='G21796-112',
 LOCATION='R1R19',
 SEC='1',
 CDS_LIB='mstr_discrete',
 CDS_PART_NAME='RES_0402-2.21K,1%,1/16W,CHIP,GA',
 PRIM_FILE='./archive_libs/mstr_discrete/res/chips/chips.prt';

PART_NAME
 R1R20 'RES_0402-2.21K,1%,1/16W,CHIP,GA':;

SECTION_NUMBER 1
 '@BASEBOARD_FAB2_LIB.BASEBOARD_FAB2(SCH_1):PAGE188_I91@MSTR_DISCRETE.RES(CHIPS)':
 C_PATH='@baseboard_fab2_lib.baseboard_fab2(sch_1):page188_i91@mstr_discrete.res~
(chips)',
 P_PATH='@baseboard_fab2_lib.baseboard_fab2(sch_1):page188_i91@mstr_discrete.res~
(chips)',
 PATH='I91',
 DRAWING='@BASEBOARD_FAB2_LIB.BASEBOARD_FAB2(SCH_1):PAGE188',
 WATTAGE='1/16W',
 TOLERANCE='1%',
 SEC_TYPE='0402',
 MATERIAL='CHIP',
 PHYS_PAGE='188',
 XY='(-3250,3650)',
 ROT='0',
 VER='1',
 VALUE='2.21K',
 PACK_TYPE='0402',
 PART_NUMBER='G21796-112',
 LOCATION='R1R20',
 SEC='1',
 CDS_LIB='mstr_discrete',
 CDS_PART_NAME='RES_0402-2.21K,1%,1/16W,CHIP,GA',
 PRIM_FILE='./archive_libs/mstr_discrete/res/chips/chips.prt';

PART_NAME
 R1R21 'RES_0402-2.21K,1%,1/16W,CHIP,GA':;

SECTION_NUMBER 1
 '@BASEBOARD_FAB2_LIB.BASEBOARD_FAB2(SCH_1):PAGE188_I90@MSTR_DISCRETE.RES(CHIPS)':
 C_PATH='@baseboard_fab2_lib.baseboard_fab2(sch_1):page188_i90@mstr_discrete.res~
(chips)',
 P_PATH='@baseboard_fab2_lib.baseboard_fab2(sch_1):page188_i90@mstr_discrete.res~
(chips)',
 PATH='I90',
 DRAWING='@BASEBOARD_FAB2_LIB.BASEBOARD_FAB2(SCH_1):PAGE188',
 WATTAGE='1/16W',
 TOLERANCE='1%',
 SEC_TYPE='0402',
 MATERIAL='CHIP',
 PHYS_PAGE='188',
 XY='(-3250,3500)',
 ROT='0',
 VER='1',
 VALUE='2.21K',
 PACK_TYPE='0402',
 PART_NUMBER='G21796-112',
 LOCATION='R1R21',
 SEC='1',
 CDS_LIB='mstr_discrete',
 CDS_PART_NAME='RES_0402-2.21K,1%,1/16W,CHIP,GA',
 PRIM_FILE='./archive_libs/mstr_discrete/res/chips/chips.prt';

PART_NAME
 R1R22 'RES_0402-2.21K,1%,1/16W,CHIP,GA':;

SECTION_NUMBER 1
 '@BASEBOARD_FAB2_LIB.BASEBOARD_FAB2(SCH_1):PAGE188_I92@MSTR_DISCRETE.RES(CHIPS)':
 C_PATH='@baseboard_fab2_lib.baseboard_fab2(sch_1):page188_i92@mstr_discrete.res~
(chips)',
 P_PATH='@baseboard_fab2_lib.baseboard_fab2(sch_1):page188_i92@mstr_discrete.res~
(chips)',
 PATH='I92',
 DRAWING='@BASEBOARD_FAB2_LIB.BASEBOARD_FAB2(SCH_1):PAGE188',
 WATTAGE='1/16W',
 TOLERANCE='1%',
 SEC_TYPE='0402',
 MATERIAL='CHIP',
 PHYS_PAGE='188',
 XY='(-3250,2900)',
 ROT='0',
 VER='1',
 VALUE='2.21K',
 PACK_TYPE='0402',
 PART_NUMBER='G21796-112',
 LOCATION='R1R22',
 SEC='1',
 CDS_LIB='mstr_discrete',
 CDS_PART_NAME='RES_0402-2.21K,1%,1/16W,CHIP,GA',
 PRIM_FILE='./archive_libs/mstr_discrete/res/chips/chips.prt';

PART_NAME
 R1R23 'RES_0402-2.21K,1%,1/16W,CHIP,GA':;

SECTION_NUMBER 1
 '@BASEBOARD_FAB2_LIB.BASEBOARD_FAB2(SCH_1):PAGE188_I95@MSTR_DISCRETE.RES(CHIPS)':
 C_PATH='@baseboard_fab2_lib.baseboard_fab2(sch_1):page188_i95@mstr_discrete.res~
(chips)',
 P_PATH='@baseboard_fab2_lib.baseboard_fab2(sch_1):page188_i95@mstr_discrete.res~
(chips)',
 PATH='I95',
 DRAWING='@BASEBOARD_FAB2_LIB.BASEBOARD_FAB2(SCH_1):PAGE188',
 WATTAGE='1/16W',
 TOLERANCE='1%',
 SEC_TYPE='0402',
 MATERIAL='CHIP',
 PHYS_PAGE='188',
 XY='(-3250,3050)',
 ROT='0',
 VER='1',
 VALUE='2.21K',
 PACK_TYPE='0402',
 PART_NUMBER='G21796-112',
 LOCATION='R1R23',
 SEC='1',
 CDS_LIB='mstr_discrete',
 CDS_PART_NAME='RES_0402-2.21K,1%,1/16W,CHIP,GA',
 PRIM_FILE='./archive_libs/mstr_discrete/res/chips/chips.prt';

PART_NAME
 R1T1 'RES_0402-10.0K,1%,1/16W,CHIP,GA':
 ROOM='NIC_SPRV';

SECTION_NUMBER 1
 '@BASEBOARD_FAB2_LIB.BASEBOARD_FAB2(SCH_1):PAGE139_I214@MSTR_DISCRETE.RES(CHIPS)':
 C_PATH='@baseboard_fab2_lib.baseboard_fab2(sch_1):page139_i214@mstr_discrete.re~
s(chips)',
 P_PATH='@baseboard_fab2_lib.baseboard_fab2(sch_1):page139_i214@mstr_discrete.re~
s(chips)',
 PATH='I214',
 DRAWING='@BASEBOARD_FAB2_LIB.BASEBOARD_FAB2(SCH_1):PAGE139',
 WATTAGE='1/16W',
 TOLERANCE='1%',
 MATERIAL='CHIP',
 BOM_COST='NT_GBE_BASE',
 PHYS_PAGE='139',
 XY='(-1300,1550)',
 ROT='0',
 VER='2',
 VALUE='10.0K',
 PACK_TYPE='0402',
 PART_NUMBER='G21796-016',
 LOCATION='R1T1',
 ROOM='NIC_SPRV',
 CDS_LIB='mstr_discrete',
 CDS_PART_NAME='RES_0402-10.0K,1%,1/16W,CHIP,GA',
 PRIM_FILE='./archive_libs/mstr_discrete/res/chips/chips.prt';

PART_NAME
 R1T2 'RES_0402-665,1.0%,1/16W,CHIP,GA':
 ROOM='SMBUS';

SECTION_NUMBER 1
 '@BASEBOARD_FAB2_LIB.BASEBOARD_FAB2(SCH_1):PAGE160_I49@MSTR_DISCRETE.RES(CHIPS)':
 C_PATH='@baseboard_fab2_lib.baseboard_fab2(sch_1):page160_i49@mstr_discrete.res~
(chips)',
 P_PATH='@baseboard_fab2_lib.baseboard_fab2(sch_1):page160_i49@mstr_discrete.res~
(chips)',
 PATH='I49',
 DRAWING='@BASEBOARD_FAB2_LIB.BASEBOARD_FAB2(SCH_1):PAGE160',
 SKU='B',
 WATTAGE='1/16W',
 TOLERANCE='1.0%',
 SEC_TYPE='0402',
 MATERIAL='CHIP',
 BOM_COST='SM_CONTROLLER',
 PHYS_PAGE='160',
 XY='(-3650,4975)',
 ROT='0',
 VER='2',
 VALUE='665',
 PACK_TYPE='0402',
 PART_NUMBER='G21796-235',
 LOCATION='R1T2',
 ROOM='SMBUS',
 SEC='1',
 CDS_LIB='mstr_discrete',
 CDS_PART_NAME='RES_0402-665,1.0%,1/16W,CHIP,GA',
 PRIM_FILE='./archive_libs/mstr_discrete/res/chips/chips.prt';

PART_NAME
 R1T3 'RES_0402-665,1.0%,1/16W,CHIP,GA':
 ROOM='SMBUS';

SECTION_NUMBER 1
 '@BASEBOARD_FAB2_LIB.BASEBOARD_FAB2(SCH_1):PAGE160_I46@MSTR_DISCRETE.RES(CHIPS)':
 C_PATH='@baseboard_fab2_lib.baseboard_fab2(sch_1):page160_i46@mstr_discrete.res~
(chips)',
 P_PATH='@baseboard_fab2_lib.baseboard_fab2(sch_1):page160_i46@mstr_discrete.res~
(chips)',
 PATH='I46',
 DRAWING='@BASEBOARD_FAB2_LIB.BASEBOARD_FAB2(SCH_1):PAGE160',
 SKU='B',
 WATTAGE='1/16W',
 TOLERANCE='1.0%',
 SEC_TYPE='0402',
 MATERIAL='CHIP',
 BOM_COST='SM_CONTROLLER',
 PHYS_PAGE='160',
 XY='(-4000,4975)',
 ROT='0',
 VER='2',
 VALUE='665',
 PACK_TYPE='0402',
 PART_NUMBER='G21796-235',
 LOCATION='R1T3',
 ROOM='SMBUS',
 SEC='1',
 CDS_LIB='mstr_discrete',
 CDS_PART_NAME='RES_0402-665,1.0%,1/16W,CHIP,GA',
 PRIM_FILE='./archive_libs/mstr_discrete/res/chips/chips.prt';

PART_NAME
 R1T4 'RES_0402-2.7K,1%,1/16W,CHIP,G2A':
 ROOM='BMC_MISC';

SECTION_NUMBER 1
 '@BASEBOARD_FAB2_LIB.BASEBOARD_FAB2(SCH_1):PAGE164_I100@MSTR_DISCRETE.RES(CHIPS)':
 C_PATH='@baseboard_fab2_lib.baseboard_fab2(sch_1):page164_i100@mstr_discrete.re~
s(chips)',
 P_PATH='@baseboard_fab2_lib.baseboard_fab2(sch_1):page164_i100@mstr_discrete.re~
s(chips)',
 PATH='I100',
 DRAWING='@BASEBOARD_FAB2_LIB.BASEBOARD_FAB2(SCH_1):PAGE164',
 WATTAGE='1/16W',
 TOLERANCE='1%',
 SEC_TYPE='0402',
 MATERIAL='CHIP',
 BOM_COST='SM_CONTROLLER',
 PHYS_PAGE='164',
 XY='(-7400,1200)',
 ROT='0',
 VER='1',
 VALUE='2.7K',
 PACK_TYPE='0402',
 PART_NUMBER='G21796-344',
 LOCATION='R1T4',
 ROOM='BMC_MISC',
 SEC='1',
 CDS_LIB='mstr_discrete',
 CDS_PART_NAME='RES_0402-2.7K,1%,1/16W,CHIP,G2A',
 PRIM_FILE='./archive_libs/mstr_discrete/res/chips/chips.prt';

PART_NAME
 R1T5 'RES_0402-2.7K,1%,1/16W,EMPTY,GA':
 ROOM='BMC_MISC';

SECTION_NUMBER 1
 '@BASEBOARD_FAB2_LIB.BASEBOARD_FAB2(SCH_1):PAGE164_I11@MSTR_DISCRETE.RES(CHIPS)':
 C_PATH='@baseboard_fab2_lib.baseboard_fab2(sch_1):page164_i11@mstr_discrete.res~
(chips)',
 P_PATH='@baseboard_fab2_lib.baseboard_fab2(sch_1):page164_i11@mstr_discrete.res~
(chips)',
 PATH='I11',
 DRAWING='@BASEBOARD_FAB2_LIB.BASEBOARD_FAB2(SCH_1):PAGE164',
 WATTAGE='1/16W',
 TOLERANCE='1%',
 SEC_TYPE='0402',
 MATERIAL='EMPTY',
 BOM_COST='SM_CONTROLLER',
 PHYS_PAGE='164',
 XY='(-7400,1600)',
 ROT='0',
 VER='1',
 VALUE='2.7K',
 PACK_TYPE='0402',
 PART_NUMBER='G21796-344',
 LOCATION='R1T5',
 ROOM='BMC_MISC',
 SEC='1',
 CDS_LIB='mstr_discrete',
 CDS_PART_NAME='RES_0402-2.7K,1%,1/16W,EMPTY,GA',
 PRIM_FILE='./archive_libs/mstr_discrete/res/chips/chips.prt';

PART_NAME
 R1T6 'RES_0402-2.7K,1%,1/16W,CHIP,G2A':
 ROOM='BMC_MISC';

SECTION_NUMBER 1
 '@BASEBOARD_FAB2_LIB.BASEBOARD_FAB2(SCH_1):PAGE164_I51@MSTR_DISCRETE.RES(CHIPS)':
 C_PATH='@baseboard_fab2_lib.baseboard_fab2(sch_1):page164_i51@mstr_discrete.res~
(chips)',
 P_PATH='@baseboard_fab2_lib.baseboard_fab2(sch_1):page164_i51@mstr_discrete.res~
(chips)',
 PATH='I51',
 DRAWING='@BASEBOARD_FAB2_LIB.BASEBOARD_FAB2(SCH_1):PAGE164',
 WATTAGE='1/16W',
 TOLERANCE='1%',
 SEC_TYPE='0402',
 MATERIAL='CHIP',
 BOM_COST='SM_CONTROLLER',
 PHYS_PAGE='164',
 XY='(-7400,1400)',
 ROT='0',
 VER='1',
 VALUE='2.7K',
 PACK_TYPE='0402',
 PART_NUMBER='G21796-344',
 LOCATION='R1T6',
 ROOM='BMC_MISC',
 SEC='1',
 CDS_LIB='mstr_discrete',
 CDS_PART_NAME='RES_0402-2.7K,1%,1/16W,CHIP,G2A',
 PRIM_FILE='./archive_libs/mstr_discrete/res/chips/chips.prt';

PART_NAME
 R1T7 'RES_0402-20.0,1%,1/16W,CHIP,G2A':
 ROOM='SMBUS';

SECTION_NUMBER 1
 '@BASEBOARD_FAB2_LIB.BASEBOARD_FAB2(SCH_1):PAGE160_I50@MSTR_DISCRETE.RES(CHIPS)':
 C_PATH='@baseboard_fab2_lib.baseboard_fab2(sch_1):page160_i50@mstr_discrete.res~
(chips)',
 P_PATH='@baseboard_fab2_lib.baseboard_fab2(sch_1):page160_i50@mstr_discrete.res~
(chips)',
 PATH='I50',
 DRAWING='@BASEBOARD_FAB2_LIB.BASEBOARD_FAB2(SCH_1):PAGE160',
 WATTAGE='1/16W',
 TOLERANCE='1%',
 MATERIAL='CHIP',
 BOM_COST='SM_CONTROLLER',
 PHYS_PAGE='160',
 XY='(-3350,4425)',
 ROT='0',
 VER='1',
 VALUE='20.0',
 PACK_TYPE='0402',
 PART_NUMBER='G21796-173',
 LOCATION='R1T7',
 ROOM='SMBUS',
 CDS_LIB='mstr_discrete',
 CDS_PART_NAME='RES_0402-20.0,1%,1/16W,CHIP,G2A',
 PRIM_FILE='./archive_libs/mstr_discrete/res/chips/chips.prt';

PART_NAME
 R1T8 'RES_0402-20.0,1%,1/16W,CHIP,G2A':
 ROOM='SMBUS';

SECTION_NUMBER 1
 '@BASEBOARD_FAB2_LIB.BASEBOARD_FAB2(SCH_1):PAGE160_I4@MSTR_DISCRETE.RES(CHIPS)':
 C_PATH='@baseboard_fab2_lib.baseboard_fab2(sch_1):page160_i4@mstr_discrete.res(~
chips)',
 P_PATH='@baseboard_fab2_lib.baseboard_fab2(sch_1):page160_i4@mstr_discrete.res(~
chips)',
 PATH='I4',
 DRAWING='@BASEBOARD_FAB2_LIB.BASEBOARD_FAB2(SCH_1):PAGE160',
 WATTAGE='1/16W',
 TOLERANCE='1%',
 MATERIAL='CHIP',
 BOM_COST='SM_CONTROLLER',
 PHYS_PAGE='160',
 XY='(-3350,4600)',
 ROT='0',
 VER='1',
 VALUE='20.0',
 PACK_TYPE='0402',
 PART_NUMBER='G21796-173',
 LOCATION='R1T8',
 ROOM='SMBUS',
 CDS_LIB='mstr_discrete',
 CDS_PART_NAME='RES_0402-20.0,1%,1/16W,CHIP,G2A',
 PRIM_FILE='./archive_libs/mstr_discrete/res/chips/chips.prt';

PART_NAME
 R1T9 'RES_0402-22.1,1.0%,1/16W,CHIP,A':
 ROOM='P1V538_BMC_STBY_VR';

SECTION_NUMBER 1
 '@BASEBOARD_FAB2_LIB.BASEBOARD_FAB2(SCH_1):PAGE239_I72@MSTR_DISCRETE.RES(CHIPS)':
 C_PATH='@baseboard_fab2_lib.baseboard_fab2(sch_1):page239_i72@mstr_discrete.res~
(chips)',
 P_PATH='@baseboard_fab2_lib.baseboard_fab2(sch_1):page239_i72@mstr_discrete.res~
(chips)',
 PATH='I72',
 DRAWING='@BASEBOARD_FAB2_LIB.BASEBOARD_FAB2(SCH_1):PAGE239',
 WATTAGE='1/16W',
 TOLERANCE='1.0%',
 SEC_TYPE='0402',
 MATERIAL='CHIP',
 PHYS_PAGE='239',
 XY='(10700,4275)',
 ROT='0',
 VER='1',
 VALUE='22.1',
 PACK_TYPE='0402',
 PART_NUMBER='G21796-250',
 LOCATION='R1T9',
 ROOM='P1V538_BMC_STBY_VR',
 SEC='1',
 CDS_LIB='mstr_discrete',
 CDS_PART_NAME='RES_0402-22.1,1.0%,1/16W,CHIP,A',
 PRIM_FILE='./archive_libs/mstr_discrete/res/chips/chips.prt';

PART_NAME
 R1T10 'RES_0402-1.00K,1%,1/16W,CHIP,GA':
 ROOM='BMC_MISC';

SECTION_NUMBER 1
 '@BASEBOARD_FAB2_LIB.BASEBOARD_FAB2(SCH_1):PAGE164_I101@MSTR_DISCRETE.RES(CHIPS)':
 C_PATH='@baseboard_fab2_lib.baseboard_fab2(sch_1):page164_i101@mstr_discrete.re~
s(chips)',
 P_PATH='@baseboard_fab2_lib.baseboard_fab2(sch_1):page164_i101@mstr_discrete.re~
s(chips)',
 PATH='I101',
 DRAWING='@BASEBOARD_FAB2_LIB.BASEBOARD_FAB2(SCH_1):PAGE164',
 POP='NOPOP',
 WATTAGE='1/16W',
 TOLERANCE='1%',
 SEC_TYPE='0402',
 MATERIAL='CHIP',
 BOM_COST='SM_CONTROLLER',
 PHYS_PAGE='164',
 XY='(-6250,925)',
 ROT='0',
 VER='2',
 VALUE='1.00K',
 PACK_TYPE='0402',
 PART_NUMBER='G21796-026',
 LOCATION='R1T10',
 ROOM='BMC_MISC',
 SEC='1',
 CDS_LIB='mstr_discrete',
 CDS_PART_NAME='RES_0402-1.00K,1%,1/16W,CHIP,GA',
 PRIM_FILE='./archive_libs/mstr_discrete/res/chips/chips.prt';

PART_NAME
 R1T11 'RES_0402-1.00K,1%,1/16W,CHIP,GA':
 ROOM='BMC_MISC';

SECTION_NUMBER 1
 '@BASEBOARD_FAB2_LIB.BASEBOARD_FAB2(SCH_1):PAGE164_I7@MSTR_DISCRETE.RES(CHIPS)':
 C_PATH='@baseboard_fab2_lib.baseboard_fab2(sch_1):page164_i7@mstr_discrete.res(~
chips)',
 P_PATH='@baseboard_fab2_lib.baseboard_fab2(sch_1):page164_i7@mstr_discrete.res(~
chips)',
 PATH='I7',
 DRAWING='@BASEBOARD_FAB2_LIB.BASEBOARD_FAB2(SCH_1):PAGE164',
 WATTAGE='1/16W',
 TOLERANCE='1%',
 SEC_TYPE='0402',
 MATERIAL='CHIP',
 BOM_COST='SM_CONTROLLER',
 PHYS_PAGE='164',
 XY='(-6850,925)',
 ROT='0',
 VER='2',
 VALUE='1.00K',
 PACK_TYPE='0402',
 PART_NUMBER='G21796-026',
 LOCATION='R1T11',
 ROOM='BMC_MISC',
 SEC='1',
 CDS_LIB='mstr_discrete',
 CDS_PART_NAME='RES_0402-1.00K,1%,1/16W,CHIP,GA',
 PRIM_FILE='./archive_libs/mstr_discrete/res/chips/chips.prt';

PART_NAME
 R1T12 'RES_0402-1.00K,1%,1/16W,CHIP,GA':
 ROOM='BMC_MISC';

SECTION_NUMBER 1
 '@BASEBOARD_FAB2_LIB.BASEBOARD_FAB2(SCH_1):PAGE164_I53@MSTR_DISCRETE.RES(CHIPS)':
 C_PATH='@baseboard_fab2_lib.baseboard_fab2(sch_1):page164_i53@mstr_discrete.res~
(chips)',
 P_PATH='@baseboard_fab2_lib.baseboard_fab2(sch_1):page164_i53@mstr_discrete.res~
(chips)',
 PATH='I53',
 DRAWING='@BASEBOARD_FAB2_LIB.BASEBOARD_FAB2(SCH_1):PAGE164',
 POP='NOPOP',
 WATTAGE='1/16W',
 TOLERANCE='1%',
 SEC_TYPE='0402',
 MATERIAL='CHIP',
 BOM_COST='SM_CONTROLLER',
 PHYS_PAGE='164',
 XY='(-6550,925)',
 ROT='0',
 VER='2',
 VALUE='1.00K',
 PACK_TYPE='0402',
 PART_NUMBER='G21796-026',
 LOCATION='R1T12',
 ROOM='BMC_MISC',
 SEC='1',
 CDS_LIB='mstr_discrete',
 CDS_PART_NAME='RES_0402-1.00K,1%,1/16W,CHIP,GA',
 PRIM_FILE='./archive_libs/mstr_discrete/res/chips/chips.prt';

PART_NAME
 R1T15 'RES_0402-0.0,5%,1/16W,EMPTY,G2A':;

SECTION_NUMBER 1
 '@BASEBOARD_FAB2_LIB.BASEBOARD_FAB2(SCH_1):PAGE145_I100@MSTR_DISCRETE.RES(CHIPS)':
 C_PATH='@baseboard_fab2_lib.baseboard_fab2(sch_1):page145_i100@mstr_discrete.re~
s(chips)',
 P_PATH='@baseboard_fab2_lib.baseboard_fab2(sch_1):page145_i100@mstr_discrete.re~
s(chips)',
 PATH='I100',
 DRAWING='@BASEBOARD_FAB2_LIB.BASEBOARD_FAB2(SCH_1):PAGE145',
 WATTAGE='1/16W',
 TOLERANCE='5%',
 SEC_TYPE='0402',
 MATERIAL='EMPTY',
 PHYS_PAGE='145',
 XY='(-7300,-3975)',
 ROT='0',
 VER='1',
 VALUE='0.0',
 PACK_TYPE='0402',
 PART_NUMBER='G21497-005',
 LOCATION='R1T15',
 SEC='1',
 CDS_LIB='mstr_discrete',
 CDS_PART_NAME='RES_0402-0.0,5%,1/16W,EMPTY,G2A',
 PRIM_FILE='./archive_libs/mstr_discrete/res/chips/chips.prt';

PART_NAME
 R1T23 'RES_0402-0.0,5%,1/16W,EMPTY,G2A':;

SECTION_NUMBER 1
 '@BASEBOARD_FAB2_LIB.BASEBOARD_FAB2(SCH_1):PAGE145_I101@MSTR_DISCRETE.RES(CHIPS)':
 C_PATH='@baseboard_fab2_lib.baseboard_fab2(sch_1):page145_i101@mstr_discrete.re~
s(chips)',
 P_PATH='@baseboard_fab2_lib.baseboard_fab2(sch_1):page145_i101@mstr_discrete.re~
s(chips)',
 PATH='I101',
 DRAWING='@BASEBOARD_FAB2_LIB.BASEBOARD_FAB2(SCH_1):PAGE145',
 WATTAGE='1/16W',
 TOLERANCE='5%',
 SEC_TYPE='0402',
 MATERIAL='EMPTY',
 PHYS_PAGE='145',
 XY='(-7050,-4200)',
 ROT='5',
 VER='1',
 VALUE='0.0',
 PACK_TYPE='0402',
 PART_NUMBER='G21497-005',
 LOCATION='R1T23',
 SEC='1',
 CDS_LIB='mstr_discrete',
 CDS_PART_NAME='RES_0402-0.0,5%,1/16W,EMPTY,G2A',
 PRIM_FILE='./archive_libs/mstr_discrete/res/chips/chips.prt';

PART_NAME
 R1T24 'RES_0402-0.0,5%,1/16W,EMPTY,G2A':;

SECTION_NUMBER 1
 '@BASEBOARD_FAB2_LIB.BASEBOARD_FAB2(SCH_1):PAGE147_I129@MSTR_DISCRETE.RES(CHIPS)':
 C_PATH='@baseboard_fab2_lib.baseboard_fab2(sch_1):page147_i129@mstr_discrete.re~
s(chips)',
 P_PATH='@baseboard_fab2_lib.baseboard_fab2(sch_1):page147_i129@mstr_discrete.re~
s(chips)',
 PATH='I129',
 DRAWING='@BASEBOARD_FAB2_LIB.BASEBOARD_FAB2(SCH_1):PAGE147',
 WATTAGE='1/16W',
 TOLERANCE='5%',
 SEC_TYPE='0402',
 MATERIAL='EMPTY',
 PHYS_PAGE='147',
 XY='(-4100,1500)',
 ROT='0',
 VER='1',
 VALUE='0.0',
 PACK_TYPE='0402',
 PART_NUMBER='G21497-005',
 LOCATION='R1T24',
 SEC='1',
 CDS_LIB='mstr_discrete',
 CDS_PART_NAME='RES_0402-0.0,5%,1/16W,EMPTY,G2A',
 PRIM_FILE='./archive_libs/mstr_discrete/res/chips/chips.prt';

PART_NAME
 R1T25 'RES_0402-8.2K,1%,1/16W,CHIP,G2A':
 ROOM='BMC';

SECTION_NUMBER 1
 '@BASEBOARD_FAB2_LIB.BASEBOARD_FAB2(SCH_1):PAGE146_I35@MSTR_DISCRETE.RES(CHIPS)':
 C_PATH='@baseboard_fab2_lib.baseboard_fab2(sch_1):page146_i35@mstr_discrete.res~
(chips)',
 P_PATH='@baseboard_fab2_lib.baseboard_fab2(sch_1):page146_i35@mstr_discrete.res~
(chips)',
 PATH='I35',
 DRAWING='@BASEBOARD_FAB2_LIB.BASEBOARD_FAB2(SCH_1):PAGE146',
 WATTAGE='1/16W',
 TOLERANCE='1%',
 SEC_TYPE='0402',
 MATERIAL='CHIP',
 BOM_COST='SM_CONTROLLER',
 PHYS_PAGE='146',
 XY='(-850,4150)',
 ROT='1',
 VER='2',
 VALUE='8.2K',
 PACK_TYPE='0402',
 PART_NUMBER='G21796-345',
 LOCATION='R1T25',
 ROOM='BMC',
 SEC='1',
 CDS_LIB='mstr_discrete',
 CDS_PART_NAME='RES_0402-8.2K,1%,1/16W,CHIP,G2A',
 PRIM_FILE='./archive_libs/mstr_discrete/res/chips/chips.prt';

PART_NAME
 R1T26 'RES_0402-8.2K,1%,1/16W,CHIP,G2A':
 ROOM='BMC';

SECTION_NUMBER 1
 '@BASEBOARD_FAB2_LIB.BASEBOARD_FAB2(SCH_1):PAGE146_I37@MSTR_DISCRETE.RES(CHIPS)':
 C_PATH='@baseboard_fab2_lib.baseboard_fab2(sch_1):page146_i37@mstr_discrete.res~
(chips)',
 P_PATH='@baseboard_fab2_lib.baseboard_fab2(sch_1):page146_i37@mstr_discrete.res~
(chips)',
 PATH='I37',
 DRAWING='@BASEBOARD_FAB2_LIB.BASEBOARD_FAB2(SCH_1):PAGE146',
 WATTAGE='1/16W',
 TOLERANCE='1%',
 SEC_TYPE='0402',
 MATERIAL='CHIP',
 BOM_COST='SM_CONTROLLER',
 PHYS_PAGE='146',
 XY='(-550,4200)',
 ROT='1',
 VER='2',
 VALUE='8.2K',
 PACK_TYPE='0402',
 PART_NUMBER='G21796-345',
 LOCATION='R1T26',
 ROOM='BMC',
 SEC='1',
 CDS_LIB='mstr_discrete',
 CDS_PART_NAME='RES_0402-8.2K,1%,1/16W,CHIP,G2A',
 PRIM_FILE='./archive_libs/mstr_discrete/res/chips/chips.prt';

PART_NAME
 R1T27 'RES_0402-240,1.0%,1/16W,CHIP,GA':
 ROOM='BMC_MEMORY';

SECTION_NUMBER 1
 '@BASEBOARD_FAB2_LIB.BASEBOARD_FAB2(SCH_1):PAGE143_I58@MSTR_DISCRETE.RES(CHIPS)':
 C_PATH='@baseboard_fab2_lib.baseboard_fab2(sch_1):page143_i58@mstr_discrete.res~
(chips)',
 P_PATH='@baseboard_fab2_lib.baseboard_fab2(sch_1):page143_i58@mstr_discrete.res~
(chips)',
 PATH='I58',
 DRAWING='@BASEBOARD_FAB2_LIB.BASEBOARD_FAB2(SCH_1):PAGE143',
 WATTAGE='1/16W',
 TOLERANCE='1.0%',
 SEC_TYPE='0402',
 MATERIAL='CHIP',
 BOM_COST='SM_MEM',
 PHYS_PAGE='143',
 XY='(-11000,-2150)',
 ROT='7',
 VER='2',
 VALUE='240',
 PACK_TYPE='0402',
 PART_NUMBER='G21796-294',
 LOCATION='R1T27',
 ROOM='BMC_MEMORY',
 SEC='1',
 CDS_LIB='mstr_discrete',
 CDS_PART_NAME='RES_0402-240,1.0%,1/16W,CHIP,GA',
 PRIM_FILE='./archive_libs/mstr_discrete/res/chips/chips.prt';

PART_NAME
 R1T28 'RES_0402-49.9,1%,1/16W,CHIP,G2A':
 ROOM='CPU0';

SECTION_NUMBER 1
 '@BASEBOARD_FAB2_LIB.BASEBOARD_FAB2(SCH_1):PAGE151_I279@MSTR_DISCRETE.RES(CHIPS)':
 C_PATH='@baseboard_fab2_lib.baseboard_fab2(sch_1):page151_i279@mstr_discrete.re~
s(chips)',
 P_PATH='@baseboard_fab2_lib.baseboard_fab2(sch_1):page151_i279@mstr_discrete.re~
s(chips)',
 PATH='I279',
 DRAWING='@BASEBOARD_FAB2_LIB.BASEBOARD_FAB2(SCH_1):PAGE151',
 WATTAGE='1/16W',
 TOLERANCE='1%',
 SEC_TYPE='0402',
 MATERIAL='CHIP',
 BOM_COST='PROC_SOCKET',
 PHYS_PAGE='151',
 XY='(1250,-1950)',
 ROT='0',
 VER='1',
 VALUE='49.9',
 PACK_TYPE='0402',
 PART_NUMBER='G21796-047',
 LOCATION='R1T28',
 ROOM='CPU0',
 SEC='1',
 CDS_LIB='mstr_discrete',
 CDS_PART_NAME='RES_0402-49.9,1%,1/16W,CHIP,G2A',
 PRIM_FILE='./archive_libs/mstr_discrete/res/chips/chips.prt';

PART_NAME
 R1T29 'RES_0402-1.00K,1%,1/16W,CHIP,GA':
 ROOM='BMC_MEMORY';

SECTION_NUMBER 1
 '@BASEBOARD_FAB2_LIB.BASEBOARD_FAB2(SCH_1):PAGE151_I202@MSTR_DISCRETE.RES(CHIPS)':
 C_PATH='@baseboard_fab2_lib.baseboard_fab2(sch_1):page151_i202@mstr_discrete.re~
s(chips)',
 P_PATH='@baseboard_fab2_lib.baseboard_fab2(sch_1):page151_i202@mstr_discrete.re~
s(chips)',
 PATH='I202',
 DRAWING='@BASEBOARD_FAB2_LIB.BASEBOARD_FAB2(SCH_1):PAGE151',
 WATTAGE='1/16W',
 TOLERANCE='1%',
 SEC_TYPE='0402',
 MATERIAL='CHIP',
 BOM_COST='SM_MEM',
 PHYS_PAGE='151',
 XY='(-1675,-2000)',
 ROT='0',
 VER='2',
 VALUE='1.00K',
 PACK_TYPE='0402',
 PART_NUMBER='G21796-026',
 LOCATION='R1T29',
 ROOM='BMC_MEMORY',
 SEC='1',
 CDS_LIB='mstr_discrete',
 CDS_PART_NAME='RES_0402-1.00K,1%,1/16W,CHIP,GA',
 PRIM_FILE='./archive_libs/mstr_discrete/res/chips/chips.prt';

PART_NAME
 R1T30 'RES_0402-1.00K,1%,1/16W,CHIP,GA':
 ROOM='BMC_MEMORY';

SECTION_NUMBER 1
 '@BASEBOARD_FAB2_LIB.BASEBOARD_FAB2(SCH_1):PAGE151_I201@MSTR_DISCRETE.RES(CHIPS)':
 C_PATH='@baseboard_fab2_lib.baseboard_fab2(sch_1):page151_i201@mstr_discrete.re~
s(chips)',
 P_PATH='@baseboard_fab2_lib.baseboard_fab2(sch_1):page151_i201@mstr_discrete.re~
s(chips)',
 PATH='I201',
 DRAWING='@BASEBOARD_FAB2_LIB.BASEBOARD_FAB2(SCH_1):PAGE151',
 WATTAGE='1/16W',
 TOLERANCE='1%',
 SEC_TYPE='0402',
 MATERIAL='CHIP',
 BOM_COST='SM_MEM',
 PHYS_PAGE='151',
 XY='(-1675,-1575)',
 ROT='0',
 VER='2',
 VALUE='1.00K',
 PACK_TYPE='0402',
 PART_NUMBER='G21796-026',
 LOCATION='R1T30',
 ROOM='BMC_MEMORY',
 SEC='1',
 CDS_LIB='mstr_discrete',
 CDS_PART_NAME='RES_0402-1.00K,1%,1/16W,CHIP,GA',
 PRIM_FILE='./archive_libs/mstr_discrete/res/chips/chips.prt';

PART_NAME
 R1T32 'RES_0603-0,5.0%,1/10W,CHIP,G22A':
 GROUP='NI_I210&RJ45',
 ROOM='NIC_SPRV';

SECTION_NUMBER 1
 '@BASEBOARD_FAB2_LIB.BASEBOARD_FAB2(SCH_1):PAGE139_I238@MSTR_DISCRETE.RES(CHIPS)':
 C_PATH='@baseboard_fab2_lib.baseboard_fab2(sch_1):page139_i238@mstr_discrete.re~
s(chips)',
 P_PATH='@baseboard_fab2_lib.baseboard_fab2(sch_1):page139_i238@mstr_discrete.re~
s(chips)',
 PATH='I238',
 DRAWING='@BASEBOARD_FAB2_LIB.BASEBOARD_FAB2(SCH_1):PAGE139',
 WATTAGE='1/10W',
 TOLERANCE='5.0%',
 SEC_TYPE='0603',
 MATERIAL='CHIP',
 BOM_COST='NT_GBE_BASE',
 PHYS_PAGE='139',
 XY='(-5800,3875)',
 ROT='0',
 VER='1',
 VALUE='0',
 PACK_TYPE='0603',
 PART_NUMBER='G22178-002',
 LOCATION='R1T32',
 ROOM='NIC_SPRV',
 GROUP='NI_I210&RJ45',
 SEC='1',
 CDS_LIB='mstr_discrete',
 CDS_PART_NAME='RES_0603-0,5.0%,1/10W,CHIP,G22A',
 PRIM_FILE='./archive_libs/mstr_discrete/res/chips/chips.prt';

PART_NAME
 R1T33 'RES_0603-0,5.0%,1/10W,EMPTY,G2A':
 GROUP='NI_I210&RJ45',
 ROOM='NIC_SPRV';

SECTION_NUMBER 1
 '@BASEBOARD_FAB2_LIB.BASEBOARD_FAB2(SCH_1):PAGE139_I240@MSTR_DISCRETE.RES(CHIPS)':
 C_PATH='@baseboard_fab2_lib.baseboard_fab2(sch_1):page139_i240@mstr_discrete.re~
s(chips)',
 P_PATH='@baseboard_fab2_lib.baseboard_fab2(sch_1):page139_i240@mstr_discrete.re~
s(chips)',
 PATH='I240',
 DRAWING='@BASEBOARD_FAB2_LIB.BASEBOARD_FAB2(SCH_1):PAGE139',
 WATTAGE='1/10W',
 TOLERANCE='5.0%',
 SEC_TYPE='0603',
 MATERIAL='EMPTY',
 BOM_COST='NT_GBE_BASE',
 PHYS_PAGE='139',
 XY='(-5800,3725)',
 ROT='0',
 VER='1',
 VALUE='0',
 PACK_TYPE='0603',
 PART_NUMBER='G22178-002',
 LOCATION='R1T33',
 ROOM='NIC_SPRV',
 GROUP='NI_I210&RJ45',
 SEC='1',
 CDS_LIB='mstr_discrete',
 CDS_PART_NAME='RES_0603-0,5.0%,1/10W,EMPTY,G2A',
 PRIM_FILE='./archive_libs/mstr_discrete/res/chips/chips.prt';

PART_NAME
 R1T34 'RES_0603-0,5.0%,1/10W,CHIP,G22A':
 GROUP='NI_I210&RJ45',
 ROOM='NIC_SPRV';

SECTION_NUMBER 1
 '@BASEBOARD_FAB2_LIB.BASEBOARD_FAB2(SCH_1):PAGE139_I239@MSTR_DISCRETE.RES(CHIPS)':
 C_PATH='@baseboard_fab2_lib.baseboard_fab2(sch_1):page139_i239@mstr_discrete.re~
s(chips)',
 P_PATH='@baseboard_fab2_lib.baseboard_fab2(sch_1):page139_i239@mstr_discrete.re~
s(chips)',
 PATH='I239',
 DRAWING='@BASEBOARD_FAB2_LIB.BASEBOARD_FAB2(SCH_1):PAGE139',
 WATTAGE='1/10W',
 TOLERANCE='5.0%',
 SEC_TYPE='0603',
 MATERIAL='CHIP',
 BOM_COST='NT_GBE_BASE',
 PHYS_PAGE='139',
 XY='(-5600,3525)',
 ROT='0',
 VER='1',
 VALUE='0',
 PACK_TYPE='0603',
 PART_NUMBER='G22178-002',
 LOCATION='R1T34',
 ROOM='NIC_SPRV',
 GROUP='NI_I210&RJ45',
 SEC='1',
 CDS_LIB='mstr_discrete',
 CDS_PART_NAME='RES_0603-0,5.0%,1/10W,CHIP,G22A',
 PRIM_FILE='./archive_libs/mstr_discrete/res/chips/chips.prt';

PART_NAME
 R1T35 'RES_0402-0.0,5%,1/16W,EMPTY,G2A':;

SECTION_NUMBER 1
 '@BASEBOARD_FAB2_LIB.BASEBOARD_FAB2(SCH_1):PAGE93_I135@MSTR_DISCRETE.RES(CHIPS)':
 C_PATH='@baseboard_fab2_lib.baseboard_fab2(sch_1):page93_i135@mstr_discrete.res~
(chips)',
 P_PATH='@baseboard_fab2_lib.baseboard_fab2(sch_1):page93_i135@mstr_discrete.res~
(chips)',
 PATH='I135',
 DRAWING='@BASEBOARD_FAB2_LIB.BASEBOARD_FAB2(SCH_1):PAGE93',
 WATTAGE='1/16W',
 TOLERANCE='5%',
 SEC_TYPE='0402',
 MATERIAL='EMPTY',
 PHYS_PAGE='93',
 XY='(-2225,475)',
 ROT='0',
 VER='1',
 VALUE='0.0',
 PACK_TYPE='0402',
 PART_NUMBER='G21497-005',
 LOCATION='R1T35',
 SEC='1',
 CDS_LIB='mstr_discrete',
 CDS_PART_NAME='RES_0402-0.0,5%,1/16W,EMPTY,G2A',
 PRIM_FILE='./archive_libs/mstr_discrete/res/chips/chips.prt';

PART_NAME
 R1T36 'RES_0402-0.0,5%,1/16W,CHIP,G21A':;

SECTION_NUMBER 1
 '@BASEBOARD_FAB2_LIB.BASEBOARD_FAB2(SCH_1):PAGE93_I122@MSTR_DISCRETE.RES(CHIPS)':
 C_PATH='@baseboard_fab2_lib.baseboard_fab2(sch_1):page93_i122@mstr_discrete.res~
(chips)',
 P_PATH='@baseboard_fab2_lib.baseboard_fab2(sch_1):page93_i122@mstr_discrete.res~
(chips)',
 PATH='I122',
 DRAWING='@BASEBOARD_FAB2_LIB.BASEBOARD_FAB2(SCH_1):PAGE93',
 WATTAGE='1/16W',
 TOLERANCE='5%',
 SEC_TYPE='0402',
 MATERIAL='CHIP',
 PHYS_PAGE='93',
 XY='(-2225,675)',
 ROT='0',
 VER='1',
 VALUE='0.0',
 PACK_TYPE='0402',
 PART_NUMBER='G21497-005',
 LOCATION='R1T36',
 SEC='1',
 CDS_LIB='mstr_discrete',
 CDS_PART_NAME='RES_0402-0.0,5%,1/16W,CHIP,G21A',
 PRIM_FILE='./archive_libs/mstr_discrete/res/chips/chips.prt';

PART_NAME
 R1T37 'RES_0402-0.0,5%,1/16W,CHIP,G21A':;

SECTION_NUMBER 1
 '@BASEBOARD_FAB2_LIB.BASEBOARD_FAB2(SCH_1):PAGE93_I123@MSTR_DISCRETE.RES(CHIPS)':
 C_PATH='@baseboard_fab2_lib.baseboard_fab2(sch_1):page93_i123@mstr_discrete.res~
(chips)',
 P_PATH='@baseboard_fab2_lib.baseboard_fab2(sch_1):page93_i123@mstr_discrete.res~
(chips)',
 PATH='I123',
 DRAWING='@BASEBOARD_FAB2_LIB.BASEBOARD_FAB2(SCH_1):PAGE93',
 WATTAGE='1/16W',
 TOLERANCE='5%',
 SEC_TYPE='0402',
 MATERIAL='CHIP',
 PHYS_PAGE='93',
 XY='(-2225,275)',
 ROT='0',
 VER='1',
 VALUE='0.0',
 PACK_TYPE='0402',
 PART_NUMBER='G21497-005',
 LOCATION='R1T37',
 SEC='1',
 CDS_LIB='mstr_discrete',
 CDS_PART_NAME='RES_0402-0.0,5%,1/16W,CHIP,G21A',
 PRIM_FILE='./archive_libs/mstr_discrete/res/chips/chips.prt';

PART_NAME
 R1T38 'RES_0402-0.0,5%,1/16W,EMPTY,G2A':;

SECTION_NUMBER 1
 '@BASEBOARD_FAB2_LIB.BASEBOARD_FAB2(SCH_1):PAGE93_I137@MSTR_DISCRETE.RES(CHIPS)':
 C_PATH='@baseboard_fab2_lib.baseboard_fab2(sch_1):page93_i137@mstr_discrete.res~
(chips)',
 P_PATH='@baseboard_fab2_lib.baseboard_fab2(sch_1):page93_i137@mstr_discrete.res~
(chips)',
 PATH='I137',
 DRAWING='@BASEBOARD_FAB2_LIB.BASEBOARD_FAB2(SCH_1):PAGE93',
 WATTAGE='1/16W',
 TOLERANCE='5%',
 SEC_TYPE='0402',
 MATERIAL='EMPTY',
 PHYS_PAGE='93',
 XY='(-2225,75)',
 ROT='0',
 VER='1',
 VALUE='0.0',
 PACK_TYPE='0402',
 PART_NUMBER='G21497-005',
 LOCATION='R1T38',
 SEC='1',
 CDS_LIB='mstr_discrete',
 CDS_PART_NAME='RES_0402-0.0,5%,1/16W,EMPTY,G2A',
 PRIM_FILE='./archive_libs/mstr_discrete/res/chips/chips.prt';

PART_NAME
 R1T40 'RES_0402-49.9,1%,1/16W,CHIP,G2A':
 ROOM='CPU0';

SECTION_NUMBER 1
 '@BASEBOARD_FAB2_LIB.BASEBOARD_FAB2(SCH_1):PAGE151_I278@MSTR_DISCRETE.RES(CHIPS)':
 C_PATH='@baseboard_fab2_lib.baseboard_fab2(sch_1):page151_i278@mstr_discrete.re~
s(chips)',
 P_PATH='@baseboard_fab2_lib.baseboard_fab2(sch_1):page151_i278@mstr_discrete.re~
s(chips)',
 PATH='I278',
 DRAWING='@BASEBOARD_FAB2_LIB.BASEBOARD_FAB2(SCH_1):PAGE151',
 WATTAGE='1/16W',
 TOLERANCE='1%',
 SEC_TYPE='0402',
 MATERIAL='CHIP',
 BOM_COST='PROC_SOCKET',
 PHYS_PAGE='151',
 XY='(1250,-1550)',
 ROT='0',
 VER='1',
 VALUE='49.9',
 PACK_TYPE='0402',
 PART_NUMBER='G21796-047',
 LOCATION='R1T40',
 ROOM='CPU0',
 SEC='1',
 CDS_LIB='mstr_discrete',
 CDS_PART_NAME='RES_0402-49.9,1%,1/16W,CHIP,G2A',
 PRIM_FILE='./archive_libs/mstr_discrete/res/chips/chips.prt';

PART_NAME
 R1U1 'RES_0402-100.0K,1%,1/16W,CHIP,A':;

SECTION_NUMBER 1
 '@BASEBOARD_FAB2_LIB.BASEBOARD_FAB2(SCH_1):PAGE147_I61@MSTR_DISCRETE.RES(CHIPS)':
 C_PATH='@baseboard_fab2_lib.baseboard_fab2(sch_1):page147_i61@mstr_discrete.res~
(chips)',
 P_PATH='@baseboard_fab2_lib.baseboard_fab2(sch_1):page147_i61@mstr_discrete.res~
(chips)',
 PATH='I61',
 DRAWING='@BASEBOARD_FAB2_LIB.BASEBOARD_FAB2(SCH_1):PAGE147',
 WATTAGE='1/16W',
 TOLERANCE='1%',
 SEC_TYPE='0402',
 MATERIAL='CHIP',
 PHYS_PAGE='147',
 XY='(-3500,1950)',
 ROT='0',
 VER='2',
 VALUE='100.0K',
 PACK_TYPE='0402',
 PART_NUMBER='G21796-010',
 LOCATION='R1U1',
 SEC='1',
 CDS_LIB='mstr_discrete',
 CDS_PART_NAME='RES_0402-100.0K,1%,1/16W,CHIP,A',
 PRIM_FILE='./archive_libs/mstr_discrete/res/chips/chips.prt';

PART_NAME
 R1U2 'RES_0402-100.0K,1%,1/16W,CHIP,A':;

SECTION_NUMBER 1
 '@BASEBOARD_FAB2_LIB.BASEBOARD_FAB2(SCH_1):PAGE147_I62@MSTR_DISCRETE.RES(CHIPS)':
 C_PATH='@baseboard_fab2_lib.baseboard_fab2(sch_1):page147_i62@mstr_discrete.res~
(chips)',
 P_PATH='@baseboard_fab2_lib.baseboard_fab2(sch_1):page147_i62@mstr_discrete.res~
(chips)',
 PATH='I62',
 DRAWING='@BASEBOARD_FAB2_LIB.BASEBOARD_FAB2(SCH_1):PAGE147',
 WATTAGE='1/16W',
 TOLERANCE='1%',
 SEC_TYPE='0402',
 MATERIAL='CHIP',
 PHYS_PAGE='147',
 XY='(-3800,1950)',
 ROT='0',
 VER='2',
 VALUE='100.0K',
 PACK_TYPE='0402',
 PART_NUMBER='G21796-010',
 LOCATION='R1U2',
 SEC='1',
 CDS_LIB='mstr_discrete',
 CDS_PART_NAME='RES_0402-100.0K,1%,1/16W,CHIP,A',
 PRIM_FILE='./archive_libs/mstr_discrete/res/chips/chips.prt';

PART_NAME
 R1U4 'RES_0402-100.0K,1%,1/16W,CHIP,A':;

SECTION_NUMBER 1
 '@BASEBOARD_FAB2_LIB.BASEBOARD_FAB2(SCH_1):PAGE147_I65@MSTR_DISCRETE.RES(CHIPS)':
 C_PATH='@baseboard_fab2_lib.baseboard_fab2(sch_1):page147_i65@mstr_discrete.res~
(chips)',
 P_PATH='@baseboard_fab2_lib.baseboard_fab2(sch_1):page147_i65@mstr_discrete.res~
(chips)',
 PATH='I65',
 DRAWING='@BASEBOARD_FAB2_LIB.BASEBOARD_FAB2(SCH_1):PAGE147',
 WATTAGE='1/16W',
 TOLERANCE='1%',
 SEC_TYPE='0402',
 MATERIAL='CHIP',
 PHYS_PAGE='147',
 XY='(-4100,1950)',
 ROT='0',
 VER='2',
 VALUE='100.0K',
 PACK_TYPE='0402',
 PART_NUMBER='G21796-010',
 LOCATION='R1U4',
 SEC='1',
 CDS_LIB='mstr_discrete',
 CDS_PART_NAME='RES_0402-100.0K,1%,1/16W,CHIP,A',
 PRIM_FILE='./archive_libs/mstr_discrete/res/chips/chips.prt';

PART_NAME
 R1U5 'RES_0402-100.0K,1%,1/16W,CHIP,A':;

SECTION_NUMBER 1
 '@BASEBOARD_FAB2_LIB.BASEBOARD_FAB2(SCH_1):PAGE147_I66@MSTR_DISCRETE.RES(CHIPS)':
 C_PATH='@baseboard_fab2_lib.baseboard_fab2(sch_1):page147_i66@mstr_discrete.res~
(chips)',
 P_PATH='@baseboard_fab2_lib.baseboard_fab2(sch_1):page147_i66@mstr_discrete.res~
(chips)',
 PATH='I66',
 DRAWING='@BASEBOARD_FAB2_LIB.BASEBOARD_FAB2(SCH_1):PAGE147',
 WATTAGE='1/16W',
 TOLERANCE='1%',
 SEC_TYPE='0402',
 MATERIAL='CHIP',
 PHYS_PAGE='147',
 XY='(-4400,1950)',
 ROT='0',
 VER='2',
 VALUE='100.0K',
 PACK_TYPE='0402',
 PART_NUMBER='G21796-010',
 LOCATION='R1U5',
 SEC='1',
 CDS_LIB='mstr_discrete',
 CDS_PART_NAME='RES_0402-100.0K,1%,1/16W,CHIP,A',
 PRIM_FILE='./archive_libs/mstr_discrete/res/chips/chips.prt';

PART_NAME
 R1U6 'RES_0402-10.0K,1%,1/16W,CHIP,GA':
 ROOM='SB_BMC_BPI_MUX';

SECTION_NUMBER 1
 '@BASEBOARD_FAB2_LIB.BASEBOARD_FAB2(SCH_1):PAGE154_I128@MSTR_DISCRETE.RES(CHIPS)':
 C_PATH='@baseboard_fab2_lib.baseboard_fab2(sch_1):page154_i128@mstr_discrete.re~
s(chips)',
 P_PATH='@baseboard_fab2_lib.baseboard_fab2(sch_1):page154_i128@mstr_discrete.re~
s(chips)',
 PATH='I128',
 DRAWING='@BASEBOARD_FAB2_LIB.BASEBOARD_FAB2(SCH_1):PAGE154',
 WATTAGE='1/16W',
 TOLERANCE='1%',
 SEC_TYPE='0402',
 MATERIAL='CHIP',
 BOM_COST='MIO_BIOS_MEM',
 PHYS_PAGE='154',
 XY='(-6250,2750)',
 ROT='0',
 VER='2',
 VALUE='10.0K',
 PACK_TYPE='0402',
 PART_NUMBER='G21796-016',
 LOCATION='R1U6',
 ROOM='SB_BMC_BPI_MUX',
 SEC='1',
 CDS_LIB='mstr_discrete',
 CDS_PART_NAME='RES_0402-10.0K,1%,1/16W,CHIP,GA',
 PRIM_FILE='./archive_libs/mstr_discrete/res/chips/chips.prt';

PART_NAME
 R1U7 'RES_0402-10.0K,1%,1/16W,CHIP,GA':
 ROOM='BMC';

SECTION_NUMBER 1
 '@BASEBOARD_FAB2_LIB.BASEBOARD_FAB2(SCH_1):PAGE146_I78@MSTR_DISCRETE.RES(CHIPS)':
 C_PATH='@baseboard_fab2_lib.baseboard_fab2(sch_1):page146_i78@mstr_discrete.res~
(chips)',
 P_PATH='@baseboard_fab2_lib.baseboard_fab2(sch_1):page146_i78@mstr_discrete.res~
(chips)',
 PATH='I78',
 DRAWING='@BASEBOARD_FAB2_LIB.BASEBOARD_FAB2(SCH_1):PAGE146',
 WATTAGE='1/16W',
 TOLERANCE='1%',
 SEC_TYPE='0402',
 MATERIAL='CHIP',
 BOM_COST='SM_CONTROLLER',
 PHYS_PAGE='146',
 XY='(-6350,2650)',
 ROT='0',
 VER='1',
 VALUE='10.0K',
 PACK_TYPE='0402',
 PART_NUMBER='G21796-016',
 LOCATION='R1U7',
 ROOM='BMC',
 SEC='1',
 CDS_LIB='mstr_discrete',
 CDS_PART_NAME='RES_0402-10.0K,1%,1/16W,CHIP,GA',
 PRIM_FILE='./archive_libs/mstr_discrete/res/chips/chips.prt';

PART_NAME
 R1U8 'RES_0402-0.0,5%,1/16W,CHIP,G21A':
 ROOM='SMBUS';

SECTION_NUMBER 1
 '@BASEBOARD_FAB2_LIB.BASEBOARD_FAB2(SCH_1):PAGE159_I223@MSTR_DISCRETE.RES(CHIPS)':
 C_PATH='@baseboard_fab2_lib.baseboard_fab2(sch_1):page159_i223@mstr_discrete.re~
s(chips)',
 P_PATH='@baseboard_fab2_lib.baseboard_fab2(sch_1):page159_i223@mstr_discrete.re~
s(chips)',
 PATH='I223',
 DRAWING='@BASEBOARD_FAB2_LIB.BASEBOARD_FAB2(SCH_1):PAGE159',
 WATTAGE='1/16W',
 TOLERANCE='5%',
 MATERIAL='CHIP',
 BOM_COST='SM_CONTROLLER',
 PHYS_PAGE='159',
 XY='(700,1775)',
 ROT='0',
 VER='1',
 VALUE='0.0',
 PACK_TYPE='0402',
 PART_NUMBER='G21497-005',
 LOCATION='R1U8',
 ROOM='SMBUS',
 CDS_LIB='mstr_discrete',
 CDS_PART_NAME='RES_0402-0.0,5%,1/16W,CHIP,G21A',
 PRIM_FILE='./archive_libs/mstr_discrete/res/chips/chips.prt';

PART_NAME
 R1U9 'RES_0402-20.0,1%,1/16W,CHIP,G2A':
 ROOM='SMBUS';

SECTION_NUMBER 1
 '@BASEBOARD_FAB2_LIB.BASEBOARD_FAB2(SCH_1):PAGE159_I232@MSTR_DISCRETE.RES(CHIPS)':
 C_PATH='@baseboard_fab2_lib.baseboard_fab2(sch_1):page159_i232@mstr_discrete.re~
s(chips)',
 P_PATH='@baseboard_fab2_lib.baseboard_fab2(sch_1):page159_i232@mstr_discrete.re~
s(chips)',
 PATH='I232',
 DRAWING='@BASEBOARD_FAB2_LIB.BASEBOARD_FAB2(SCH_1):PAGE159',
 WATTAGE='1/16W',
 TOLERANCE='1%',
 MATERIAL='CHIP',
 BOM_COST='SM_CONTROLLER',
 PHYS_PAGE='159',
 XY='(-3175,4775)',
 ROT='0',
 VER='1',
 VALUE='20.0',
 PACK_TYPE='0402',
 PART_NUMBER='G21796-173',
 LOCATION='R1U9',
 ROOM='SMBUS',
 CDS_LIB='mstr_discrete',
 CDS_PART_NAME='RES_0402-20.0,1%,1/16W,CHIP,G2A',
 PRIM_FILE='./archive_libs/mstr_discrete/res/chips/chips.prt';

PART_NAME
 R1U10 'RES_0402-20.0,1%,1/16W,CHIP,G2A':
 ROOM='SMBUS';

SECTION_NUMBER 1
 '@BASEBOARD_FAB2_LIB.BASEBOARD_FAB2(SCH_1):PAGE159_I233@MSTR_DISCRETE.RES(CHIPS)':
 C_PATH='@baseboard_fab2_lib.baseboard_fab2(sch_1):page159_i233@mstr_discrete.re~
s(chips)',
 P_PATH='@baseboard_fab2_lib.baseboard_fab2(sch_1):page159_i233@mstr_discrete.re~
s(chips)',
 PATH='I233',
 DRAWING='@BASEBOARD_FAB2_LIB.BASEBOARD_FAB2(SCH_1):PAGE159',
 WATTAGE='1/16W',
 TOLERANCE='1%',
 MATERIAL='CHIP',
 BOM_COST='SM_CONTROLLER',
 PHYS_PAGE='159',
 XY='(-3175,4950)',
 ROT='0',
 VER='1',
 VALUE='20.0',
 PACK_TYPE='0402',
 PART_NUMBER='G21796-173',
 LOCATION='R1U10',
 ROOM='SMBUS',
 CDS_LIB='mstr_discrete',
 CDS_PART_NAME='RES_0402-20.0,1%,1/16W,CHIP,G2A',
 PRIM_FILE='./archive_libs/mstr_discrete/res/chips/chips.prt';

PART_NAME
 R1U11 'RES_0402-0.0,5%,1/16W,CHIP,G21A':
 ROOM='SMBUS';

SECTION_NUMBER 1
 '@BASEBOARD_FAB2_LIB.BASEBOARD_FAB2(SCH_1):PAGE159_I222@MSTR_DISCRETE.RES(CHIPS)':
 C_PATH='@baseboard_fab2_lib.baseboard_fab2(sch_1):page159_i222@mstr_discrete.re~
s(chips)',
 P_PATH='@baseboard_fab2_lib.baseboard_fab2(sch_1):page159_i222@mstr_discrete.re~
s(chips)',
 PATH='I222',
 DRAWING='@BASEBOARD_FAB2_LIB.BASEBOARD_FAB2(SCH_1):PAGE159',
 WATTAGE='1/16W',
 TOLERANCE='5%',
 MATERIAL='CHIP',
 BOM_COST='SM_CONTROLLER',
 PHYS_PAGE='159',
 XY='(700,1600)',
 ROT='0',
 VER='1',
 VALUE='0.0',
 PACK_TYPE='0402',
 PART_NUMBER='G21497-005',
 LOCATION='R1U11',
 ROOM='SMBUS',
 CDS_LIB='mstr_discrete',
 CDS_PART_NAME='RES_0402-0.0,5%,1/16W,CHIP,G21A',
 PRIM_FILE='./archive_libs/mstr_discrete/res/chips/chips.prt';

PART_NAME
 R1U12 'RES_0402-51,5.0%,1/16W,CHIP,G2A':
 ROOM='BMC';

SECTION_NUMBER 1
 '@BASEBOARD_FAB2_LIB.BASEBOARD_FAB2(SCH_1):PAGE144_I59@MSTR_DISCRETE.RES(CHIPS)':
 C_PATH='@baseboard_fab2_lib.baseboard_fab2(sch_1):page144_i59@mstr_discrete.res~
(chips)',
 P_PATH='@baseboard_fab2_lib.baseboard_fab2(sch_1):page144_i59@mstr_discrete.res~
(chips)',
 PATH='I59',
 DRAWING='@BASEBOARD_FAB2_LIB.BASEBOARD_FAB2(SCH_1):PAGE144',
 WATTAGE='1/16W',
 TOLERANCE='5.0%',
 SEC_TYPE='0402',
 MATERIAL='CHIP',
 PHYS_PAGE='144',
 XY='(-1750,-2150)',
 ROT='0',
 VER='1',
 VALUE='51',
 PACK_TYPE='0402',
 PART_NUMBER='G21497-048',
 LOCATION='R1U12',
 ROOM='BMC',
 SEC='1',
 CDS_LIB='mstr_discrete',
 CDS_PART_NAME='RES_0402-51,5.0%,1/16W,CHIP,G2A',
 PRIM_FILE='./archive_libs/mstr_discrete/res/chips/chips.prt';

PART_NAME
 R1U13 'RES_0402-51,5.0%,1/16W,CHIP,G2A':
 ROOM='BMC';

SECTION_NUMBER 1
 '@BASEBOARD_FAB2_LIB.BASEBOARD_FAB2(SCH_1):PAGE144_I58@MSTR_DISCRETE.RES(CHIPS)':
 C_PATH='@baseboard_fab2_lib.baseboard_fab2(sch_1):page144_i58@mstr_discrete.res~
(chips)',
 P_PATH='@baseboard_fab2_lib.baseboard_fab2(sch_1):page144_i58@mstr_discrete.res~
(chips)',
 PATH='I58',
 DRAWING='@BASEBOARD_FAB2_LIB.BASEBOARD_FAB2(SCH_1):PAGE144',
 WATTAGE='1/16W',
 TOLERANCE='5.0%',
 SEC_TYPE='0402',
 MATERIAL='CHIP',
 PHYS_PAGE='144',
 XY='(-1750,-2050)',
 ROT='0',
 VER='1',
 VALUE='51',
 PACK_TYPE='0402',
 PART_NUMBER='G21497-048',
 LOCATION='R1U13',
 ROOM='BMC',
 SEC='1',
 CDS_LIB='mstr_discrete',
 CDS_PART_NAME='RES_0402-51,5.0%,1/16W,CHIP,G2A',
 PRIM_FILE='./archive_libs/mstr_discrete/res/chips/chips.prt';

PART_NAME
 R1U14 'RES_0402-51,5.0%,1/16W,CHIP,G2A':
 ROOM='BMC';

SECTION_NUMBER 1
 '@BASEBOARD_FAB2_LIB.BASEBOARD_FAB2(SCH_1):PAGE144_I57@MSTR_DISCRETE.RES(CHIPS)':
 C_PATH='@baseboard_fab2_lib.baseboard_fab2(sch_1):page144_i57@mstr_discrete.res~
(chips)',
 P_PATH='@baseboard_fab2_lib.baseboard_fab2(sch_1):page144_i57@mstr_discrete.res~
(chips)',
 PATH='I57',
 DRAWING='@BASEBOARD_FAB2_LIB.BASEBOARD_FAB2(SCH_1):PAGE144',
 WATTAGE='1/16W',
 TOLERANCE='5.0%',
 SEC_TYPE='0402',
 MATERIAL='CHIP',
 PHYS_PAGE='144',
 XY='(-1750,-2200)',
 ROT='0',
 VER='1',
 VALUE='51',
 PACK_TYPE='0402',
 PART_NUMBER='G21497-048',
 LOCATION='R1U14',
 ROOM='BMC',
 SEC='1',
 CDS_LIB='mstr_discrete',
 CDS_PART_NAME='RES_0402-51,5.0%,1/16W,CHIP,G2A',
 PRIM_FILE='./archive_libs/mstr_discrete/res/chips/chips.prt';

PART_NAME
 R1U15 'RES_0402-1.00K,1%,1/16W,CHIP,GA':
 GROUP='PD_SKU_ID3',
 ROOM='BMC_MISC';

SECTION_NUMBER 1
 '@BASEBOARD_FAB2_LIB.BASEBOARD_FAB2(SCH_1):PAGE164_I48@MSTR_DISCRETE.RES(CHIPS)':
 C_PATH='@baseboard_fab2_lib.baseboard_fab2(sch_1):page164_i48@mstr_discrete.res~
(chips)',
 P_PATH='@baseboard_fab2_lib.baseboard_fab2(sch_1):page164_i48@mstr_discrete.res~
(chips)',
 PATH='I48',
 DRAWING='@BASEBOARD_FAB2_LIB.BASEBOARD_FAB2(SCH_1):PAGE164',
 WATTAGE='1/16W',
 TOLERANCE='1%',
 SEC_TYPE='0402',
 MATERIAL='CHIP',
 BOM_COST='SM_CONTROLLER',
 PHYS_PAGE='164',
 XY='(-6325,3350)',
 ROT='0',
 VER='2',
 VALUE='1.00K',
 PACK_TYPE='0402',
 PART_NUMBER='G21796-026',
 LOCATION='R1U15',
 ROOM='BMC_MISC',
 GROUP='PD_SKU_ID3',
 SEC='1',
 CDS_LIB='mstr_discrete',
 CDS_PART_NAME='RES_0402-1.00K,1%,1/16W,CHIP,GA',
 PRIM_FILE='./archive_libs/mstr_discrete/res/chips/chips.prt';

PART_NAME
 R1U16 'RES_0402-1.00K,1%,1/16W,CHIP,GA':
 GROUP='PD_SKU_ID1',
 ROOM='BMC_MISC';

SECTION_NUMBER 1
 '@BASEBOARD_FAB2_LIB.BASEBOARD_FAB2(SCH_1):PAGE164_I37@MSTR_DISCRETE.RES(CHIPS)':
 C_PATH='@baseboard_fab2_lib.baseboard_fab2(sch_1):page164_i37@mstr_discrete.res~
(chips)',
 P_PATH='@baseboard_fab2_lib.baseboard_fab2(sch_1):page164_i37@mstr_discrete.res~
(chips)',
 PATH='I37',
 DRAWING='@BASEBOARD_FAB2_LIB.BASEBOARD_FAB2(SCH_1):PAGE164',
 WATTAGE='1/16W',
 TOLERANCE='1%',
 SEC_TYPE='0402',
 MATERIAL='CHIP',
 BOM_COST='SM_CONTROLLER',
 PHYS_PAGE='164',
 XY='(-5725,3350)',
 ROT='0',
 VER='2',
 VALUE='1.00K',
 PACK_TYPE='0402',
 PART_NUMBER='G21796-026',
 LOCATION='R1U16',
 ROOM='BMC_MISC',
 GROUP='PD_SKU_ID1',
 SEC='1',
 CDS_LIB='mstr_discrete',
 CDS_PART_NAME='RES_0402-1.00K,1%,1/16W,CHIP,GA',
 PRIM_FILE='./archive_libs/mstr_discrete/res/chips/chips.prt';

PART_NAME
 R1U17 'RES_0402-1.00K,1%,1/16W,CHIP,GA':
 ROOM='BMC_MISC';

SECTION_NUMBER 1
 '@BASEBOARD_FAB2_LIB.BASEBOARD_FAB2(SCH_1):PAGE164_I21@MSTR_DISCRETE.RES(CHIPS)':
 C_PATH='@baseboard_fab2_lib.baseboard_fab2(sch_1):page164_i21@mstr_discrete.res~
(chips)',
 P_PATH='@baseboard_fab2_lib.baseboard_fab2(sch_1):page164_i21@mstr_discrete.res~
(chips)',
 PATH='I21',
 DRAWING='@BASEBOARD_FAB2_LIB.BASEBOARD_FAB2(SCH_1):PAGE164',
 WATTAGE='1/16W',
 TOLERANCE='1%',
 SEC_TYPE='0402',
 MATERIAL='CHIP',
 BOM_COST='SM_CONTROLLER',
 PHYS_PAGE='164',
 XY='(-6025,3350)',
 ROT='0',
 VER='2',
 VALUE='1.00K',
 PACK_TYPE='0402',
 PART_NUMBER='G21796-026',
 LOCATION='R1U17',
 ROOM='BMC_MISC',
 SEC='1',
 CDS_LIB='mstr_discrete',
 CDS_PART_NAME='RES_0402-1.00K,1%,1/16W,CHIP,GA',
 PRIM_FILE='./archive_libs/mstr_discrete/res/chips/chips.prt';

PART_NAME
 R1U18 'RES_0402-1.00K,1%,1/16W,CHIP,GA':
 GROUP='PD_SKU_ID0',
 ROOM='BMC_MISC';

SECTION_NUMBER 1
 '@BASEBOARD_FAB2_LIB.BASEBOARD_FAB2(SCH_1):PAGE164_I40@MSTR_DISCRETE.RES(CHIPS)':
 C_PATH='@baseboard_fab2_lib.baseboard_fab2(sch_1):page164_i40@mstr_discrete.res~
(chips)',
 P_PATH='@baseboard_fab2_lib.baseboard_fab2(sch_1):page164_i40@mstr_discrete.res~
(chips)',
 PATH='I40',
 DRAWING='@BASEBOARD_FAB2_LIB.BASEBOARD_FAB2(SCH_1):PAGE164',
 WATTAGE='1/16W',
 TOLERANCE='1%',
 SEC_TYPE='0402',
 MATERIAL='CHIP',
 BOM_COST='SM_CONTROLLER',
 PHYS_PAGE='164',
 XY='(-5425,3350)',
 ROT='0',
 VER='2',
 VALUE='1.00K',
 PACK_TYPE='0402',
 PART_NUMBER='G21796-026',
 LOCATION='R1U18',
 ROOM='BMC_MISC',
 GROUP='PD_SKU_ID0',
 SEC='1',
 CDS_LIB='mstr_discrete',
 CDS_PART_NAME='RES_0402-1.00K,1%,1/16W,CHIP,GA',
 PRIM_FILE='./archive_libs/mstr_discrete/res/chips/chips.prt';

PART_NAME
 R1U19 'RES_0402-20.0,1%,1/16W,CHIP,G2A':
 ROOM='SMBUS';

SECTION_NUMBER 1
 '@BASEBOARD_FAB2_LIB.BASEBOARD_FAB2(SCH_1):PAGE159_I226@MSTR_DISCRETE.RES(CHIPS)':
 C_PATH='@baseboard_fab2_lib.baseboard_fab2(sch_1):page159_i226@mstr_discrete.re~
s(chips)',
 P_PATH='@baseboard_fab2_lib.baseboard_fab2(sch_1):page159_i226@mstr_discrete.re~
s(chips)',
 PATH='I226',
 DRAWING='@BASEBOARD_FAB2_LIB.BASEBOARD_FAB2(SCH_1):PAGE159',
 WATTAGE='1/16W',
 TOLERANCE='1%',
 MATERIAL='CHIP',
 BOM_COST='SM_CONTROLLER',
 PHYS_PAGE='159',
 XY='(-3625,1325)',
 ROT='0',
 VER='1',
 VALUE='20.0',
 PACK_TYPE='0402',
 PART_NUMBER='G21796-173',
 LOCATION='R1U19',
 ROOM='SMBUS',
 CDS_LIB='mstr_discrete',
 CDS_PART_NAME='RES_0402-20.0,1%,1/16W,CHIP,G2A',
 PRIM_FILE='./archive_libs/mstr_discrete/res/chips/chips.prt';

PART_NAME
 R1U20 'RES_0402-20.0,1%,1/16W,CHIP,G2A':
 ROOM='SMBUS';

SECTION_NUMBER 1
 '@BASEBOARD_FAB2_LIB.BASEBOARD_FAB2(SCH_1):PAGE159_I225@MSTR_DISCRETE.RES(CHIPS)':
 C_PATH='@baseboard_fab2_lib.baseboard_fab2(sch_1):page159_i225@mstr_discrete.re~
s(chips)',
 P_PATH='@baseboard_fab2_lib.baseboard_fab2(sch_1):page159_i225@mstr_discrete.re~
s(chips)',
 PATH='I225',
 DRAWING='@BASEBOARD_FAB2_LIB.BASEBOARD_FAB2(SCH_1):PAGE159',
 WATTAGE='1/16W',
 TOLERANCE='1%',
 MATERIAL='CHIP',
 BOM_COST='SM_CONTROLLER',
 PHYS_PAGE='159',
 XY='(-3625,1450)',
 ROT='0',
 VER='1',
 VALUE='20.0',
 PACK_TYPE='0402',
 PART_NUMBER='G21796-173',
 LOCATION='R1U20',
 ROOM='SMBUS',
 CDS_LIB='mstr_discrete',
 CDS_PART_NAME='RES_0402-20.0,1%,1/16W,CHIP,G2A',
 PRIM_FILE='./archive_libs/mstr_discrete/res/chips/chips.prt';

PART_NAME
 R1U21 'RES_0402-2.7K,1%,1/16W,CHIP,G2A':
 GROUP='PU_SKU_ID3',
 ROOM='BMC_MISC';

SECTION_NUMBER 1
 '@BASEBOARD_FAB2_LIB.BASEBOARD_FAB2(SCH_1):PAGE164_I41@MSTR_DISCRETE.RES(CHIPS)':
 C_PATH='@baseboard_fab2_lib.baseboard_fab2(sch_1):page164_i41@mstr_discrete.res~
(chips)',
 P_PATH='@baseboard_fab2_lib.baseboard_fab2(sch_1):page164_i41@mstr_discrete.res~
(chips)',
 PATH='I41',
 DRAWING='@BASEBOARD_FAB2_LIB.BASEBOARD_FAB2(SCH_1):PAGE164',
 WATTAGE='1/16W',
 TOLERANCE='1%',
 SEC_TYPE='0402',
 MATERIAL='CHIP',
 BOM_COST='SM_CONTROLLER',
 PHYS_PAGE='164',
 XY='(-7175,4275)',
 ROT='0',
 VER='1',
 VALUE='2.7K',
 PACK_TYPE='0402',
 PART_NUMBER='G21796-344',
 LOCATION='R1U21',
 ROOM='BMC_MISC',
 GROUP='PU_SKU_ID3',
 SEC='1',
 CDS_LIB='mstr_discrete',
 CDS_PART_NAME='RES_0402-2.7K,1%,1/16W,CHIP,G2A',
 PRIM_FILE='./archive_libs/mstr_discrete/res/chips/chips.prt';

PART_NAME
 R1U22 'RES_0402-2.7K,1%,1/16W,CHIP,G2A':
 GROUP='PU_SKU_ID1',
 ROOM='BMC_MISC';

SECTION_NUMBER 1
 '@BASEBOARD_FAB2_LIB.BASEBOARD_FAB2(SCH_1):PAGE164_I43@MSTR_DISCRETE.RES(CHIPS)':
 C_PATH='@baseboard_fab2_lib.baseboard_fab2(sch_1):page164_i43@mstr_discrete.res~
(chips)',
 P_PATH='@baseboard_fab2_lib.baseboard_fab2(sch_1):page164_i43@mstr_discrete.res~
(chips)',
 PATH='I43',
 DRAWING='@BASEBOARD_FAB2_LIB.BASEBOARD_FAB2(SCH_1):PAGE164',
 WATTAGE='1/16W',
 TOLERANCE='1%',
 SEC_TYPE='0402',
 MATERIAL='CHIP',
 BOM_COST='SM_CONTROLLER',
 PHYS_PAGE='164',
 XY='(-7175,3875)',
 ROT='0',
 VER='1',
 VALUE='2.7K',
 PACK_TYPE='0402',
 PART_NUMBER='G21796-344',
 LOCATION='R1U22',
 ROOM='BMC_MISC',
 GROUP='PU_SKU_ID1',
 SEC='1',
 CDS_LIB='mstr_discrete',
 CDS_PART_NAME='RES_0402-2.7K,1%,1/16W,CHIP,G2A',
 PRIM_FILE='./archive_libs/mstr_discrete/res/chips/chips.prt';

PART_NAME
 R1U23 'RES_0402-2.7K,1%,1/16W,CHIP,G2A':
 GROUP='PU_SKU_ID0',
 ROOM='BMC_MISC';

SECTION_NUMBER 1
 '@BASEBOARD_FAB2_LIB.BASEBOARD_FAB2(SCH_1):PAGE164_I34@MSTR_DISCRETE.RES(CHIPS)':
 C_PATH='@baseboard_fab2_lib.baseboard_fab2(sch_1):page164_i34@mstr_discrete.res~
(chips)',
 P_PATH='@baseboard_fab2_lib.baseboard_fab2(sch_1):page164_i34@mstr_discrete.res~
(chips)',
 PATH='I34',
 DRAWING='@BASEBOARD_FAB2_LIB.BASEBOARD_FAB2(SCH_1):PAGE164',
 WATTAGE='1/16W',
 TOLERANCE='1%',
 SEC_TYPE='0402',
 MATERIAL='CHIP',
 BOM_COST='SM_CONTROLLER',
 PHYS_PAGE='164',
 XY='(-7175,3675)',
 ROT='0',
 VER='1',
 VALUE='2.7K',
 PACK_TYPE='0402',
 PART_NUMBER='G21796-344',
 LOCATION='R1U23',
 ROOM='BMC_MISC',
 GROUP='PU_SKU_ID0',
 SEC='1',
 CDS_LIB='mstr_discrete',
 CDS_PART_NAME='RES_0402-2.7K,1%,1/16W,CHIP,G2A',
 PRIM_FILE='./archive_libs/mstr_discrete/res/chips/chips.prt';

PART_NAME
 R1U24 'RES_0402-2.7K,1%,1/16W,CHIP,G2A':
 ROOM='BMC_MISC';

SECTION_NUMBER 1
 '@BASEBOARD_FAB2_LIB.BASEBOARD_FAB2(SCH_1):PAGE164_I47@MSTR_DISCRETE.RES(CHIPS)':
 C_PATH='@baseboard_fab2_lib.baseboard_fab2(sch_1):page164_i47@mstr_discrete.res~
(chips)',
 P_PATH='@baseboard_fab2_lib.baseboard_fab2(sch_1):page164_i47@mstr_discrete.res~
(chips)',
 PATH='I47',
 DRAWING='@BASEBOARD_FAB2_LIB.BASEBOARD_FAB2(SCH_1):PAGE164',
 POP='NOPOP',
 WATTAGE='1/16W',
 TOLERANCE='1%',
 SEC_TYPE='0402',
 MATERIAL='CHIP',
 BOM_COST='SM_CONTROLLER',
 PHYS_PAGE='164',
 XY='(-7175,4075)',
 ROT='0',
 VER='1',
 VALUE='2.7K',
 PACK_TYPE='0402',
 PART_NUMBER='G21796-344',
 LOCATION='R1U24',
 ROOM='BMC_MISC',
 SEC='1',
 CDS_LIB='mstr_discrete',
 CDS_PART_NAME='RES_0402-2.7K,1%,1/16W,CHIP,G2A',
 PRIM_FILE='./archive_libs/mstr_discrete/res/chips/chips.prt';

PART_NAME
 R1U26 'RES_0402-5.11K,1%,1/16W,CHIP,GA':
 ROOM='BMC_VOLT_MONITOR';

SECTION_NUMBER 1
 '@BASEBOARD_FAB2_LIB.BASEBOARD_FAB2(SCH_1):PAGE169_I148@MSTR_DISCRETE.RES(CHIPS)':
 C_PATH='@baseboard_fab2_lib.baseboard_fab2(sch_1):page169_i148@mstr_discrete.re~
s(chips)',
 P_PATH='@baseboard_fab2_lib.baseboard_fab2(sch_1):page169_i148@mstr_discrete.re~
s(chips)',
 PATH='I148',
 DRAWING='@BASEBOARD_FAB2_LIB.BASEBOARD_FAB2(SCH_1):PAGE169',
 WATTAGE='1/16W',
 TOLERANCE='1%',
 SEC_TYPE='0402',
 MATERIAL='CHIP',
 BOM_COST='SM_HM',
 PHYS_PAGE='169',
 XY='(-2900,5000)',
 ROT='0',
 VER='2',
 VALUE='5.11K',
 PACK_TYPE='0402',
 PART_NUMBER='G21796-140',
 LOCATION='R1U26',
 ROOM='BMC_VOLT_MONITOR',
 SEC='1',
 CDS_LIB='mstr_discrete',
 CDS_PART_NAME='RES_0402-5.11K,1%,1/16W,CHIP,GA',
 PRIM_FILE='./archive_libs/mstr_discrete/res/chips/chips.prt';

PART_NAME
 R1U27 'RES_0402-3.48K,1.0%,1/16W,CHIPA':;

SECTION_NUMBER 1
 '@BASEBOARD_FAB2_LIB.BASEBOARD_FAB2(SCH_1):PAGE169_I173@MSTR_DISCRETE.RES(CHIPS)':
 C_PATH='@baseboard_fab2_lib.baseboard_fab2(sch_1):page169_i173@mstr_discrete.re~
s(chips)',
 P_PATH='@baseboard_fab2_lib.baseboard_fab2(sch_1):page169_i173@mstr_discrete.re~
s(chips)',
 PATH='I173',
 DRAWING='@BASEBOARD_FAB2_LIB.BASEBOARD_FAB2(SCH_1):PAGE169',
 WATTAGE='1/16W',
 TOLERANCE='1.0%',
 SEC_TYPE='0402',
 MATERIAL='CHIP',
 PHYS_PAGE='169',
 XY='(-2900,4625)',
 ROT='5',
 VER='1',
 VALUE='3.48K',
 PACK_TYPE='0402',
 PART_NUMBER='G21796-279',
 LOCATION='R1U27',
 SEC='1',
 CDS_LIB='mstr_discrete',
 CDS_PART_NAME='RES_0402-3.48K,1.0%,1/16W,CHIPA',
 PRIM_FILE='./archive_libs/mstr_discrete/res/chips/chips.prt';

PART_NAME
 R1U28 '1K82R2F-1-GP_SMD-RG-1K82R2F-1-A':;

SECTION_NUMBER 1
 '@BASEBOARD_FAB2_LIB.BASEBOARD_FAB2(SCH_1):PAGE169_I169@W_HDL.1K82R2F-1-GP(CHIPS)':
 C_PATH='@baseboard_fab2_lib.baseboard_fab2(sch_1):page169_i169@w_hdl.\1k82r2f-1~
-gp\(chips)',
 P_PATH='@baseboard_fab2_lib.baseboard_fab2(sch_1):page169_i169@w_hdl.\1k82r2f-1~
-gp\(chips)',
 PATH='I169',
 DRAWING='@BASEBOARD_FAB2_LIB.BASEBOARD_FAB2(SCH_1):PAGE169',
 PACK_SIZE='0402',
 RATED='1/16W',
 ATTRIBUTE='1.82KOHM',
 TOLERANCE='1%',
 SEC_TYPE='SMD-RG',
 PHYS_PAGE='169',
 XY='(-4700,4575)',
 ROT='0',
 VER='1',
 VALUE='1K82R2F-1-GP',
 PACK_TYPE='SMD-RG',
 PART_NUMBER='64.18215.6DL',
 LOCATION='R1U28',
 SEC='1',
 CDS_LIB='w_hdl',
 CDS_PART_NAME='1K82R2F-1-GP_SMD-RG-1K82R2F-1-A',
 PRIM_FILE='C:/<user>/w_hdl/1k82r2f#2d1#2dgp/chips/chips.prt';

PART_NAME
 R1U29 'RES_0402-5.11K,1%,1/16W,CHIP,GA':
 ROOM='BMC_VOLT_MONITOR';

SECTION_NUMBER 1
 '@BASEBOARD_FAB2_LIB.BASEBOARD_FAB2(SCH_1):PAGE169_I141@MSTR_DISCRETE.RES(CHIPS)':
 C_PATH='@baseboard_fab2_lib.baseboard_fab2(sch_1):page169_i141@mstr_discrete.re~
s(chips)',
 P_PATH='@baseboard_fab2_lib.baseboard_fab2(sch_1):page169_i141@mstr_discrete.re~
s(chips)',
 PATH='I141',
 DRAWING='@BASEBOARD_FAB2_LIB.BASEBOARD_FAB2(SCH_1):PAGE169',
 WATTAGE='1/16W',
 TOLERANCE='1%',
 SEC_TYPE='0402',
 MATERIAL='CHIP',
 BOM_COST='SM_HM',
 PHYS_PAGE='169',
 XY='(-4700,4950)',
 ROT='0',
 VER='2',
 VALUE='5.11K',
 PACK_TYPE='0402',
 PART_NUMBER='G21796-140',
 LOCATION='R1U29',
 ROOM='BMC_VOLT_MONITOR',
 SEC='1',
 CDS_LIB='mstr_discrete',
 CDS_PART_NAME='RES_0402-5.11K,1%,1/16W,CHIP,GA',
 PRIM_FILE='./archive_libs/mstr_discrete/res/chips/chips.prt';

PART_NAME
 R1U30 'RES_0402-1.00K,1%,1/16W,CHIP,GA':
 ROOM='PROC_TRANSLATORS';

SECTION_NUMBER 1
 '@BASEBOARD_FAB2_LIB.BASEBOARD_FAB2(SCH_1):PAGE152_I2@MSTR_DISCRETE.RES(CHIPS)':
 C_PATH='@baseboard_fab2_lib.baseboard_fab2(sch_1):page152_i2@mstr_discrete.res(~
chips)',
 P_PATH='@baseboard_fab2_lib.baseboard_fab2(sch_1):page152_i2@mstr_discrete.res(~
chips)',
 PATH='I2',
 DRAWING='@BASEBOARD_FAB2_LIB.BASEBOARD_FAB2(SCH_1):PAGE152',
 WATTAGE='1/16W',
 TOLERANCE='1%',
 SEC_TYPE='0402',
 MATERIAL='CHIP',
 BOM_COST='PROC_SIDEBAND',
 PHYS_PAGE='152',
 XY='(-4350,4200)',
 ROT='0',
 VER='1',
 VALUE='1.00K',
 PACK_TYPE='0402',
 PART_NUMBER='G21796-026',
 LOCATION='R1U30',
 ROOM='PROC_TRANSLATORS',
 SEC='1',
 CDS_LIB='mstr_discrete',
 CDS_PART_NAME='RES_0402-1.00K,1%,1/16W,CHIP,GA',
 PRIM_FILE='./archive_libs/mstr_discrete/res/chips/chips.prt';

PART_NAME
 R1U32 'RES_0402-5.11K,1%,1/16W,CHIP,GA':
 ROOM='BMC_VOLT_MONITOR';

SECTION_NUMBER 1
 '@BASEBOARD_FAB2_LIB.BASEBOARD_FAB2(SCH_1):PAGE169_I82@MSTR_DISCRETE.RES(CHIPS)':
 C_PATH='@baseboard_fab2_lib.baseboard_fab2(sch_1):page169_i82@mstr_discrete.res~
(chips)',
 P_PATH='@baseboard_fab2_lib.baseboard_fab2(sch_1):page169_i82@mstr_discrete.res~
(chips)',
 PATH='I82',
 DRAWING='@BASEBOARD_FAB2_LIB.BASEBOARD_FAB2(SCH_1):PAGE169',
 WATTAGE='1/16W',
 TOLERANCE='1%',
 SEC_TYPE='0402',
 MATERIAL='CHIP',
 BOM_COST='SM_HM',
 PHYS_PAGE='169',
 XY='(-1125,1825)',
 ROT='0',
 VER='2',
 VALUE='5.11K',
 PACK_TYPE='0402',
 PART_NUMBER='G21796-140',
 LOCATION='R1U32',
 ROOM='BMC_VOLT_MONITOR',
 SEC='1',
 CDS_LIB='mstr_discrete',
 CDS_PART_NAME='RES_0402-5.11K,1%,1/16W,CHIP,GA',
 PRIM_FILE='./archive_libs/mstr_discrete/res/chips/chips.prt';

PART_NAME
 R1U33 '649R2F-GP_RCL_GP-649R2F-GP,64.A':;

SECTION_NUMBER 1
 '@BASEBOARD_FAB2_LIB.BASEBOARD_FAB2(SCH_1):PAGE169_I171@W_HDL.649R2F-GP(CHIPS)':
 C_PATH='@baseboard_fab2_lib.baseboard_fab2(sch_1):page169_i171@w_hdl.\649r2f-gp~
\(chips)',
 P_PATH='@baseboard_fab2_lib.baseboard_fab2(sch_1):page169_i171@w_hdl.\649r2f-gp~
\(chips)',
 PATH='I171',
 DRAWING='@BASEBOARD_FAB2_LIB.BASEBOARD_FAB2(SCH_1):PAGE169',
 PACK_SIZE='0402',
 RATED='1/16W',
 ATTRIBUTE='649OHM',
 TOLERANCE='1%',
 SEC_TYPE='RCL_GP',
 PHYS_PAGE='169',
 XY='(-1125,1425)',
 ROT='0',
 VER='1',
 VALUE='649R2F-GP',
 PACK_TYPE='RCL_GP',
 PART_NUMBER='64.64905.6DL',
 LOCATION='R1U33',
 SEC='1',
 CDS_LIB='w_hdl',
 CDS_PART_NAME='649R2F-GP_RCL_GP-649R2F-GP,64.A',
 PRIM_FILE='C:/<user>/w_hdl/649r2f#2dgp/chips/chips.prt';

PART_NAME
 R1U34 'RES_0402-33.2,1%,1/16W,CHIP,G2A':
 ROOM='PROC_TRANSLATORS';

SECTION_NUMBER 1
 '@BASEBOARD_FAB2_LIB.BASEBOARD_FAB2(SCH_1):PAGE152_I16@MSTR_DISCRETE.RES(CHIPS)':
 C_PATH='@baseboard_fab2_lib.baseboard_fab2(sch_1):page152_i16@mstr_discrete.res~
(chips)',
 P_PATH='@baseboard_fab2_lib.baseboard_fab2(sch_1):page152_i16@mstr_discrete.res~
(chips)',
 PATH='I16',
 DRAWING='@BASEBOARD_FAB2_LIB.BASEBOARD_FAB2(SCH_1):PAGE152',
 WATTAGE='1/16W',
 TOLERANCE='1%',
 SEC_TYPE='0402',
 MATERIAL='CHIP',
 BOM_COST='PROC_SIDEBAND',
 PHYS_PAGE='152',
 XY='(-2400,3725)',
 ROT='0',
 VER='1',
 VALUE='33.2',
 PACK_TYPE='0402',
 PART_NUMBER='G21796-074',
 LOCATION='R1U34',
 ROOM='PROC_TRANSLATORS',
 SEC='1',
 CDS_LIB='mstr_discrete',
 CDS_PART_NAME='RES_0402-33.2,1%,1/16W,CHIP,G2A',
 PRIM_FILE='./archive_libs/mstr_discrete/res/chips/chips.prt';

PART_NAME
 R1U35 'RES_0402-150.0,1%,1/16W,CHIP,GA':
 ROOM='PROC_SIDEBAND';

SECTION_NUMBER 1
 '@BASEBOARD_FAB2_LIB.BASEBOARD_FAB2(SCH_1):PAGE152_I57@MSTR_DISCRETE.RES(CHIPS)':
 C_PATH='@baseboard_fab2_lib.baseboard_fab2(sch_1):page152_i57@mstr_discrete.res~
(chips)',
 P_PATH='@baseboard_fab2_lib.baseboard_fab2(sch_1):page152_i57@mstr_discrete.res~
(chips)',
 PATH='I57',
 DRAWING='@BASEBOARD_FAB2_LIB.BASEBOARD_FAB2(SCH_1):PAGE152',
 WATTAGE='1/16W',
 TOLERANCE='1%',
 SEC_TYPE='0402',
 MATERIAL='CHIP',
 BOM_COST='PROC_SIDEBAND',
 PHYS_PAGE='152',
 XY='(-8425,4650)',
 ROT='2',
 VER='2',
 VALUE='150.0',
 PACK_TYPE='0402',
 PART_NUMBER='G21796-009',
 LOCATION='R1U35',
 ROOM='PROC_SIDEBAND',
 SEC='1',
 CDS_LIB='mstr_discrete',
 CDS_PART_NAME='RES_0402-150.0,1%,1/16W,CHIP,GA',
 PRIM_FILE='./archive_libs/mstr_discrete/res/chips/chips.prt';

PART_NAME
 R1U36 'RES_0402-33.2,1%,1/16W,CHIP,G2A':
 ROOM='PROC_SIDEBAND';

SECTION_NUMBER 1
 '@BASEBOARD_FAB2_LIB.BASEBOARD_FAB2(SCH_1):PAGE152_I15@MSTR_DISCRETE.RES(CHIPS)':
 C_PATH='@baseboard_fab2_lib.baseboard_fab2(sch_1):page152_i15@mstr_discrete.res~
(chips)',
 P_PATH='@baseboard_fab2_lib.baseboard_fab2(sch_1):page152_i15@mstr_discrete.res~
(chips)',
 PATH='I15',
 DRAWING='@BASEBOARD_FAB2_LIB.BASEBOARD_FAB2(SCH_1):PAGE152',
 WATTAGE='1/16W',
 TOLERANCE='1%',
 SEC_TYPE='0402',
 MATERIAL='CHIP',
 BOM_COST='PROC_SIDEBAND',
 PHYS_PAGE='152',
 XY='(-2400,3900)',
 ROT='0',
 VER='1',
 VALUE='33.2',
 PACK_TYPE='0402',
 PART_NUMBER='G21796-074',
 LOCATION='R1U36',
 ROOM='PROC_SIDEBAND',
 SEC='1',
 CDS_LIB='mstr_discrete',
 CDS_PART_NAME='RES_0402-33.2,1%,1/16W,CHIP,G2A',
 PRIM_FILE='./archive_libs/mstr_discrete/res/chips/chips.prt';

PART_NAME
 R1U37 'RES_0402-100.0,1%,1/16W,CHIP,GA':
 ROOM='PROC_SIDEBAND';

SECTION_NUMBER 1
 '@BASEBOARD_FAB2_LIB.BASEBOARD_FAB2(SCH_1):PAGE152_I26@MSTR_DISCRETE.RES(CHIPS)':
 C_PATH='@baseboard_fab2_lib.baseboard_fab2(sch_1):page152_i26@mstr_discrete.res~
(chips)',
 P_PATH='@baseboard_fab2_lib.baseboard_fab2(sch_1):page152_i26@mstr_discrete.res~
(chips)',
 PATH='I26',
 DRAWING='@BASEBOARD_FAB2_LIB.BASEBOARD_FAB2(SCH_1):PAGE152',
 WATTAGE='1/16W',
 TOLERANCE='1%',
 SEC_TYPE='0402',
 MATERIAL='CHIP',
 BOM_COST='PROC_SIDEBAND',
 PHYS_PAGE='152',
 XY='(-2550,1600)',
 ROT='0',
 VER='2',
 VALUE='100.0',
 PACK_TYPE='0402',
 PART_NUMBER='G21796-017',
 LOCATION='R1U37',
 ROOM='PROC_SIDEBAND',
 SEC='1',
 CDS_LIB='mstr_discrete',
 CDS_PART_NAME='RES_0402-100.0,1%,1/16W,CHIP,GA',
 PRIM_FILE='./archive_libs/mstr_discrete/res/chips/chips.prt';

PART_NAME
 R1U38 'RES_0402-3.48K,1.0%,1/16W,CHIPA':;

SECTION_NUMBER 1
 '@BASEBOARD_FAB2_LIB.BASEBOARD_FAB2(SCH_1):PAGE169_I172@MSTR_DISCRETE.RES(CHIPS)':
 C_PATH='@baseboard_fab2_lib.baseboard_fab2(sch_1):page169_i172@mstr_discrete.re~
s(chips)',
 P_PATH='@baseboard_fab2_lib.baseboard_fab2(sch_1):page169_i172@mstr_discrete.re~
s(chips)',
 PATH='I172',
 DRAWING='@BASEBOARD_FAB2_LIB.BASEBOARD_FAB2(SCH_1):PAGE169',
 WATTAGE='1/16W',
 TOLERANCE='1.0%',
 SEC_TYPE='0402',
 MATERIAL='CHIP',
 PHYS_PAGE='169',
 XY='(-4825,1400)',
 ROT='5',
 VER='1',
 VALUE='3.48K',
 PACK_TYPE='0402',
 PART_NUMBER='G21796-279',
 LOCATION='R1U38',
 SEC='1',
 CDS_LIB='mstr_discrete',
 CDS_PART_NAME='RES_0402-3.48K,1.0%,1/16W,CHIPA',
 PRIM_FILE='./archive_libs/mstr_discrete/res/chips/chips.prt';

PART_NAME
 R1U39 'RES_0402-5.11K,1%,1/16W,CHIP,GA':
 ROOM='BMC_VOLT_MONITOR';

SECTION_NUMBER 1
 '@BASEBOARD_FAB2_LIB.BASEBOARD_FAB2(SCH_1):PAGE169_I88@MSTR_DISCRETE.RES(CHIPS)':
 C_PATH='@baseboard_fab2_lib.baseboard_fab2(sch_1):page169_i88@mstr_discrete.res~
(chips)',
 P_PATH='@baseboard_fab2_lib.baseboard_fab2(sch_1):page169_i88@mstr_discrete.res~
(chips)',
 PATH='I88',
 DRAWING='@BASEBOARD_FAB2_LIB.BASEBOARD_FAB2(SCH_1):PAGE169',
 WATTAGE='1/16W',
 TOLERANCE='1%',
 SEC_TYPE='0402',
 MATERIAL='CHIP',
 BOM_COST='SM_HM',
 PHYS_PAGE='169',
 XY='(-4825,1800)',
 ROT='0',
 VER='2',
 VALUE='5.11K',
 PACK_TYPE='0402',
 PART_NUMBER='G21796-140',
 LOCATION='R1U39',
 ROOM='BMC_VOLT_MONITOR',
 SEC='1',
 CDS_LIB='mstr_discrete',
 CDS_PART_NAME='RES_0402-5.11K,1%,1/16W,CHIP,GA',
 PRIM_FILE='./archive_libs/mstr_discrete/res/chips/chips.prt';

PART_NAME
 R1U41 'RES_0402-150.0,1%,1/16W,CHIP,GA':
 ROOM='PROC_SIDEBAND';

SECTION_NUMBER 1
 '@BASEBOARD_FAB2_LIB.BASEBOARD_FAB2(SCH_1):PAGE152_I56@MSTR_DISCRETE.RES(CHIPS)':
 C_PATH='@baseboard_fab2_lib.baseboard_fab2(sch_1):page152_i56@mstr_discrete.res~
(chips)',
 P_PATH='@baseboard_fab2_lib.baseboard_fab2(sch_1):page152_i56@mstr_discrete.res~
(chips)',
 PATH='I56',
 DRAWING='@BASEBOARD_FAB2_LIB.BASEBOARD_FAB2(SCH_1):PAGE152',
 WATTAGE='1/16W',
 TOLERANCE='1%',
 SEC_TYPE='0402',
 MATERIAL='CHIP',
 BOM_COST='PROC_SIDEBAND',
 PHYS_PAGE='152',
 XY='(-8325,4650)',
 ROT='0',
 VER='2',
 VALUE='150.0',
 PACK_TYPE='0402',
 PART_NUMBER='G21796-009',
 LOCATION='R1U41',
 ROOM='PROC_SIDEBAND',
 SEC='1',
 CDS_LIB='mstr_discrete',
 CDS_PART_NAME='RES_0402-150.0,1%,1/16W,CHIP,GA',
 PRIM_FILE='./archive_libs/mstr_discrete/res/chips/chips.prt';

PART_NAME
 R1U43 '374R2F-1-GP_SMD-RG-374R2F-1-GPA':;

SECTION_NUMBER 1
 '@BASEBOARD_FAB2_LIB.BASEBOARD_FAB2(SCH_1):PAGE152_I106@W_HDL.374R2F-1-GP(CHIPS)':
 C_PATH='@baseboard_fab2_lib.baseboard_fab2(sch_1):page152_i106@w_hdl.\374r2f-1-~
gp\(chips)',
 P_PATH='@baseboard_fab2_lib.baseboard_fab2(sch_1):page152_i106@w_hdl.\374r2f-1-~
gp\(chips)',
 PATH='I106',
 DRAWING='@BASEBOARD_FAB2_LIB.BASEBOARD_FAB2(SCH_1):PAGE152',
 PACK_SIZE='0402',
 RATED='1/16W',
 ATTRIBUTE='374 OHM',
 TOLERANCE='1%',
 PHYS_PAGE='152',
 XY='(-2550,2075)',
 ROT='0',
 VER='1',
 VALUE='374R2F-1-GP',
 PACK_TYPE='SMD-RG',
 PART_NUMBER='64.37405.6DL',
 LOCATION='R1U43',
 CDS_LIB='w_hdl',
 CDS_PART_NAME='374R2F-1-GP_SMD-RG-374R2F-1-GPA',
 PRIM_FILE='C:/<user>/w_hdl/374r2f#2d1#2dgp/chips/chips.prt';

PART_NAME
 R1U44 '1K82R2F-1-GP_SMD-RG-1K82R2F-1-A':;

SECTION_NUMBER 1
 '@BASEBOARD_FAB2_LIB.BASEBOARD_FAB2(SCH_1):PAGE169_I170@W_HDL.1K82R2F-1-GP(CHIPS)':
 C_PATH='@baseboard_fab2_lib.baseboard_fab2(sch_1):page169_i170@w_hdl.\1k82r2f-1~
-gp\(chips)',
 P_PATH='@baseboard_fab2_lib.baseboard_fab2(sch_1):page169_i170@w_hdl.\1k82r2f-1~
-gp\(chips)',
 PATH='I170',
 DRAWING='@BASEBOARD_FAB2_LIB.BASEBOARD_FAB2(SCH_1):PAGE169',
 PACK_SIZE='0402',
 RATED='1/16W',
 ATTRIBUTE='1.82KOHM',
 TOLERANCE='1%',
 SEC_TYPE='SMD-RG',
 PHYS_PAGE='169',
 XY='(-2850,1375)',
 ROT='0',
 VER='1',
 VALUE='1K82R2F-1-GP',
 PACK_TYPE='SMD-RG',
 PART_NUMBER='64.18215.6DL',
 LOCATION='R1U44',
 SEC='1',
 CDS_LIB='w_hdl',
 CDS_PART_NAME='1K82R2F-1-GP_SMD-RG-1K82R2F-1-A',
 PRIM_FILE='C:/<user>/w_hdl/1k82r2f#2d1#2dgp/chips/chips.prt';

PART_NAME
 R1U46 'RES_0402-33.2,1%,1/16W,CHIP,G2A':
 ROOM='PROC_SIDEBAND';

SECTION_NUMBER 1
 '@BASEBOARD_FAB2_LIB.BASEBOARD_FAB2(SCH_1):PAGE152_I6@MSTR_DISCRETE.RES(CHIPS)':
 C_PATH='@baseboard_fab2_lib.baseboard_fab2(sch_1):page152_i6@mstr_discrete.res(~
chips)',
 P_PATH='@baseboard_fab2_lib.baseboard_fab2(sch_1):page152_i6@mstr_discrete.res(~
chips)',
 PATH='I6',
 DRAWING='@BASEBOARD_FAB2_LIB.BASEBOARD_FAB2(SCH_1):PAGE152',
 WATTAGE='1/16W',
 TOLERANCE='1%',
 SEC_TYPE='0402',
 MATERIAL='CHIP',
 BOM_COST='PROC_SIDEBAND',
 PHYS_PAGE='152',
 XY='(-2400,4250)',
 ROT='0',
 VER='1',
 VALUE='33.2',
 PACK_TYPE='0402',
 PART_NUMBER='G21796-074',
 LOCATION='R1U46',
 ROOM='PROC_SIDEBAND',
 SEC='1',
 CDS_LIB='mstr_discrete',
 CDS_PART_NAME='RES_0402-33.2,1%,1/16W,CHIP,G2A',
 PRIM_FILE='./archive_libs/mstr_discrete/res/chips/chips.prt';

PART_NAME
 R1U47 'RES_0402-5.11K,1%,1/16W,CHIP,GA':
 ROOM='BMC_VOLT_MONITOR';

SECTION_NUMBER 1
 '@BASEBOARD_FAB2_LIB.BASEBOARD_FAB2(SCH_1):PAGE169_I115@MSTR_DISCRETE.RES(CHIPS)':
 C_PATH='@baseboard_fab2_lib.baseboard_fab2(sch_1):page169_i115@mstr_discrete.re~
s(chips)',
 P_PATH='@baseboard_fab2_lib.baseboard_fab2(sch_1):page169_i115@mstr_discrete.re~
s(chips)',
 PATH='I115',
 DRAWING='@BASEBOARD_FAB2_LIB.BASEBOARD_FAB2(SCH_1):PAGE169',
 WATTAGE='1/16W',
 TOLERANCE='1%',
 SEC_TYPE='0402',
 MATERIAL='CHIP',
 BOM_COST='SM_HM',
 PHYS_PAGE='169',
 XY='(-2850,1750)',
 ROT='0',
 VER='2',
 VALUE='5.11K',
 PACK_TYPE='0402',
 PART_NUMBER='G21796-140',
 LOCATION='R1U47',
 ROOM='BMC_VOLT_MONITOR',
 SEC='1',
 CDS_LIB='mstr_discrete',
 CDS_PART_NAME='RES_0402-5.11K,1%,1/16W,CHIP,GA',
 PRIM_FILE='./archive_libs/mstr_discrete/res/chips/chips.prt';

PART_NAME
 R1U49 'RES_0402-2.7K,1%,1/16W,CHIP,G2A':
 ROOM='BMC_VOLT_MONITOR';

SECTION_NUMBER 1
 '@BASEBOARD_FAB2_LIB.BASEBOARD_FAB2(SCH_1):PAGE169_I163@MSTR_DISCRETE.RES(CHIPS)':
 C_PATH='@baseboard_fab2_lib.baseboard_fab2(sch_1):page169_i163@mstr_discrete.re~
s(chips)',
 P_PATH='@baseboard_fab2_lib.baseboard_fab2(sch_1):page169_i163@mstr_discrete.re~
s(chips)',
 PATH='I163',
 DRAWING='@BASEBOARD_FAB2_LIB.BASEBOARD_FAB2(SCH_1):PAGE169',
 WATTAGE='1/16W',
 TOLERANCE='1%',
 SEC_TYPE='0402',
 MATERIAL='CHIP',
 BOM_COST='SM_HM',
 PHYS_PAGE='169',
 XY='(-650,3375)',
 ROT='0',
 VER='2',
 VALUE='2.7K',
 PACK_TYPE='0402',
 PART_NUMBER='G21796-344',
 LOCATION='R1U49',
 ROOM='BMC_VOLT_MONITOR',
 SEC='1',
 CDS_LIB='mstr_discrete',
 CDS_PART_NAME='RES_0402-2.7K,1%,1/16W,CHIP,G2A',
 PRIM_FILE='./archive_libs/mstr_discrete/res/chips/chips.prt';

PART_NAME
 R1U50 'RES_0402-200.0K,1%,1/16W,CHIP,A':
 ROOM='BMC_VOLT_MONITOR';

SECTION_NUMBER 1
 '@BASEBOARD_FAB2_LIB.BASEBOARD_FAB2(SCH_1):PAGE169_I126@MSTR_DISCRETE.RES(CHIPS)':
 C_PATH='@baseboard_fab2_lib.baseboard_fab2(sch_1):page169_i126@mstr_discrete.re~
s(chips)',
 P_PATH='@baseboard_fab2_lib.baseboard_fab2(sch_1):page169_i126@mstr_discrete.re~
s(chips)',
 PATH='I126',
 DRAWING='@BASEBOARD_FAB2_LIB.BASEBOARD_FAB2(SCH_1):PAGE169',
 WATTAGE='1/16W',
 TOLERANCE='1%',
 SEC_TYPE='0402',
 MATERIAL='CHIP',
 BOM_COST='SM_HM',
 PHYS_PAGE='169',
 XY='(200,4025)',
 ROT='0',
 VER='2',
 VALUE='200.0K',
 PACK_TYPE='0402',
 PART_NUMBER='G21796-080',
 LOCATION='R1U50',
 ROOM='BMC_VOLT_MONITOR',
 SEC='1',
 CDS_LIB='mstr_discrete',
 CDS_PART_NAME='RES_0402-200.0K,1%,1/16W,CHIP,A',
 PRIM_FILE='./archive_libs/mstr_discrete/res/chips/chips.prt';

PART_NAME
 R1U53 'RES_0402-0.0,5%,1/16W,CHIP,G21A':;

SECTION_NUMBER 1
 '@BASEBOARD_FAB2_LIB.BASEBOARD_FAB2(SCH_1):PAGE152_I64@MSTR_DISCRETE.RES(CHIPS)':
 C_PATH='@baseboard_fab2_lib.baseboard_fab2(sch_1):page152_i64@mstr_discrete.res~
(chips)',
 P_PATH='@baseboard_fab2_lib.baseboard_fab2(sch_1):page152_i64@mstr_discrete.res~
(chips)',
 PATH='I64',
 DRAWING='@BASEBOARD_FAB2_LIB.BASEBOARD_FAB2(SCH_1):PAGE152',
 WATTAGE='1/16W',
 TOLERANCE='5%',
 SEC_TYPE='0402',
 MATERIAL='CHIP',
 PHYS_PAGE='152',
 XY='(-6950,3900)',
 ROT='0',
 VER='1',
 VALUE='0.0',
 PACK_TYPE='0402',
 PART_NUMBER='G21497-005',
 LOCATION='R1U53',
 SEC='1',
 CDS_LIB='mstr_discrete',
 CDS_PART_NAME='RES_0402-0.0,5%,1/16W,CHIP,G21A',
 PRIM_FILE='./archive_libs/mstr_discrete/res/chips/chips.prt';

PART_NAME
 R1U54 'RES_0402-0.0,5%,1/16W,CHIP,G21A':;

SECTION_NUMBER 1
 '@BASEBOARD_FAB2_LIB.BASEBOARD_FAB2(SCH_1):PAGE152_I93@MSTR_DISCRETE.RES(CHIPS)':
 C_PATH='@baseboard_fab2_lib.baseboard_fab2(sch_1):page152_i93@mstr_discrete.res~
(chips)',
 P_PATH='@baseboard_fab2_lib.baseboard_fab2(sch_1):page152_i93@mstr_discrete.res~
(chips)',
 PATH='I93',
 DRAWING='@BASEBOARD_FAB2_LIB.BASEBOARD_FAB2(SCH_1):PAGE152',
 WATTAGE='1/16W',
 TOLERANCE='5%',
 SEC_TYPE='0402',
 MATERIAL='CHIP',
 PHYS_PAGE='152',
 XY='(-6700,1600)',
 ROT='0',
 VER='1',
 VALUE='0.0',
 PACK_TYPE='0402',
 PART_NUMBER='G21497-005',
 LOCATION='R1U54',
 SEC='1',
 CDS_LIB='mstr_discrete',
 CDS_PART_NAME='RES_0402-0.0,5%,1/16W,CHIP,G21A',
 PRIM_FILE='./archive_libs/mstr_discrete/res/chips/chips.prt';

PART_NAME
 R1U55 'RES_0402-0.0,5%,1/16W,EMPTY,G2A':;

SECTION_NUMBER 1
 '@BASEBOARD_FAB2_LIB.BASEBOARD_FAB2(SCH_1):PAGE152_I67@MSTR_DISCRETE.RES(CHIPS)':
 C_PATH='@baseboard_fab2_lib.baseboard_fab2(sch_1):page152_i67@mstr_discrete.res~
(chips)',
 P_PATH='@baseboard_fab2_lib.baseboard_fab2(sch_1):page152_i67@mstr_discrete.res~
(chips)',
 PATH='I67',
 DRAWING='@BASEBOARD_FAB2_LIB.BASEBOARD_FAB2(SCH_1):PAGE152',
 WATTAGE='1/16W',
 TOLERANCE='5%',
 SEC_TYPE='0402',
 MATERIAL='EMPTY',
 PHYS_PAGE='152',
 XY='(-7175,3500)',
 ROT='0',
 VER='2',
 VALUE='0.0',
 PACK_TYPE='0402',
 PART_NUMBER='G21497-005',
 LOCATION='R1U55',
 SEC='1',
 CDS_LIB='mstr_discrete',
 CDS_PART_NAME='RES_0402-0.0,5%,1/16W,EMPTY,G2A',
 PRIM_FILE='./archive_libs/mstr_discrete/res/chips/chips.prt';

PART_NAME
 R1U56 'RES_0402-0.0,5%,1/16W,EMPTY,G2A':;

SECTION_NUMBER 1
 '@BASEBOARD_FAB2_LIB.BASEBOARD_FAB2(SCH_1):PAGE152_I50@MSTR_DISCRETE.RES(CHIPS)':
 C_PATH='@baseboard_fab2_lib.baseboard_fab2(sch_1):page152_i50@mstr_discrete.res~
(chips)',
 P_PATH='@baseboard_fab2_lib.baseboard_fab2(sch_1):page152_i50@mstr_discrete.res~
(chips)',
 PATH='I50',
 DRAWING='@BASEBOARD_FAB2_LIB.BASEBOARD_FAB2(SCH_1):PAGE152',
 WATTAGE='1/16W',
 TOLERANCE='5%',
 SEC_TYPE='0402',
 MATERIAL='EMPTY',
 PHYS_PAGE='152',
 XY='(-7175,4525)',
 ROT='0',
 VER='2',
 VALUE='0.0',
 PACK_TYPE='0402',
 PART_NUMBER='G21497-005',
 LOCATION='R1U56',
 SEC='1',
 CDS_LIB='mstr_discrete',
 CDS_PART_NAME='RES_0402-0.0,5%,1/16W,EMPTY,G2A',
 PRIM_FILE='./archive_libs/mstr_discrete/res/chips/chips.prt';

PART_NAME
 R1U57 'RES_0402-0.0,5%,1/16W,EMPTY,G2A':;

SECTION_NUMBER 1
 '@BASEBOARD_FAB2_LIB.BASEBOARD_FAB2(SCH_1):PAGE152_I69@MSTR_DISCRETE.RES(CHIPS)':
 C_PATH='@baseboard_fab2_lib.baseboard_fab2(sch_1):page152_i69@mstr_discrete.res~
(chips)',
 P_PATH='@baseboard_fab2_lib.baseboard_fab2(sch_1):page152_i69@mstr_discrete.res~
(chips)',
 PATH='I69',
 DRAWING='@BASEBOARD_FAB2_LIB.BASEBOARD_FAB2(SCH_1):PAGE152',
 WATTAGE='1/16W',
 TOLERANCE='5%',
 SEC_TYPE='0402',
 MATERIAL='EMPTY',
 PHYS_PAGE='152',
 XY='(-3175,3425)',
 ROT='0',
 VER='2',
 VALUE='0.0',
 PACK_TYPE='0402',
 PART_NUMBER='G21497-005',
 LOCATION='R1U57',
 SEC='1',
 CDS_LIB='mstr_discrete',
 CDS_PART_NAME='RES_0402-0.0,5%,1/16W,EMPTY,G2A',
 PRIM_FILE='./archive_libs/mstr_discrete/res/chips/chips.prt';

PART_NAME
 R1U58 'RES_0402-0.0,5%,1/16W,CHIP,G21A':;

SECTION_NUMBER 1
 '@BASEBOARD_FAB2_LIB.BASEBOARD_FAB2(SCH_1):PAGE152_I49@MSTR_DISCRETE.RES(CHIPS)':
 C_PATH='@baseboard_fab2_lib.baseboard_fab2(sch_1):page152_i49@mstr_discrete.res~
(chips)',
 P_PATH='@baseboard_fab2_lib.baseboard_fab2(sch_1):page152_i49@mstr_discrete.res~
(chips)',
 PATH='I49',
 DRAWING='@BASEBOARD_FAB2_LIB.BASEBOARD_FAB2(SCH_1):PAGE152',
 WATTAGE='1/16W',
 TOLERANCE='5%',
 SEC_TYPE='0402',
 MATERIAL='CHIP',
 PHYS_PAGE='152',
 XY='(-6950,4050)',
 ROT='0',
 VER='1',
 VALUE='0.0',
 PACK_TYPE='0402',
 PART_NUMBER='G21497-005',
 LOCATION='R1U58',
 SEC='1',
 CDS_LIB='mstr_discrete',
 CDS_PART_NAME='RES_0402-0.0,5%,1/16W,CHIP,G21A',
 PRIM_FILE='./archive_libs/mstr_discrete/res/chips/chips.prt';

PART_NAME
 R1U59 'RES_0402-0.0,5%,1/16W,CHIP,G21A':;

SECTION_NUMBER 1
 '@BASEBOARD_FAB2_LIB.BASEBOARD_FAB2(SCH_1):PAGE152_I74@MSTR_DISCRETE.RES(CHIPS)':
 C_PATH='@baseboard_fab2_lib.baseboard_fab2(sch_1):page152_i74@mstr_discrete.res~
(chips)',
 P_PATH='@baseboard_fab2_lib.baseboard_fab2(sch_1):page152_i74@mstr_discrete.res~
(chips)',
 PATH='I74',
 DRAWING='@BASEBOARD_FAB2_LIB.BASEBOARD_FAB2(SCH_1):PAGE152',
 WATTAGE='1/16W',
 TOLERANCE='5%',
 SEC_TYPE='0402',
 MATERIAL='CHIP',
 PHYS_PAGE='152',
 XY='(-3375,4250)',
 ROT='0',
 VER='1',
 VALUE='0.0',
 PACK_TYPE='0402',
 PART_NUMBER='G21497-005',
 LOCATION='R1U59',
 SEC='1',
 CDS_LIB='mstr_discrete',
 CDS_PART_NAME='RES_0402-0.0,5%,1/16W,CHIP,G21A',
 PRIM_FILE='./archive_libs/mstr_discrete/res/chips/chips.prt';

PART_NAME
 R1U60 'RES_0402-0.0,5%,1/16W,CHIP,G21A':;

SECTION_NUMBER 1
 '@BASEBOARD_FAB2_LIB.BASEBOARD_FAB2(SCH_1):PAGE152_I65@MSTR_DISCRETE.RES(CHIPS)':
 C_PATH='@baseboard_fab2_lib.baseboard_fab2(sch_1):page152_i65@mstr_discrete.res~
(chips)',
 P_PATH='@baseboard_fab2_lib.baseboard_fab2(sch_1):page152_i65@mstr_discrete.res~
(chips)',
 PATH='I65',
 DRAWING='@BASEBOARD_FAB2_LIB.BASEBOARD_FAB2(SCH_1):PAGE152',
 WATTAGE='1/16W',
 TOLERANCE='5%',
 SEC_TYPE='0402',
 MATERIAL='CHIP',
 PHYS_PAGE='152',
 XY='(-6950,3750)',
 ROT='0',
 VER='1',
 VALUE='0.0',
 PACK_TYPE='0402',
 PART_NUMBER='G21497-005',
 LOCATION='R1U60',
 SEC='1',
 CDS_LIB='mstr_discrete',
 CDS_PART_NAME='RES_0402-0.0,5%,1/16W,CHIP,G21A',
 PRIM_FILE='./archive_libs/mstr_discrete/res/chips/chips.prt';

PART_NAME
 R1U61 'RES_0402-0.0,5%,1/16W,EMPTY,G2A':;

SECTION_NUMBER 1
 '@BASEBOARD_FAB2_LIB.BASEBOARD_FAB2(SCH_1):PAGE152_I70@MSTR_DISCRETE.RES(CHIPS)':
 C_PATH='@baseboard_fab2_lib.baseboard_fab2(sch_1):page152_i70@mstr_discrete.res~
(chips)',
 P_PATH='@baseboard_fab2_lib.baseboard_fab2(sch_1):page152_i70@mstr_discrete.res~
(chips)',
 PATH='I70',
 DRAWING='@BASEBOARD_FAB2_LIB.BASEBOARD_FAB2(SCH_1):PAGE152',
 WATTAGE='1/16W',
 TOLERANCE='5%',
 SEC_TYPE='0402',
 MATERIAL='EMPTY',
 PHYS_PAGE='152',
 XY='(-2875,3425)',
 ROT='0',
 VER='2',
 VALUE='0.0',
 PACK_TYPE='0402',
 PART_NUMBER='G21497-005',
 LOCATION='R1U61',
 SEC='1',
 CDS_LIB='mstr_discrete',
 CDS_PART_NAME='RES_0402-0.0,5%,1/16W,EMPTY,G2A',
 PRIM_FILE='./archive_libs/mstr_discrete/res/chips/chips.prt';

PART_NAME
 R1U62 'RES_0402-0.0,5%,1/16W,EMPTY,G2A':;

SECTION_NUMBER 1
 '@BASEBOARD_FAB2_LIB.BASEBOARD_FAB2(SCH_1):PAGE152_I68@MSTR_DISCRETE.RES(CHIPS)':
 C_PATH='@baseboard_fab2_lib.baseboard_fab2(sch_1):page152_i68@mstr_discrete.res~
(chips)',
 P_PATH='@baseboard_fab2_lib.baseboard_fab2(sch_1):page152_i68@mstr_discrete.res~
(chips)',
 PATH='I68',
 DRAWING='@BASEBOARD_FAB2_LIB.BASEBOARD_FAB2(SCH_1):PAGE152',
 WATTAGE='1/16W',
 TOLERANCE='5%',
 SEC_TYPE='0402',
 MATERIAL='EMPTY',
 PHYS_PAGE='152',
 XY='(-7450,3500)',
 ROT='0',
 VER='2',
 VALUE='0.0',
 PACK_TYPE='0402',
 PART_NUMBER='G21497-005',
 LOCATION='R1U62',
 SEC='1',
 CDS_LIB='mstr_discrete',
 CDS_PART_NAME='RES_0402-0.0,5%,1/16W,EMPTY,G2A',
 PRIM_FILE='./archive_libs/mstr_discrete/res/chips/chips.prt';

PART_NAME
 R1U63 'RES_0402-1.00K,1%,1/16W,CHIP,GA':
 ROOM='SB';

SECTION_NUMBER 1
 '@BASEBOARD_FAB2_LIB.BASEBOARD_FAB2(SCH_1):PAGE137_I15@MSTR_DISCRETE.RES(CHIPS)':
 C_PATH='@baseboard_fab2_lib.baseboard_fab2(sch_1):page137_i15@mstr_discrete.res~
(chips)',
 P_PATH='@baseboard_fab2_lib.baseboard_fab2(sch_1):page137_i15@mstr_discrete.res~
(chips)',
 PATH='I15',
 DRAWING='@BASEBOARD_FAB2_LIB.BASEBOARD_FAB2(SCH_1):PAGE137',
 WATTAGE='1/16W',
 TOLERANCE='1%',
 SEC_TYPE='0402',
 MATERIAL='CHIP',
 BOM_COST='SB',
 PHYS_PAGE='137',
 XY='(-275,3450)',
 ROT='2',
 VER='2',
 VALUE='1.00K',
 PACK_TYPE='0402',
 PART_NUMBER='G21796-026',
 LOCATION='R1U63',
 ROOM='SB',
 SEC='1',
 CDS_LIB='mstr_discrete',
 CDS_PART_NAME='RES_0402-1.00K,1%,1/16W,CHIP,GA',
 PRIM_FILE='./archive_libs/mstr_discrete/res/chips/chips.prt';

PART_NAME
 R1U64 'RES_0402-1.00K,1%,1/16W,CHIP,GA':
 ROOM='SB';

SECTION_NUMBER 1
 '@BASEBOARD_FAB2_LIB.BASEBOARD_FAB2(SCH_1):PAGE137_I69@MSTR_DISCRETE.RES(CHIPS)':
 C_PATH='@baseboard_fab2_lib.baseboard_fab2(sch_1):page137_i69@mstr_discrete.res~
(chips)',
 P_PATH='@baseboard_fab2_lib.baseboard_fab2(sch_1):page137_i69@mstr_discrete.res~
(chips)',
 PATH='I69',
 DRAWING='@BASEBOARD_FAB2_LIB.BASEBOARD_FAB2(SCH_1):PAGE137',
 WATTAGE='1/16W',
 TOLERANCE='1%',
 SEC_TYPE='0402',
 MATERIAL='CHIP',
 BOM_COST='SB',
 PHYS_PAGE='137',
 XY='(-3150,3275)',
 ROT='0',
 VER='2',
 VALUE='1.00K',
 PACK_TYPE='0402',
 PART_NUMBER='G21796-026',
 LOCATION='R1U64',
 ROOM='SB',
 SEC='1',
 CDS_LIB='mstr_discrete',
 CDS_PART_NAME='RES_0402-1.00K,1%,1/16W,CHIP,GA',
 PRIM_FILE='./archive_libs/mstr_discrete/res/chips/chips.prt';

PART_NAME
 R1W1 '1MR2F-L-GP_SMD-RG1-1MR2F-L-GP,A':;

SECTION_NUMBER 1
 '@BASEBOARD_FAB2_LIB.BASEBOARD_FAB2(SCH_1):PAGE250_I18@W_HDL.1MR2F-L-GP(CHIPS)':
 C_PATH='@baseboard_fab2_lib.baseboard_fab2(sch_1):page250_i18@w_hdl.\1mr2f-l-gp~
\(chips)',
 P_PATH='@baseboard_fab2_lib.baseboard_fab2(sch_1):page250_i18@w_hdl.\1mr2f-l-gp~
\(chips)',
 PATH='I18',
 DRAWING='@BASEBOARD_FAB2_LIB.BASEBOARD_FAB2(SCH_1):PAGE250',
 PACK_SIZE='0402',
 RATED='1/16W',
 ATTRIBUTE='1MOHM',
 TOLERANCE='1%',
 PHYS_PAGE='250',
 XY='(-8300,5500)',
 ROT='0',
 VER='1',
 VALUE='1MR2F-L-GP',
 PACK_TYPE='SMD-RG1',
 PART_NUMBER='64.10045.L1L',
 LOCATION='R1W1',
 CDS_LIB='w_hdl',
 CDS_PART_NAME='1MR2F-L-GP_SMD-RG1-1MR2F-L-GP,A',
 PRIM_FILE='C:/<user>/w_hdl/1mr2f#2dl#2dgp/chips/chips.prt';

PART_NAME
 R1W3 '1MR2F-L-GP_SMD-RG1-1MR2F-L-GP,A':;

SECTION_NUMBER 1
 '@BASEBOARD_FAB2_LIB.BASEBOARD_FAB2(SCH_1):PAGE250_I27@W_HDL.1MR2F-L-GP(CHIPS)':
 C_PATH='@baseboard_fab2_lib.baseboard_fab2(sch_1):page250_i27@w_hdl.\1mr2f-l-gp~
\(chips)',
 P_PATH='@baseboard_fab2_lib.baseboard_fab2(sch_1):page250_i27@w_hdl.\1mr2f-l-gp~
\(chips)',
 PATH='I27',
 DRAWING='@BASEBOARD_FAB2_LIB.BASEBOARD_FAB2(SCH_1):PAGE250',
 PACK_SIZE='0402',
 RATED='1/16W',
 ATTRIBUTE='1MOHM',
 TOLERANCE='1%',
 PHYS_PAGE='250',
 XY='(-8300,4350)',
 ROT='0',
 VER='1',
 VALUE='1MR2F-L-GP',
 PACK_TYPE='SMD-RG1',
 PART_NUMBER='64.10045.L1L',
 LOCATION='R1W3',
 CDS_LIB='w_hdl',
 CDS_PART_NAME='1MR2F-L-GP_SMD-RG1-1MR2F-L-GP,A',
 PRIM_FILE='C:/<user>/w_hdl/1mr2f#2dl#2dgp/chips/chips.prt';

PART_NAME
 R1W4 'RES_0402-10.0K,1%,1/16W,CHIP,GA':
 ROOM='SB';

SECTION_NUMBER 1
 '@BASEBOARD_FAB2_LIB.BASEBOARD_FAB2(SCH_1):PAGE250_I22@MSTR_DISCRETE.RES(CHIPS)':
 C_PATH='@baseboard_fab2_lib.baseboard_fab2(sch_1):page250_i22@mstr_discrete.res~
(chips)',
 P_PATH='@baseboard_fab2_lib.baseboard_fab2(sch_1):page250_i22@mstr_discrete.res~
(chips)',
 PATH='I22',
 DRAWING='@BASEBOARD_FAB2_LIB.BASEBOARD_FAB2(SCH_1):PAGE250',
 WATTAGE='1/16W',
 TOLERANCE='1%',
 SEC_TYPE='0402',
 MATERIAL='CHIP',
 PHYS_PAGE='250',
 XY='(-7350,4700)',
 ROT='1',
 VER='1',
 VALUE='10.0K',
 PACK_TYPE='0402',
 PART_NUMBER='G21796-016',
 LOCATION='R1W4',
 ROOM='SB',
 SEC='1',
 CDS_LIB='mstr_discrete',
 CDS_PART_NAME='RES_0402-10.0K,1%,1/16W,CHIP,GA',
 PRIM_FILE='./archive_libs/mstr_discrete/res/chips/chips.prt';

PART_NAME
 R1W6 '1MR2F-L-GP_SMD-RG1-1MR2F-L-GP,A':;

SECTION_NUMBER 1
 '@BASEBOARD_FAB2_LIB.BASEBOARD_FAB2(SCH_1):PAGE250_I2@W_HDL.1MR2F-L-GP(CHIPS)':
 C_PATH='@baseboard_fab2_lib.baseboard_fab2(sch_1):page250_i2@w_hdl.\1mr2f-l-gp\~
(chips)',
 P_PATH='@baseboard_fab2_lib.baseboard_fab2(sch_1):page250_i2@w_hdl.\1mr2f-l-gp\~
(chips)',
 PATH='I2',
 DRAWING='@BASEBOARD_FAB2_LIB.BASEBOARD_FAB2(SCH_1):PAGE250',
 PACK_SIZE='0402',
 RATED='1/16W',
 ATTRIBUTE='1MOHM',
 TOLERANCE='1%',
 PHYS_PAGE='250',
 XY='(-8725,2575)',
 ROT='0',
 VER='1',
 VALUE='1MR2F-L-GP',
 PACK_TYPE='SMD-RG1',
 PART_NUMBER='64.10045.L1L',
 LOCATION='R1W6',
 CDS_LIB='w_hdl',
 CDS_PART_NAME='1MR2F-L-GP_SMD-RG1-1MR2F-L-GP,A',
 PRIM_FILE='C:/<user>/w_hdl/1mr2f#2dl#2dgp/chips/chips.prt';

PART_NAME
 R1W7 'RES_0402-10.0K,1%,1/16W,CHIP,GA':
 ROOM='SB';

SECTION_NUMBER 1
 '@BASEBOARD_FAB2_LIB.BASEBOARD_FAB2(SCH_1):PAGE250_I6@MSTR_DISCRETE.RES(CHIPS)':
 C_PATH='@baseboard_fab2_lib.baseboard_fab2(sch_1):page250_i6@mstr_discrete.res(~
chips)',
 P_PATH='@baseboard_fab2_lib.baseboard_fab2(sch_1):page250_i6@mstr_discrete.res(~
chips)',
 PATH='I6',
 DRAWING='@BASEBOARD_FAB2_LIB.BASEBOARD_FAB2(SCH_1):PAGE250',
 WATTAGE='1/16W',
 TOLERANCE='1%',
 SEC_TYPE='0402',
 MATERIAL='CHIP',
 PHYS_PAGE='250',
 XY='(-7700,2900)',
 ROT='1',
 VER='1',
 VALUE='10.0K',
 PACK_TYPE='0402',
 PART_NUMBER='G21796-016',
 LOCATION='R1W7',
 ROOM='SB',
 SEC='1',
 CDS_LIB='mstr_discrete',
 CDS_PART_NAME='RES_0402-10.0K,1%,1/16W,CHIP,GA',
 PRIM_FILE='./archive_libs/mstr_discrete/res/chips/chips.prt';

PART_NAME
 R1W9 'RES_0402-22.1,1.0%,1/16W,CHIP,A':
 ROOM='P1V538_BMC_STBY_VR';

SECTION_NUMBER 1
 '@BASEBOARD_FAB2_LIB.BASEBOARD_FAB2(SCH_1):PAGE239_I77@MSTR_DISCRETE.RES(CHIPS)':
 C_PATH='@baseboard_fab2_lib.baseboard_fab2(sch_1):page239_i77@mstr_discrete.res~
(chips)',
 P_PATH='@baseboard_fab2_lib.baseboard_fab2(sch_1):page239_i77@mstr_discrete.res~
(chips)',
 PATH='I77',
 DRAWING='@BASEBOARD_FAB2_LIB.BASEBOARD_FAB2(SCH_1):PAGE239',
 WATTAGE='1/16W',
 TOLERANCE='1.0%',
 SEC_TYPE='0402',
 MATERIAL='CHIP',
 PHYS_PAGE='239',
 XY='(10275,2200)',
 ROT='0',
 VER='1',
 VALUE='22.1',
 PACK_TYPE='0402',
 PART_NUMBER='G21796-250',
 LOCATION='R1W9',
 ROOM='P1V538_BMC_STBY_VR',
 SEC='1',
 CDS_LIB='mstr_discrete',
 CDS_PART_NAME='RES_0402-22.1,1.0%,1/16W,CHIP,A',
 PRIM_FILE='./archive_libs/mstr_discrete/res/chips/chips.prt';

PART_NAME
 R1W10 'RES_0805-0.0,5%,1/8W,CHIP,G221A':
 ROOM='HOT_SWAP';

SECTION_NUMBER 1
 '@BASEBOARD_FAB2_LIB.BASEBOARD_FAB2(SCH_1):PAGE176_I132@MSTR_DISCRETE.RES(CHIPS)':
 C_PATH='@baseboard_fab2_lib.baseboard_fab2(sch_1):page176_i132@mstr_discrete.re~
s(chips)',
 P_PATH='@baseboard_fab2_lib.baseboard_fab2(sch_1):page176_i132@mstr_discrete.re~
s(chips)',
 PATH='I132',
 DRAWING='@BASEBOARD_FAB2_LIB.BASEBOARD_FAB2(SCH_1):PAGE176',
 WATTAGE='1/8W',
 TOLERANCE='5%',
 SEC_TYPE='0805',
 MATERIAL='CHIP',
 PHYS_PAGE='176',
 XY='(-5350,3950)',
 ROT='5',
 VER='1',
 VALUE='0.0',
 PACK_TYPE='0805',
 PART_NUMBER='G22179-004',
 LOCATION='R1W10',
 ROOM='HOT_SWAP',
 SEC='1',
 CDS_LIB='mstr_discrete',
 CDS_PART_NAME='RES_0805-0.0,5%,1/8W,CHIP,G221A',
 PRIM_FILE='./archive_libs/mstr_discrete/res/chips/chips.prt';

PART_NAME
 R1W11 'RES_0805-0.0,5%,1/8W,EMPTY,G22A':;

SECTION_NUMBER 1
 '@BASEBOARD_FAB2_LIB.BASEBOARD_FAB2(SCH_1):PAGE176_I133@MSTR_DISCRETE.RES(CHIPS)':
 C_PATH='@baseboard_fab2_lib.baseboard_fab2(sch_1):page176_i133@mstr_discrete.re~
s(chips)',
 P_PATH='@baseboard_fab2_lib.baseboard_fab2(sch_1):page176_i133@mstr_discrete.re~
s(chips)',
 PATH='I133',
 DRAWING='@BASEBOARD_FAB2_LIB.BASEBOARD_FAB2(SCH_1):PAGE176',
 WATTAGE='1/8W',
 TOLERANCE='5%',
 SEC_TYPE='0805',
 MATERIAL='EMPTY',
 PHYS_PAGE='176',
 XY='(-4950,3950)',
 ROT='5',
 VER='1',
 VALUE='0.0',
 PACK_TYPE='0805',
 PART_NUMBER='G22179-004',
 LOCATION='R1W11',
 SEC='1',
 CDS_LIB='mstr_discrete',
 CDS_PART_NAME='RES_0805-0.0,5%,1/8W,EMPTY,G22A',
 PRIM_FILE='./archive_libs/mstr_discrete/res/chips/chips.prt';

PART_NAME
 R1W12 'RES_0402-0.0,5%,1/16W,CHIP,G21A':
 ROOM='CPU0';

SECTION_NUMBER 1
 '@BASEBOARD_FAB2_LIB.BASEBOARD_FAB2(SCH_1):PAGE176_I137@MSTR_DISCRETE.RES(CHIPS)':
 C_PATH='@baseboard_fab2_lib.baseboard_fab2(sch_1):page176_i137@mstr_discrete.re~
s(chips)',
 P_PATH='@baseboard_fab2_lib.baseboard_fab2(sch_1):page176_i137@mstr_discrete.re~
s(chips)',
 PATH='I137',
 DRAWING='@BASEBOARD_FAB2_LIB.BASEBOARD_FAB2(SCH_1):PAGE176',
 WATTAGE='1/16W',
 TOLERANCE='5%',
 SEC_TYPE='0402',
 MATERIAL='CHIP',
 BOM_COST='PROC_SIDEBAND',
 PHYS_PAGE='176',
 XY='(-5650,3225)',
 ROT='0',
 VER='1',
 VALUE='0.0',
 PACK_TYPE='0402',
 PART_NUMBER='G21497-005',
 LOCATION='R1W12',
 ROOM='CPU0',
 SEC='1',
 CDS_LIB='mstr_discrete',
 CDS_PART_NAME='RES_0402-0.0,5%,1/16W,CHIP,G21A',
 PRIM_FILE='./archive_libs/mstr_discrete/res/chips/chips.prt';

PART_NAME
 R1W13 'RES_0402-0.0,5%,1/16W,CHIP,G21A':
 ROOM='CPU0';

SECTION_NUMBER 1
 '@BASEBOARD_FAB2_LIB.BASEBOARD_FAB2(SCH_1):PAGE176_I138@MSTR_DISCRETE.RES(CHIPS)':
 C_PATH='@baseboard_fab2_lib.baseboard_fab2(sch_1):page176_i138@mstr_discrete.re~
s(chips)',
 P_PATH='@baseboard_fab2_lib.baseboard_fab2(sch_1):page176_i138@mstr_discrete.re~
s(chips)',
 PATH='I138',
 DRAWING='@BASEBOARD_FAB2_LIB.BASEBOARD_FAB2(SCH_1):PAGE176',
 POP='NOPOP',
 WATTAGE='1/16W',
 TOLERANCE='5%',
 SEC_TYPE='0402',
 MATERIAL='CHIP',
 BOM_COST='PROC_SIDEBAND',
 PHYS_PAGE='176',
 XY='(-5650,3000)',
 ROT='0',
 VER='1',
 VALUE='0.0',
 PACK_TYPE='0402',
 PART_NUMBER='G21497-005',
 LOCATION='R1W13',
 ROOM='CPU0',
 SEC='1',
 CDS_LIB='mstr_discrete',
 CDS_PART_NAME='RES_0402-0.0,5%,1/16W,CHIP,G21A',
 PRIM_FILE='./archive_libs/mstr_discrete/res/chips/chips.prt';

PART_NAME
 R1W14 'RES_0402-0.0,5%,1/16W,CHIP,G21A':
 ROOM='BMC';

SECTION_NUMBER 1
 '@BASEBOARD_FAB2_LIB.BASEBOARD_FAB2(SCH_1):PAGE115_I118@MSTR_DISCRETE.RES(CHIPS)':
 C_PATH='@baseboard_fab2_lib.baseboard_fab2(sch_1):page115_i118@mstr_discrete.re~
s(chips)',
 P_PATH='@baseboard_fab2_lib.baseboard_fab2(sch_1):page115_i118@mstr_discrete.re~
s(chips)',
 PATH='I118',
 DRAWING='@BASEBOARD_FAB2_LIB.BASEBOARD_FAB2(SCH_1):PAGE115',
 WATTAGE='1/16W',
 TOLERANCE='5%',
 SEC_TYPE='0402',
 MATERIAL='CHIP',
 BOM_COST='SM_CONTROLLER',
 PHYS_PAGE='115',
 XY='(-2150,1950)',
 ROT='0',
 VER='1',
 VALUE='0.0',
 PACK_TYPE='0402',
 PART_NUMBER='G21497-005',
 LOCATION='R1W14',
 ROOM='BMC',
 SEC='1',
 CDS_LIB='mstr_discrete',
 CDS_PART_NAME='RES_0402-0.0,5%,1/16W,CHIP,G21A',
 PRIM_FILE='./archive_libs/mstr_discrete/res/chips/chips.prt';

PART_NAME
 R1W15 'RES_0402-0.0,5%,1/16W,CHIP,G21A':
 ROOM='BMC';

SECTION_NUMBER 1
 '@BASEBOARD_FAB2_LIB.BASEBOARD_FAB2(SCH_1):PAGE115_I119@MSTR_DISCRETE.RES(CHIPS)':
 C_PATH='@baseboard_fab2_lib.baseboard_fab2(sch_1):page115_i119@mstr_discrete.re~
s(chips)',
 P_PATH='@baseboard_fab2_lib.baseboard_fab2(sch_1):page115_i119@mstr_discrete.re~
s(chips)',
 PATH='I119',
 DRAWING='@BASEBOARD_FAB2_LIB.BASEBOARD_FAB2(SCH_1):PAGE115',
 WATTAGE='1/16W',
 TOLERANCE='5%',
 SEC_TYPE='0402',
 MATERIAL='CHIP',
 BOM_COST='SM_CONTROLLER',
 PHYS_PAGE='115',
 XY='(-2150,1900)',
 ROT='0',
 VER='1',
 VALUE='0.0',
 PACK_TYPE='0402',
 PART_NUMBER='G21497-005',
 LOCATION='R1W15',
 ROOM='BMC',
 SEC='1',
 CDS_LIB='mstr_discrete',
 CDS_PART_NAME='RES_0402-0.0,5%,1/16W,CHIP,G21A',
 PRIM_FILE='./archive_libs/mstr_discrete/res/chips/chips.prt';

PART_NAME
 R1W16 'RES_0402-0.0,5%,1/16W,CHIP,G21A':
 ROOM='BMC';

SECTION_NUMBER 1
 '@BASEBOARD_FAB2_LIB.BASEBOARD_FAB2(SCH_1):PAGE115_I121@MSTR_DISCRETE.RES(CHIPS)':
 C_PATH='@baseboard_fab2_lib.baseboard_fab2(sch_1):page115_i121@mstr_discrete.re~
s(chips)',
 P_PATH='@baseboard_fab2_lib.baseboard_fab2(sch_1):page115_i121@mstr_discrete.re~
s(chips)',
 PATH='I121',
 DRAWING='@BASEBOARD_FAB2_LIB.BASEBOARD_FAB2(SCH_1):PAGE115',
 WATTAGE='1/16W',
 TOLERANCE='5%',
 SEC_TYPE='0402',
 MATERIAL='CHIP',
 BOM_COST='SM_CONTROLLER',
 PHYS_PAGE='115',
 XY='(-2150,1850)',
 ROT='0',
 VER='1',
 VALUE='0.0',
 PACK_TYPE='0402',
 PART_NUMBER='G21497-005',
 LOCATION='R1W16',
 ROOM='BMC',
 SEC='1',
 CDS_LIB='mstr_discrete',
 CDS_PART_NAME='RES_0402-0.0,5%,1/16W,CHIP,G21A',
 PRIM_FILE='./archive_libs/mstr_discrete/res/chips/chips.prt';

PART_NAME
 R1W17 'RES_0402-0.0,5%,1/16W,CHIP,G21A':
 ROOM='BMC';

SECTION_NUMBER 1
 '@BASEBOARD_FAB2_LIB.BASEBOARD_FAB2(SCH_1):PAGE115_I120@MSTR_DISCRETE.RES(CHIPS)':
 C_PATH='@baseboard_fab2_lib.baseboard_fab2(sch_1):page115_i120@mstr_discrete.re~
s(chips)',
 P_PATH='@baseboard_fab2_lib.baseboard_fab2(sch_1):page115_i120@mstr_discrete.re~
s(chips)',
 PATH='I120',
 DRAWING='@BASEBOARD_FAB2_LIB.BASEBOARD_FAB2(SCH_1):PAGE115',
 WATTAGE='1/16W',
 TOLERANCE='5%',
 SEC_TYPE='0402',
 MATERIAL='CHIP',
 BOM_COST='SM_CONTROLLER',
 PHYS_PAGE='115',
 XY='(-2150,1800)',
 ROT='0',
 VER='1',
 VALUE='0.0',
 PACK_TYPE='0402',
 PART_NUMBER='G21497-005',
 LOCATION='R1W17',
 ROOM='BMC',
 SEC='1',
 CDS_LIB='mstr_discrete',
 CDS_PART_NAME='RES_0402-0.0,5%,1/16W,CHIP,G21A',
 PRIM_FILE='./archive_libs/mstr_discrete/res/chips/chips.prt';

PART_NAME
 R1W18 'RES_0402-0.0,5%,1/16W,CHIP,G21A':
 ROOM='BMC';

SECTION_NUMBER 1
 '@BASEBOARD_FAB2_LIB.BASEBOARD_FAB2(SCH_1):PAGE115_I123@MSTR_DISCRETE.RES(CHIPS)':
 C_PATH='@baseboard_fab2_lib.baseboard_fab2(sch_1):page115_i123@mstr_discrete.re~
s(chips)',
 P_PATH='@baseboard_fab2_lib.baseboard_fab2(sch_1):page115_i123@mstr_discrete.re~
s(chips)',
 PATH='I123',
 DRAWING='@BASEBOARD_FAB2_LIB.BASEBOARD_FAB2(SCH_1):PAGE115',
 WATTAGE='1/16W',
 TOLERANCE='5%',
 SEC_TYPE='0402',
 MATERIAL='CHIP',
 BOM_COST='SM_CONTROLLER',
 PHYS_PAGE='115',
 XY='(-2150,1650)',
 ROT='0',
 VER='1',
 VALUE='0.0',
 PACK_TYPE='0402',
 PART_NUMBER='G21497-005',
 LOCATION='R1W18',
 ROOM='BMC',
 SEC='1',
 CDS_LIB='mstr_discrete',
 CDS_PART_NAME='RES_0402-0.0,5%,1/16W,CHIP,G21A',
 PRIM_FILE='./archive_libs/mstr_discrete/res/chips/chips.prt';

PART_NAME
 R1W19 'RES_0402-0.0,5%,1/16W,CHIP,G21A':
 ROOM='BMC';

SECTION_NUMBER 1
 '@BASEBOARD_FAB2_LIB.BASEBOARD_FAB2(SCH_1):PAGE115_I122@MSTR_DISCRETE.RES(CHIPS)':
 C_PATH='@baseboard_fab2_lib.baseboard_fab2(sch_1):page115_i122@mstr_discrete.re~
s(chips)',
 P_PATH='@baseboard_fab2_lib.baseboard_fab2(sch_1):page115_i122@mstr_discrete.re~
s(chips)',
 PATH='I122',
 DRAWING='@BASEBOARD_FAB2_LIB.BASEBOARD_FAB2(SCH_1):PAGE115',
 WATTAGE='1/16W',
 TOLERANCE='5%',
 SEC_TYPE='0402',
 MATERIAL='CHIP',
 BOM_COST='SM_CONTROLLER',
 PHYS_PAGE='115',
 XY='(-2150,1600)',
 ROT='0',
 VER='1',
 VALUE='0.0',
 PACK_TYPE='0402',
 PART_NUMBER='G21497-005',
 LOCATION='R1W19',
 ROOM='BMC',
 SEC='1',
 CDS_LIB='mstr_discrete',
 CDS_PART_NAME='RES_0402-0.0,5%,1/16W,CHIP,G21A',
 PRIM_FILE='./archive_libs/mstr_discrete/res/chips/chips.prt';

PART_NAME
 R1W20 'RES_0402-0.0,5%,1/16W,CHIP,G21A':
 ROOM='CPU0';

SECTION_NUMBER 1
 '@BASEBOARD_FAB2_LIB.BASEBOARD_FAB2(SCH_1):PAGE199_I134@MSTR_DISCRETE.RES(CHIPS)':
 C_PATH='@baseboard_fab2_lib.baseboard_fab2(sch_1):page199_i134@mstr_discrete.re~
s(chips)',
 P_PATH='@baseboard_fab2_lib.baseboard_fab2(sch_1):page199_i134@mstr_discrete.re~
s(chips)',
 PATH='I134',
 DRAWING='@BASEBOARD_FAB2_LIB.BASEBOARD_FAB2(SCH_1):PAGE199',
 WATTAGE='1/16W',
 TOLERANCE='5%',
 SEC_TYPE='0402',
 MATERIAL='CHIP',
 BOM_COST='PROC_SIDEBAND',
 PHYS_PAGE='199',
 XY='(-1250,1850)',
 ROT='0',
 VER='1',
 VALUE='0.0',
 PACK_TYPE='0402',
 PART_NUMBER='G21497-005',
 LOCATION='R1W20',
 ROOM='CPU0',
 SEC='1',
 CDS_LIB='mstr_discrete',
 CDS_PART_NAME='RES_0402-0.0,5%,1/16W,CHIP,G21A',
 PRIM_FILE='./archive_libs/mstr_discrete/res/chips/chips.prt';

PART_NAME
 R1W21 'RES_0402-0.0,5%,1/16W,CHIP,G21A':
 ROOM='CPU0';

SECTION_NUMBER 1
 '@BASEBOARD_FAB2_LIB.BASEBOARD_FAB2(SCH_1):PAGE199_I135@MSTR_DISCRETE.RES(CHIPS)':
 C_PATH='@baseboard_fab2_lib.baseboard_fab2(sch_1):page199_i135@mstr_discrete.re~
s(chips)',
 P_PATH='@baseboard_fab2_lib.baseboard_fab2(sch_1):page199_i135@mstr_discrete.re~
s(chips)',
 PATH='I135',
 DRAWING='@BASEBOARD_FAB2_LIB.BASEBOARD_FAB2(SCH_1):PAGE199',
 WATTAGE='1/16W',
 TOLERANCE='5%',
 SEC_TYPE='0402',
 MATERIAL='CHIP',
 BOM_COST='PROC_SIDEBAND',
 PHYS_PAGE='199',
 XY='(-1250,1550)',
 ROT='0',
 VER='1',
 VALUE='0.0',
 PACK_TYPE='0402',
 PART_NUMBER='G21497-005',
 LOCATION='R1W21',
 ROOM='CPU0',
 SEC='1',
 CDS_LIB='mstr_discrete',
 CDS_PART_NAME='RES_0402-0.0,5%,1/16W,CHIP,G21A',
 PRIM_FILE='./archive_libs/mstr_discrete/res/chips/chips.prt';

PART_NAME
 R1W22 'RES_0402-0.0,5%,1/16W,CHIP,G21A':
 ROOM='IO_SLOT';

SECTION_NUMBER 1
 '@BASEBOARD_FAB2_LIB.BASEBOARD_FAB2(SCH_1):PAGE101_I134@MSTR_DISCRETE.RES(CHIPS)':
 C_PATH='@baseboard_fab2_lib.baseboard_fab2(sch_1):page101_i134@mstr_discrete.re~
s(chips)',
 P_PATH='@baseboard_fab2_lib.baseboard_fab2(sch_1):page101_i134@mstr_discrete.re~
s(chips)',
 PATH='I134',
 DRAWING='@BASEBOARD_FAB2_LIB.BASEBOARD_FAB2(SCH_1):PAGE101',
 WATTAGE='1/16W',
 TOLERANCE='5%',
 SEC_TYPE='0402',
 MATERIAL='CHIP',
 PHYS_PAGE='101',
 XY='(-7125,1950)',
 ROT='0',
 VER='1',
 VALUE='0.0',
 PACK_TYPE='0402',
 PART_NUMBER='G21497-005',
 LOCATION='R1W22',
 ROOM='IO_SLOT',
 SEC='1',
 CDS_LIB='mstr_discrete',
 CDS_PART_NAME='RES_0402-0.0,5%,1/16W,CHIP,G21A',
 PRIM_FILE='./archive_libs/mstr_discrete/res/chips/chips.prt';

PART_NAME
 R1W23 'RES_0402-0.0,5%,1/16W,CHIP,G21A':
 ROOM='IO_SLOT';

SECTION_NUMBER 1
 '@BASEBOARD_FAB2_LIB.BASEBOARD_FAB2(SCH_1):PAGE101_I135@MSTR_DISCRETE.RES(CHIPS)':
 C_PATH='@baseboard_fab2_lib.baseboard_fab2(sch_1):page101_i135@mstr_discrete.re~
s(chips)',
 P_PATH='@baseboard_fab2_lib.baseboard_fab2(sch_1):page101_i135@mstr_discrete.re~
s(chips)',
 PATH='I135',
 DRAWING='@BASEBOARD_FAB2_LIB.BASEBOARD_FAB2(SCH_1):PAGE101',
 WATTAGE='1/16W',
 TOLERANCE='5%',
 SEC_TYPE='0402',
 MATERIAL='CHIP',
 PHYS_PAGE='101',
 XY='(-7125,1825)',
 ROT='0',
 VER='1',
 VALUE='0.0',
 PACK_TYPE='0402',
 PART_NUMBER='G21497-005',
 LOCATION='R1W23',
 ROOM='IO_SLOT',
 SEC='1',
 CDS_LIB='mstr_discrete',
 CDS_PART_NAME='RES_0402-0.0,5%,1/16W,CHIP,G21A',
 PRIM_FILE='./archive_libs/mstr_discrete/res/chips/chips.prt';

PART_NAME
 R1W24 'RES_0402-0.0,5%,1/16W,CHIP,G21A':
 ROOM='IO_SLOT';

SECTION_NUMBER 1
 '@BASEBOARD_FAB2_LIB.BASEBOARD_FAB2(SCH_1):PAGE101_I138@MSTR_DISCRETE.RES(CHIPS)':
 C_PATH='@baseboard_fab2_lib.baseboard_fab2(sch_1):page101_i138@mstr_discrete.re~
s(chips)',
 P_PATH='@baseboard_fab2_lib.baseboard_fab2(sch_1):page101_i138@mstr_discrete.re~
s(chips)',
 PATH='I138',
 DRAWING='@BASEBOARD_FAB2_LIB.BASEBOARD_FAB2(SCH_1):PAGE101',
 WATTAGE='1/16W',
 TOLERANCE='5%',
 SEC_TYPE='0402',
 MATERIAL='CHIP',
 PHYS_PAGE='101',
 XY='(-6925,1250)',
 ROT='0',
 VER='1',
 VALUE='0.0',
 PACK_TYPE='0402',
 PART_NUMBER='G21497-005',
 LOCATION='R1W24',
 ROOM='IO_SLOT',
 SEC='1',
 CDS_LIB='mstr_discrete',
 CDS_PART_NAME='RES_0402-0.0,5%,1/16W,CHIP,G21A',
 PRIM_FILE='./archive_libs/mstr_discrete/res/chips/chips.prt';

PART_NAME
 R1W25 'RES_0402-1.00K,1%,1/16W,CHIP,GA':
 ROOM='SYS_CLOCK';

SECTION_NUMBER 1
 '@BASEBOARD_FAB2_LIB.BASEBOARD_FAB2(SCH_1):PAGE101_I140@MSTR_DISCRETE.RES(CHIPS)':
 C_PATH='@baseboard_fab2_lib.baseboard_fab2(sch_1):page101_i140@mstr_discrete.re~
s(chips)',
 P_PATH='@baseboard_fab2_lib.baseboard_fab2(sch_1):page101_i140@mstr_discrete.re~
s(chips)',
 PATH='I140',
 DRAWING='@BASEBOARD_FAB2_LIB.BASEBOARD_FAB2(SCH_1):PAGE101',
 WATTAGE='1/16W',
 TOLERANCE='1%',
 SEC_TYPE='0402',
 MATERIAL='CHIP',
 BOM_COST='SM_CONTROLLER',
 PHYS_PAGE='101',
 XY='(-8325,1400)',
 ROT='0',
 VER='2',
 VALUE='1.00K',
 PACK_TYPE='0402',
 PART_NUMBER='G21796-026',
 LOCATION='R1W25',
 ROOM='SYS_CLOCK',
 SEC='1',
 CDS_LIB='mstr_discrete',
 CDS_PART_NAME='RES_0402-1.00K,1%,1/16W,CHIP,GA',
 PRIM_FILE='./archive_libs/mstr_discrete/res/chips/chips.prt';

PART_NAME
 R1W26 'RES_0402-10.0K,1%,1/16W,EMPTY,A':
 ROOM='DB1200ZL';

SECTION_NUMBER 1
 '@BASEBOARD_FAB2_LIB.BASEBOARD_FAB2(SCH_1):PAGE190_I349@MSTR_DISCRETE.RES(CHIPS)':
 C_PATH='@baseboard_fab2_lib.baseboard_fab2(sch_1):page190_i349@mstr_discrete.re~
s(chips)',
 P_PATH='@baseboard_fab2_lib.baseboard_fab2(sch_1):page190_i349@mstr_discrete.re~
s(chips)',
 PATH='I349',
 DRAWING='@BASEBOARD_FAB2_LIB.BASEBOARD_FAB2(SCH_1):PAGE190',
 WATTAGE='1/16W',
 TOLERANCE='1%',
 SEC_TYPE='0402',
 MATERIAL='EMPTY',
 BOM_COST='SYS_CLOCK',
 PHYS_PAGE='190',
 XY='(-1800,5000)',
 ROT='0',
 VER='2',
 VALUE='10.0K',
 PACK_TYPE='0402',
 PART_NUMBER='G21796-016',
 LOCATION='R1W26',
 ROOM='DB1200ZL',
 SEC='1',
 CDS_LIB='mstr_discrete',
 CDS_PART_NAME='RES_0402-10.0K,1%,1/16W,EMPTY,A',
 PRIM_FILE='./archive_libs/mstr_discrete/res/chips/chips.prt';

PART_NAME
 R1W27 'RES_0402-0.0,5%,1/16W,CHIP,G21A':
 ROOM='BMC';

SECTION_NUMBER 1
 '@BASEBOARD_FAB2_LIB.BASEBOARD_FAB2(SCH_1):PAGE190_I351@MSTR_DISCRETE.RES(CHIPS)':
 C_PATH='@baseboard_fab2_lib.baseboard_fab2(sch_1):page190_i351@mstr_discrete.re~
s(chips)',
 P_PATH='@baseboard_fab2_lib.baseboard_fab2(sch_1):page190_i351@mstr_discrete.re~
s(chips)',
 PATH='I351',
 DRAWING='@BASEBOARD_FAB2_LIB.BASEBOARD_FAB2(SCH_1):PAGE190',
 WATTAGE='1/16W',
 TOLERANCE='5%',
 SEC_TYPE='0402',
 MATERIAL='CHIP',
 BOM_COST='SM_CONTROLLER',
 PHYS_PAGE='190',
 XY='(-3300,3900)',
 ROT='0',
 VER='1',
 VALUE='0.0',
 PACK_TYPE='0402',
 PART_NUMBER='G21497-005',
 LOCATION='R1W27',
 ROOM='BMC',
 SEC='1',
 CDS_LIB='mstr_discrete',
 CDS_PART_NAME='RES_0402-0.0,5%,1/16W,CHIP,G21A',
 PRIM_FILE='./archive_libs/mstr_discrete/res/chips/chips.prt';

PART_NAME
 R1W28 'RES_0402-0.0,5%,1/16W,CHIP,G21A':
 ROOM='BMC';

SECTION_NUMBER 1
 '@BASEBOARD_FAB2_LIB.BASEBOARD_FAB2(SCH_1):PAGE191_I197@MSTR_DISCRETE.RES(CHIPS)':
 C_PATH='@baseboard_fab2_lib.baseboard_fab2(sch_1):page191_i197@mstr_discrete.re~
s(chips)',
 P_PATH='@baseboard_fab2_lib.baseboard_fab2(sch_1):page191_i197@mstr_discrete.re~
s(chips)',
 PATH='I197',
 DRAWING='@BASEBOARD_FAB2_LIB.BASEBOARD_FAB2(SCH_1):PAGE191',
 WATTAGE='1/16W',
 TOLERANCE='5%',
 SEC_TYPE='0402',
 MATERIAL='CHIP',
 BOM_COST='SM_CONTROLLER',
 PHYS_PAGE='191',
 XY='(-3100,1375)',
 ROT='0',
 VER='1',
 VALUE='0.0',
 PACK_TYPE='0402',
 PART_NUMBER='G21497-005',
 LOCATION='R1W28',
 ROOM='BMC',
 SEC='1',
 CDS_LIB='mstr_discrete',
 CDS_PART_NAME='RES_0402-0.0,5%,1/16W,CHIP,G21A',
 PRIM_FILE='./archive_libs/mstr_discrete/res/chips/chips.prt';

PART_NAME
 R1W29 'RES_0402-0.0,5%,1/16W,CHIP,G21A':
 ROOM='BMC';

SECTION_NUMBER 1
 '@BASEBOARD_FAB2_LIB.BASEBOARD_FAB2(SCH_1):PAGE191_I198@MSTR_DISCRETE.RES(CHIPS)':
 C_PATH='@baseboard_fab2_lib.baseboard_fab2(sch_1):page191_i198@mstr_discrete.re~
s(chips)',
 P_PATH='@baseboard_fab2_lib.baseboard_fab2(sch_1):page191_i198@mstr_discrete.re~
s(chips)',
 PATH='I198',
 DRAWING='@BASEBOARD_FAB2_LIB.BASEBOARD_FAB2(SCH_1):PAGE191',
 WATTAGE='1/16W',
 TOLERANCE='5%',
 SEC_TYPE='0402',
 MATERIAL='CHIP',
 BOM_COST='SM_CONTROLLER',
 PHYS_PAGE='191',
 XY='(-6200,3525)',
 ROT='0',
 VER='1',
 VALUE='0.0',
 PACK_TYPE='0402',
 PART_NUMBER='G21497-005',
 LOCATION='R1W29',
 ROOM='BMC',
 SEC='1',
 CDS_LIB='mstr_discrete',
 CDS_PART_NAME='RES_0402-0.0,5%,1/16W,CHIP,G21A',
 PRIM_FILE='./archive_libs/mstr_discrete/res/chips/chips.prt';

PART_NAME
 R1W30 'RES_0402-0.0,5%,1/16W,EMPTY,G2A':
 ROOM='NV_DIMM';

SECTION_NUMBER 1
 '@BASEBOARD_FAB2_LIB.BASEBOARD_FAB2(SCH_1):PAGE118_I168@MSTR_DISCRETE.RES(CHIPS)':
 C_PATH='@baseboard_fab2_lib.baseboard_fab2(sch_1):page118_i168@mstr_discrete.re~
s(chips)',
 P_PATH='@baseboard_fab2_lib.baseboard_fab2(sch_1):page118_i168@mstr_discrete.re~
s(chips)',
 PATH='I168',
 DRAWING='@BASEBOARD_FAB2_LIB.BASEBOARD_FAB2(SCH_1):PAGE118',
 WATTAGE='1/16W',
 TOLERANCE='5%',
 SEC_TYPE='0402',
 MATERIAL='EMPTY',
 BOM_COST='MEM_NV',
 PHYS_PAGE='118',
 XY='(-2725,3650)',
 ROT='0',
 VER='1',
 VALUE='0.0',
 PACK_TYPE='0402',
 PART_NUMBER='G21497-005',
 LOCATION='R1W30',
 ROOM='NV_DIMM',
 SEC='1',
 CDS_LIB='mstr_discrete',
 CDS_PART_NAME='RES_0402-0.0,5%,1/16W,EMPTY,G2A',
 PRIM_FILE='./archive_libs/mstr_discrete/res/chips/chips.prt';

PART_NAME
 R1W31 'RES_0402-330,5%,1/16W,CHIP,G21A':
 ROOM='UART_MUX';

SECTION_NUMBER 1
 '@BASEBOARD_FAB2_LIB.BASEBOARD_FAB2(SCH_1):PAGE89_I56@MSTR_DISCRETE.RES(CHIPS)':
 C_PATH='@baseboard_fab2_lib.baseboard_fab2(sch_1):page89_i56@mstr_discrete.res(~
chips)',
 P_PATH='@baseboard_fab2_lib.baseboard_fab2(sch_1):page89_i56@mstr_discrete.res(~
chips)',
 PATH='I56',
 DRAWING='@BASEBOARD_FAB2_LIB.BASEBOARD_FAB2(SCH_1):PAGE89',
 WATTAGE='1/16W',
 TOLERANCE='5%',
 SEC_TYPE='0402',
 MATERIAL='CHIP',
 BOM_COST='DEBUG',
 PHYS_PAGE='89',
 XY='(-1350,1550)',
 ROT='0',
 VER='1',
 VALUE='330',
 PACK_TYPE='0402',
 PART_NUMBER='G21497-028',
 LOCATION='R1W31',
 ROOM='UART_MUX',
 SEC='1',
 CDS_LIB='mstr_discrete',
 CDS_PART_NAME='RES_0402-330,5%,1/16W,CHIP,G21A',
 PRIM_FILE='./archive_libs/mstr_discrete/res/chips/chips.prt';

PART_NAME
 R1W32 'RES_0402-330,5%,1/16W,CHIP,G21A':
 ROOM='UART_MUX';

SECTION_NUMBER 1
 '@BASEBOARD_FAB2_LIB.BASEBOARD_FAB2(SCH_1):PAGE89_I54@MSTR_DISCRETE.RES(CHIPS)':
 C_PATH='@baseboard_fab2_lib.baseboard_fab2(sch_1):page89_i54@mstr_discrete.res(~
chips)',
 P_PATH='@baseboard_fab2_lib.baseboard_fab2(sch_1):page89_i54@mstr_discrete.res(~
chips)',
 PATH='I54',
 DRAWING='@BASEBOARD_FAB2_LIB.BASEBOARD_FAB2(SCH_1):PAGE89',
 WATTAGE='1/16W',
 TOLERANCE='5%',
 SEC_TYPE='0402',
 MATERIAL='CHIP',
 BOM_COST='DEBUG',
 PHYS_PAGE='89',
 XY='(-1350,2725)',
 ROT='0',
 VER='1',
 VALUE='330',
 PACK_TYPE='0402',
 PART_NUMBER='G21497-028',
 LOCATION='R1W32',
 ROOM='UART_MUX',
 SEC='1',
 CDS_LIB='mstr_discrete',
 CDS_PART_NAME='RES_0402-330,5%,1/16W,CHIP,G21A',
 PRIM_FILE='./archive_libs/mstr_discrete/res/chips/chips.prt';

PART_NAME
 R1W33 'RES_0402-0.0,5%,1/16W,CHIP,G21A':
 ROOM='CPU0';

SECTION_NUMBER 1
 '@BASEBOARD_FAB2_LIB.BASEBOARD_FAB2(SCH_1):PAGE176_I142@MSTR_DISCRETE.RES(CHIPS)':
 C_PATH='@baseboard_fab2_lib.baseboard_fab2(sch_1):page176_i142@mstr_discrete.re~
s(chips)',
 P_PATH='@baseboard_fab2_lib.baseboard_fab2(sch_1):page176_i142@mstr_discrete.re~
s(chips)',
 PATH='I142',
 DRAWING='@BASEBOARD_FAB2_LIB.BASEBOARD_FAB2(SCH_1):PAGE176',
 WATTAGE='1/16W',
 TOLERANCE='5%',
 SEC_TYPE='0402',
 MATERIAL='CHIP',
 BOM_COST='PROC_SIDEBAND',
 PHYS_PAGE='176',
 XY='(-1350,3900)',
 ROT='0',
 VER='1',
 VALUE='0.0',
 PACK_TYPE='0402',
 PART_NUMBER='G21497-005',
 LOCATION='R1W33',
 ROOM='CPU0',
 SEC='1',
 CDS_LIB='mstr_discrete',
 CDS_PART_NAME='RES_0402-0.0,5%,1/16W,CHIP,G21A',
 PRIM_FILE='./archive_libs/mstr_discrete/res/chips/chips.prt';

PART_NAME
 R1W34 'RES_0402-0.0,5%,1/16W,CHIP,G21A':
 ROOM='CPU0';

SECTION_NUMBER 1
 '@BASEBOARD_FAB2_LIB.BASEBOARD_FAB2(SCH_1):PAGE176_I143@MSTR_DISCRETE.RES(CHIPS)':
 C_PATH='@baseboard_fab2_lib.baseboard_fab2(sch_1):page176_i143@mstr_discrete.re~
s(chips)',
 P_PATH='@baseboard_fab2_lib.baseboard_fab2(sch_1):page176_i143@mstr_discrete.re~
s(chips)',
 PATH='I143',
 DRAWING='@BASEBOARD_FAB2_LIB.BASEBOARD_FAB2(SCH_1):PAGE176',
 WATTAGE='1/16W',
 TOLERANCE='5%',
 SEC_TYPE='0402',
 MATERIAL='CHIP',
 BOM_COST='PROC_SIDEBAND',
 PHYS_PAGE='176',
 XY='(-1350,3850)',
 ROT='0',
 VER='1',
 VALUE='0.0',
 PACK_TYPE='0402',
 PART_NUMBER='G21497-005',
 LOCATION='R1W34',
 ROOM='CPU0',
 SEC='1',
 CDS_LIB='mstr_discrete',
 CDS_PART_NAME='RES_0402-0.0,5%,1/16W,CHIP,G21A',
 PRIM_FILE='./archive_libs/mstr_discrete/res/chips/chips.prt';

PART_NAME
 R1W35 'RES_0402-49.9,1%,1/16W,EMPTY,GA':
 ROOM='SB';

SECTION_NUMBER 1
 '@BASEBOARD_FAB2_LIB.BASEBOARD_FAB2(SCH_1):PAGE152_I105@MSTR_DISCRETE.RES(CHIPS)':
 C_PATH='@baseboard_fab2_lib.baseboard_fab2(sch_1):page152_i105@mstr_discrete.re~
s(chips)',
 P_PATH='@baseboard_fab2_lib.baseboard_fab2(sch_1):page152_i105@mstr_discrete.re~
s(chips)',
 PATH='I105',
 DRAWING='@BASEBOARD_FAB2_LIB.BASEBOARD_FAB2(SCH_1):PAGE152',
 WATTAGE='1/16W',
 TOLERANCE='1%',
 SEC_TYPE='0402',
 MATERIAL='EMPTY',
 PHYS_PAGE='152',
 XY='(-3100,2075)',
 ROT='0',
 VER='2',
 VALUE='49.9',
 PACK_TYPE='0402',
 PART_NUMBER='G21796-047',
 LOCATION='R1W35',
 ROOM='SB',
 SEC='1',
 CDS_LIB='mstr_discrete',
 CDS_PART_NAME='RES_0402-49.9,1%,1/16W,EMPTY,GA',
 PRIM_FILE='./archive_libs/mstr_discrete/res/chips/chips.prt';

PART_NAME
 R1W36 'RES_0402-4.75K,1%,1/16W,CHIP,GA':;

SECTION_NUMBER 1
 '@BASEBOARD_FAB2_LIB.BASEBOARD_FAB2(SCH_1):PAGE176_I172@MSTR_DISCRETE.RES(CHIPS)':
 C_PATH='@baseboard_fab2_lib.baseboard_fab2(sch_1):page176_i172@mstr_discrete.re~
s(chips)',
 P_PATH='@baseboard_fab2_lib.baseboard_fab2(sch_1):page176_i172@mstr_discrete.re~
s(chips)',
 PATH='I172',
 DRAWING='@BASEBOARD_FAB2_LIB.BASEBOARD_FAB2(SCH_1):PAGE176',
 WATTAGE='1/16W',
 TOLERANCE='1%',
 SEC_TYPE='0402',
 MATERIAL='CHIP',
 PHYS_PAGE='176',
 XY='(-6100,2250)',
 ROT='5',
 VER='1',
 VALUE='4.75K',
 PACK_TYPE='0402',
 PART_NUMBER='G21796-072',
 LOCATION='R1W36',
 SEC='1',
 CDS_LIB='mstr_discrete',
 CDS_PART_NAME='RES_0402-4.75K,1%,1/16W,CHIP,GA',
 PRIM_FILE='./archive_libs/mstr_discrete/res/chips/chips.prt';

PART_NAME
 R1W37 'RES_0402-4.75K,1%,1/16W,CHIP,GA':;

SECTION_NUMBER 1
 '@BASEBOARD_FAB2_LIB.BASEBOARD_FAB2(SCH_1):PAGE176_I173@MSTR_DISCRETE.RES(CHIPS)':
 C_PATH='@baseboard_fab2_lib.baseboard_fab2(sch_1):page176_i173@mstr_discrete.re~
s(chips)',
 P_PATH='@baseboard_fab2_lib.baseboard_fab2(sch_1):page176_i173@mstr_discrete.re~
s(chips)',
 PATH='I173',
 DRAWING='@BASEBOARD_FAB2_LIB.BASEBOARD_FAB2(SCH_1):PAGE176',
 WATTAGE='1/16W',
 TOLERANCE='1%',
 SEC_TYPE='0402',
 MATERIAL='CHIP',
 PHYS_PAGE='176',
 XY='(-5800,2250)',
 ROT='5',
 VER='1',
 VALUE='4.75K',
 PACK_TYPE='0402',
 PART_NUMBER='G21796-072',
 LOCATION='R1W37',
 SEC='1',
 CDS_LIB='mstr_discrete',
 CDS_PART_NAME='RES_0402-4.75K,1%,1/16W,CHIP,GA',
 PRIM_FILE='./archive_libs/mstr_discrete/res/chips/chips.prt';

PART_NAME
 R1W38 'RES_0402-0.0,5%,1/16W,CHIP,G21A':
 ROOM='CPU0';

SECTION_NUMBER 1
 '@BASEBOARD_FAB2_LIB.BASEBOARD_FAB2(SCH_1):PAGE176_I176@MSTR_DISCRETE.RES(CHIPS)':
 C_PATH='@baseboard_fab2_lib.baseboard_fab2(sch_1):page176_i176@mstr_discrete.re~
s(chips)',
 P_PATH='@baseboard_fab2_lib.baseboard_fab2(sch_1):page176_i176@mstr_discrete.re~
s(chips)',
 PATH='I176',
 DRAWING='@BASEBOARD_FAB2_LIB.BASEBOARD_FAB2(SCH_1):PAGE176',
 POP='NOPOP',
 WATTAGE='1/16W',
 TOLERANCE='5%',
 SEC_TYPE='0402',
 MATERIAL='CHIP',
 BOM_COST='PROC_SIDEBAND',
 PHYS_PAGE='176',
 XY='(-5950,1600)',
 ROT='0',
 VER='1',
 VALUE='0.0',
 PACK_TYPE='0402',
 PART_NUMBER='G21497-005',
 LOCATION='R1W38',
 ROOM='CPU0',
 SEC='1',
 CDS_LIB='mstr_discrete',
 CDS_PART_NAME='RES_0402-0.0,5%,1/16W,CHIP,G21A',
 PRIM_FILE='./archive_libs/mstr_discrete/res/chips/chips.prt';

PART_NAME
 R1W39 'RES_0402-0.0,5%,1/16W,CHIP,G21A':
 ROOM='CPU0';

SECTION_NUMBER 1
 '@BASEBOARD_FAB2_LIB.BASEBOARD_FAB2(SCH_1):PAGE176_I175@MSTR_DISCRETE.RES(CHIPS)':
 C_PATH='@baseboard_fab2_lib.baseboard_fab2(sch_1):page176_i175@mstr_discrete.re~
s(chips)',
 P_PATH='@baseboard_fab2_lib.baseboard_fab2(sch_1):page176_i175@mstr_discrete.re~
s(chips)',
 PATH='I175',
 DRAWING='@BASEBOARD_FAB2_LIB.BASEBOARD_FAB2(SCH_1):PAGE176',
 POP='NOPOP',
 WATTAGE='1/16W',
 TOLERANCE='5%',
 SEC_TYPE='0402',
 MATERIAL='CHIP',
 BOM_COST='PROC_SIDEBAND',
 PHYS_PAGE='176',
 XY='(-5950,1550)',
 ROT='0',
 VER='1',
 VALUE='0.0',
 PACK_TYPE='0402',
 PART_NUMBER='G21497-005',
 LOCATION='R1W39',
 ROOM='CPU0',
 SEC='1',
 CDS_LIB='mstr_discrete',
 CDS_PART_NAME='RES_0402-0.0,5%,1/16W,CHIP,G21A',
 PRIM_FILE='./archive_libs/mstr_discrete/res/chips/chips.prt';

PART_NAME
 R1W40 'RES_0402-4.75K,1%,1/16W,CHIP,GA':
 GROUP='KR',
 ROOM='CPU0';

SECTION_NUMBER 1
 '@BASEBOARD_FAB2_LIB.BASEBOARD_FAB2(SCH_1):PAGE188_I128@MSTR_DISCRETE.RES(CHIPS)':
 C_PATH='@baseboard_fab2_lib.baseboard_fab2(sch_1):page188_i128@mstr_discrete.re~
s(chips)',
 P_PATH='@baseboard_fab2_lib.baseboard_fab2(sch_1):page188_i128@mstr_discrete.re~
s(chips)',
 PATH='I128',
 DRAWING='@BASEBOARD_FAB2_LIB.BASEBOARD_FAB2(SCH_1):PAGE188',
 WATTAGE='1/16W',
 TOLERANCE='1%',
 SEC_TYPE='0402',
 MATERIAL='CHIP',
 PHYS_PAGE='188',
 XY='(-3250,2750)',
 ROT='1',
 VER='2',
 VALUE='4.75K',
 PACK_TYPE='0402',
 PART_NUMBER='G21796-072',
 LOCATION='R1W40',
 ROOM='CPU0',
 GROUP='KR',
 SEC='1',
 CDS_LIB='mstr_discrete',
 CDS_PART_NAME='RES_0402-4.75K,1%,1/16W,CHIP,GA',
 PRIM_FILE='./archive_libs/mstr_discrete/res/chips/chips.prt';

PART_NAME
 R1W41 'RES_0402-4.75K,1%,1/16W,CHIP,GA':
 GROUP='KR',
 ROOM='CPU0';

SECTION_NUMBER 1
 '@BASEBOARD_FAB2_LIB.BASEBOARD_FAB2(SCH_1):PAGE188_I129@MSTR_DISCRETE.RES(CHIPS)':
 C_PATH='@baseboard_fab2_lib.baseboard_fab2(sch_1):page188_i129@mstr_discrete.re~
s(chips)',
 P_PATH='@baseboard_fab2_lib.baseboard_fab2(sch_1):page188_i129@mstr_discrete.re~
s(chips)',
 PATH='I129',
 DRAWING='@BASEBOARD_FAB2_LIB.BASEBOARD_FAB2(SCH_1):PAGE188',
 POP='NOPOP',
 WATTAGE='1/16W',
 TOLERANCE='1%',
 SEC_TYPE='0402',
 MATERIAL='CHIP',
 PHYS_PAGE='188',
 XY='(-3250,2600)',
 ROT='1',
 VER='2',
 VALUE='4.75K',
 PACK_TYPE='0402',
 PART_NUMBER='G21796-072',
 LOCATION='R1W41',
 ROOM='CPU0',
 GROUP='KR',
 SEC='1',
 CDS_LIB='mstr_discrete',
 CDS_PART_NAME='RES_0402-4.75K,1%,1/16W,CHIP,GA',
 PRIM_FILE='./archive_libs/mstr_discrete/res/chips/chips.prt';

PART_NAME
 R1W42 'RES_0402-4.75K,1%,1/16W,CHIP,GA':
 ROOM='CPU0';

SECTION_NUMBER 1
 '@BASEBOARD_FAB2_LIB.BASEBOARD_FAB2(SCH_1):PAGE188_I131@MSTR_DISCRETE.RES(CHIPS)':
 C_PATH='@baseboard_fab2_lib.baseboard_fab2(sch_1):page188_i131@mstr_discrete.re~
s(chips)',
 P_PATH='@baseboard_fab2_lib.baseboard_fab2(sch_1):page188_i131@mstr_discrete.re~
s(chips)',
 PATH='I131',
 DRAWING='@BASEBOARD_FAB2_LIB.BASEBOARD_FAB2(SCH_1):PAGE188',
 WATTAGE='1/16W',
 TOLERANCE='1%',
 SEC_TYPE='0402',
 MATERIAL='CHIP',
 PHYS_PAGE='188',
 XY='(-3250,2350)',
 ROT='1',
 VER='2',
 VALUE='4.75K',
 PACK_TYPE='0402',
 PART_NUMBER='G21796-072',
 LOCATION='R1W42',
 ROOM='CPU0',
 SEC='1',
 CDS_LIB='mstr_discrete',
 CDS_PART_NAME='RES_0402-4.75K,1%,1/16W,CHIP,GA',
 PRIM_FILE='./archive_libs/mstr_discrete/res/chips/chips.prt';

PART_NAME
 R1W43 'RES_0402-4.75K,1%,1/16W,CHIP,GA':
 ROOM='CPU0';

SECTION_NUMBER 1
 '@BASEBOARD_FAB2_LIB.BASEBOARD_FAB2(SCH_1):PAGE188_I132@MSTR_DISCRETE.RES(CHIPS)':
 C_PATH='@baseboard_fab2_lib.baseboard_fab2(sch_1):page188_i132@mstr_discrete.re~
s(chips)',
 P_PATH='@baseboard_fab2_lib.baseboard_fab2(sch_1):page188_i132@mstr_discrete.re~
s(chips)',
 PATH='I132',
 DRAWING='@BASEBOARD_FAB2_LIB.BASEBOARD_FAB2(SCH_1):PAGE188',
 WATTAGE='1/16W',
 TOLERANCE='1%',
 SEC_TYPE='0402',
 MATERIAL='CHIP',
 PHYS_PAGE='188',
 XY='(-3250,2200)',
 ROT='1',
 VER='2',
 VALUE='4.75K',
 PACK_TYPE='0402',
 PART_NUMBER='G21796-072',
 LOCATION='R1W43',
 ROOM='CPU0',
 SEC='1',
 CDS_LIB='mstr_discrete',
 CDS_PART_NAME='RES_0402-4.75K,1%,1/16W,CHIP,GA',
 PRIM_FILE='./archive_libs/mstr_discrete/res/chips/chips.prt';

PART_NAME
 R1W44 'RES_0402-4.75K,1%,1/16W,CHIP,GA':
 ROOM='CPU0';

SECTION_NUMBER 1
 '@BASEBOARD_FAB2_LIB.BASEBOARD_FAB2(SCH_1):PAGE188_I133@MSTR_DISCRETE.RES(CHIPS)':
 C_PATH='@baseboard_fab2_lib.baseboard_fab2(sch_1):page188_i133@mstr_discrete.re~
s(chips)',
 P_PATH='@baseboard_fab2_lib.baseboard_fab2(sch_1):page188_i133@mstr_discrete.re~
s(chips)',
 PATH='I133',
 DRAWING='@BASEBOARD_FAB2_LIB.BASEBOARD_FAB2(SCH_1):PAGE188',
 WATTAGE='1/16W',
 TOLERANCE='1%',
 SEC_TYPE='0402',
 MATERIAL='CHIP',
 PHYS_PAGE='188',
 XY='(-3250,2050)',
 ROT='1',
 VER='2',
 VALUE='4.75K',
 PACK_TYPE='0402',
 PART_NUMBER='G21796-072',
 LOCATION='R1W44',
 ROOM='CPU0',
 SEC='1',
 CDS_LIB='mstr_discrete',
 CDS_PART_NAME='RES_0402-4.75K,1%,1/16W,CHIP,GA',
 PRIM_FILE='./archive_libs/mstr_discrete/res/chips/chips.prt';

PART_NAME
 R1W45 'RES_0402-4.75K,1%,1/16W,CHIP,GA':
 ROOM='CPU0';

SECTION_NUMBER 1
 '@BASEBOARD_FAB2_LIB.BASEBOARD_FAB2(SCH_1):PAGE188_I134@MSTR_DISCRETE.RES(CHIPS)':
 C_PATH='@baseboard_fab2_lib.baseboard_fab2(sch_1):page188_i134@mstr_discrete.re~
s(chips)',
 P_PATH='@baseboard_fab2_lib.baseboard_fab2(sch_1):page188_i134@mstr_discrete.re~
s(chips)',
 PATH='I134',
 DRAWING='@BASEBOARD_FAB2_LIB.BASEBOARD_FAB2(SCH_1):PAGE188',
 WATTAGE='1/16W',
 TOLERANCE='1%',
 SEC_TYPE='0402',
 MATERIAL='CHIP',
 PHYS_PAGE='188',
 XY='(-3250,1900)',
 ROT='1',
 VER='2',
 VALUE='4.75K',
 PACK_TYPE='0402',
 PART_NUMBER='G21796-072',
 LOCATION='R1W45',
 ROOM='CPU0',
 SEC='1',
 CDS_LIB='mstr_discrete',
 CDS_PART_NAME='RES_0402-4.75K,1%,1/16W,CHIP,GA',
 PRIM_FILE='./archive_libs/mstr_discrete/res/chips/chips.prt';

PART_NAME
 R2L4 'RES_0402-2.0K,1%,1/16W,CHIP,G2A':
 ROOM='ST_SATA';

SECTION_NUMBER 1
 '@BASEBOARD_FAB2_LIB.BASEBOARD_FAB2(SCH_1):PAGE178_I18@MSTR_DISCRETE.RES(CHIPS)':
 C_PATH='@baseboard_fab2_lib.baseboard_fab2(sch_1):page178_i18@mstr_discrete.res~
(chips)',
 P_PATH='@baseboard_fab2_lib.baseboard_fab2(sch_1):page178_i18@mstr_discrete.res~
(chips)',
 PATH='I18',
 DRAWING='@BASEBOARD_FAB2_LIB.BASEBOARD_FAB2(SCH_1):PAGE178',
 WATTAGE='1/16W',
 TOLERANCE='1%',
 SEC_TYPE='0402',
 MATERIAL='CHIP',
 BOM_COST='ST_SATA',
 PHYS_PAGE='178',
 XY='(125,2225)',
 ROT='2',
 VER='2',
 VALUE='2.0K',
 PACK_TYPE='0402',
 PART_NUMBER='G21796-001',
 LOCATION='R2L4',
 ROOM='ST_SATA',
 SEC='1',
 CDS_LIB='mstr_discrete',
 CDS_PART_NAME='RES_0402-2.0K,1%,1/16W,CHIP,G2A',
 PRIM_FILE='./archive_libs/mstr_discrete/res/chips/chips.prt';

PART_NAME
 R2L5 'RES_0402-2.0K,1%,1/16W,CHIP,G2A':
 ROOM='ST_SATA';

SECTION_NUMBER 1
 '@BASEBOARD_FAB2_LIB.BASEBOARD_FAB2(SCH_1):PAGE178_I20@MSTR_DISCRETE.RES(CHIPS)':
 C_PATH='@baseboard_fab2_lib.baseboard_fab2(sch_1):page178_i20@mstr_discrete.res~
(chips)',
 P_PATH='@baseboard_fab2_lib.baseboard_fab2(sch_1):page178_i20@mstr_discrete.res~
(chips)',
 PATH='I20',
 DRAWING='@BASEBOARD_FAB2_LIB.BASEBOARD_FAB2(SCH_1):PAGE178',
 WATTAGE='1/16W',
 TOLERANCE='1%',
 SEC_TYPE='0402',
 MATERIAL='CHIP',
 BOM_COST='ST_SATA',
 PHYS_PAGE='178',
 XY='(-200,2225)',
 ROT='2',
 VER='2',
 VALUE='2.0K',
 PACK_TYPE='0402',
 PART_NUMBER='G21796-001',
 LOCATION='R2L5',
 ROOM='ST_SATA',
 SEC='1',
 CDS_LIB='mstr_discrete',
 CDS_PART_NAME='RES_0402-2.0K,1%,1/16W,CHIP,G2A',
 PRIM_FILE='./archive_libs/mstr_discrete/res/chips/chips.prt';

PART_NAME
 R2L6 'RES_0402-2.0K,1%,1/16W,CHIP,G2A':
 ROOM='ST_SATA';

SECTION_NUMBER 1
 '@BASEBOARD_FAB2_LIB.BASEBOARD_FAB2(SCH_1):PAGE178_I17@MSTR_DISCRETE.RES(CHIPS)':
 C_PATH='@baseboard_fab2_lib.baseboard_fab2(sch_1):page178_i17@mstr_discrete.res~
(chips)',
 P_PATH='@baseboard_fab2_lib.baseboard_fab2(sch_1):page178_i17@mstr_discrete.res~
(chips)',
 PATH='I17',
 DRAWING='@BASEBOARD_FAB2_LIB.BASEBOARD_FAB2(SCH_1):PAGE178',
 WATTAGE='1/16W',
 TOLERANCE='1%',
 SEC_TYPE='0402',
 MATERIAL='CHIP',
 BOM_COST='ST_SATA',
 PHYS_PAGE='178',
 XY='(475,2225)',
 ROT='2',
 VER='2',
 VALUE='2.0K',
 PACK_TYPE='0402',
 PART_NUMBER='G21796-001',
 LOCATION='R2L6',
 ROOM='ST_SATA',
 SEC='1',
 CDS_LIB='mstr_discrete',
 CDS_PART_NAME='RES_0402-2.0K,1%,1/16W,CHIP,G2A',
 PRIM_FILE='./archive_libs/mstr_discrete/res/chips/chips.prt';

PART_NAME
 R2L8 'RES_0603-10.0,1%,1/10W,CHIP,G2A':
 ROOM='PVNN_PCH_STBY';

SECTION_NUMBER 1
 '@BASEBOARD_FAB2_LIB.BASEBOARD_FAB2(SCH_1):PAGE235_I154@MSTR_DISCRETE.RES(CHIPS)':
 C_PATH='@baseboard_fab2_lib.baseboard_fab2(sch_1):page235_i154@mstr_discrete.re~
s(chips)',
 P_PATH='@baseboard_fab2_lib.baseboard_fab2(sch_1):page235_i154@mstr_discrete.re~
s(chips)',
 PATH='I154',
 DRAWING='@BASEBOARD_FAB2_LIB.BASEBOARD_FAB2(SCH_1):PAGE235',
 WATTAGE='1/10W',
 TOLERANCE='1%',
 SEC_TYPE='0603',
 MATERIAL='CHIP',
 PHYS_PAGE='235',
 XY='(-12675,2225)',
 ROT='0',
 VER='1',
 VALUE='10.0',
 PACK_TYPE='0603',
 PART_NUMBER='G22026-041',
 LOCATION='R2L8',
 ROOM='PVNN_PCH_STBY',
 SEC='1',
 CDS_LIB='mstr_discrete',
 CDS_PART_NAME='RES_0603-10.0,1%,1/10W,CHIP,G2A',
 PRIM_FILE='./archive_libs/mstr_discrete/res/chips/chips.prt';

PART_NAME
 R2L9 'RES_0402-4.02K,1%,1/16W,CHIP,GA':
 ROOM='PVCCIN_CPU0_VR';

SECTION_NUMBER 1
 '@BASEBOARD_FAB2_LIB.BASEBOARD_FAB2(SCH_1):PAGE235_I254@MSTR_DISCRETE.RES(CHIPS)':
 C_PATH='@baseboard_fab2_lib.baseboard_fab2(sch_1):page235_i254@mstr_discrete.re~
s(chips)',
 P_PATH='@baseboard_fab2_lib.baseboard_fab2(sch_1):page235_i254@mstr_discrete.re~
s(chips)',
 PATH='I254',
 DRAWING='@BASEBOARD_FAB2_LIB.BASEBOARD_FAB2(SCH_1):PAGE235',
 WATTAGE='1/16W',
 TOLERANCE='1%',
 SEC_TYPE='0402',
 MATERIAL='CHIP',
 PHYS_PAGE='235',
 XY='(-10750,2150)',
 ROT='0',
 VER='2',
 VALUE='4.02K',
 PACK_TYPE='0402',
 PART_NUMBER='G21796-082',
 LOCATION='R2L9',
 ROOM='PVCCIN_CPU0_VR',
 SEC='1',
 CDS_LIB='mstr_discrete',
 CDS_PART_NAME='RES_0402-4.02K,1%,1/16W,CHIP,GA',
 PRIM_FILE='./archive_libs/mstr_discrete/res/chips/chips.prt';

PART_NAME
 R2L10 'RES_0402-1.5K,1%,1/16W,CHIP,G2A':
 ROOM='PVNN_PCH_STBY';

SECTION_NUMBER 1
 '@BASEBOARD_FAB2_LIB.BASEBOARD_FAB2(SCH_1):PAGE235_I166@MSTR_DISCRETE.RES(CHIPS)':
 C_PATH='@baseboard_fab2_lib.baseboard_fab2(sch_1):page235_i166@mstr_discrete.re~
s(chips)',
 P_PATH='@baseboard_fab2_lib.baseboard_fab2(sch_1):page235_i166@mstr_discrete.re~
s(chips)',
 PATH='I166',
 DRAWING='@BASEBOARD_FAB2_LIB.BASEBOARD_FAB2(SCH_1):PAGE235',
 WATTAGE='1/16W',
 TOLERANCE='1%',
 SEC_TYPE='0402',
 MATERIAL='CHIP',
 PHYS_PAGE='235',
 XY='(-12325,5175)',
 ROT='0',
 VER='2',
 VALUE='1.5K',
 PACK_TYPE='0402',
 PART_NUMBER='G21796-003',
 LOCATION='R2L10',
 ROOM='PVNN_PCH_STBY',
 SEC='1',
 CDS_LIB='mstr_discrete',
 CDS_PART_NAME='RES_0402-1.5K,1%,1/16W,CHIP,G2A',
 PRIM_FILE='./archive_libs/mstr_discrete/res/chips/chips.prt';

PART_NAME
 R2L11 'RES_0402-2.0K,1%,1/16W,CHIP,G2A':
 ROOM='ST_SATA';

SECTION_NUMBER 1
 '@BASEBOARD_FAB2_LIB.BASEBOARD_FAB2(SCH_1):PAGE178_I13@MSTR_DISCRETE.RES(CHIPS)':
 C_PATH='@baseboard_fab2_lib.baseboard_fab2(sch_1):page178_i13@mstr_discrete.res~
(chips)',
 P_PATH='@baseboard_fab2_lib.baseboard_fab2(sch_1):page178_i13@mstr_discrete.res~
(chips)',
 PATH='I13',
 DRAWING='@BASEBOARD_FAB2_LIB.BASEBOARD_FAB2(SCH_1):PAGE178',
 WATTAGE='1/16W',
 TOLERANCE='1%',
 SEC_TYPE='0402',
 MATERIAL='CHIP',
 BOM_COST='ST_SATA',
 PHYS_PAGE='178',
 XY='(575,4125)',
 ROT='2',
 VER='2',
 VALUE='2.0K',
 PACK_TYPE='0402',
 PART_NUMBER='G21796-001',
 LOCATION='R2L11',
 ROOM='ST_SATA',
 SEC='1',
 CDS_LIB='mstr_discrete',
 CDS_PART_NAME='RES_0402-2.0K,1%,1/16W,CHIP,G2A',
 PRIM_FILE='./archive_libs/mstr_discrete/res/chips/chips.prt';

PART_NAME
 R2L12 'RES_0402-2.0K,1%,1/16W,CHIP,G2A':
 ROOM='ST_SATA';

SECTION_NUMBER 1
 '@BASEBOARD_FAB2_LIB.BASEBOARD_FAB2(SCH_1):PAGE178_I2@MSTR_DISCRETE.RES(CHIPS)':
 C_PATH='@baseboard_fab2_lib.baseboard_fab2(sch_1):page178_i2@mstr_discrete.res(~
chips)',
 P_PATH='@baseboard_fab2_lib.baseboard_fab2(sch_1):page178_i2@mstr_discrete.res(~
chips)',
 PATH='I2',
 DRAWING='@BASEBOARD_FAB2_LIB.BASEBOARD_FAB2(SCH_1):PAGE178',
 WATTAGE='1/16W',
 TOLERANCE='1%',
 SEC_TYPE='0402',
 MATERIAL='CHIP',
 BOM_COST='ST_SATA',
 PHYS_PAGE='178',
 XY='(-200,4125)',
 ROT='2',
 VER='2',
 VALUE='2.0K',
 PACK_TYPE='0402',
 PART_NUMBER='G21796-001',
 LOCATION='R2L12',
 ROOM='ST_SATA',
 SEC='1',
 CDS_LIB='mstr_discrete',
 CDS_PART_NAME='RES_0402-2.0K,1%,1/16W,CHIP,G2A',
 PRIM_FILE='./archive_libs/mstr_discrete/res/chips/chips.prt';

PART_NAME
 R2L14 'RES_0402-0.0,5%,1/16W,CHIP,G21A':
 ROOM='PVNN_PCH_STBY';

SECTION_NUMBER 1
 '@BASEBOARD_FAB2_LIB.BASEBOARD_FAB2(SCH_1):PAGE235_I159@MSTR_DISCRETE.RES(CHIPS)':
 C_PATH='@baseboard_fab2_lib.baseboard_fab2(sch_1):page235_i159@mstr_discrete.re~
s(chips)',
 P_PATH='@baseboard_fab2_lib.baseboard_fab2(sch_1):page235_i159@mstr_discrete.re~
s(chips)',
 PATH='I159',
 DRAWING='@BASEBOARD_FAB2_LIB.BASEBOARD_FAB2(SCH_1):PAGE235',
 WATTAGE='1/16W',
 TOLERANCE='5%',
 SEC_TYPE='0402',
 MATERIAL='CHIP',
 PHYS_PAGE='235',
 XY='(-10450,5425)',
 ROT='0',
 VER='2',
 VALUE='0.0',
 PACK_TYPE='0402',
 PART_NUMBER='G21497-005',
 LOCATION='R2L14',
 ROOM='PVNN_PCH_STBY',
 SEC='1',
 CDS_LIB='mstr_discrete',
 CDS_PART_NAME='RES_0402-0.0,5%,1/16W,CHIP,G21A',
 PRIM_FILE='./archive_libs/mstr_discrete/res/chips/chips.prt';

PART_NAME
 R2L15 'RES_0402-2.0K,1%,1/16W,CHIP,G2A':
 ROOM='ST_SATA';

SECTION_NUMBER 1
 '@BASEBOARD_FAB2_LIB.BASEBOARD_FAB2(SCH_1):PAGE178_I12@MSTR_DISCRETE.RES(CHIPS)':
 C_PATH='@baseboard_fab2_lib.baseboard_fab2(sch_1):page178_i12@mstr_discrete.res~
(chips)',
 P_PATH='@baseboard_fab2_lib.baseboard_fab2(sch_1):page178_i12@mstr_discrete.res~
(chips)',
 PATH='I12',
 DRAWING='@BASEBOARD_FAB2_LIB.BASEBOARD_FAB2(SCH_1):PAGE178',
 WATTAGE='1/16W',
 TOLERANCE='1%',
 SEC_TYPE='0402',
 MATERIAL='CHIP',
 BOM_COST='ST_SATA',
 PHYS_PAGE='178',
 XY='(225,4125)',
 ROT='2',
 VER='2',
 VALUE='2.0K',
 PACK_TYPE='0402',
 PART_NUMBER='G21796-001',
 LOCATION='R2L15',
 ROOM='ST_SATA',
 SEC='1',
 CDS_LIB='mstr_discrete',
 CDS_PART_NAME='RES_0402-2.0K,1%,1/16W,CHIP,G2A',
 PRIM_FILE='./archive_libs/mstr_discrete/res/chips/chips.prt';

PART_NAME
 R2L16 'RES_0402-22.1,1.0%,1/16W,CHIP,A':
 ROOM='PVNN_PCH_STBY';

SECTION_NUMBER 1
 '@BASEBOARD_FAB2_LIB.BASEBOARD_FAB2(SCH_1):PAGE235_I147@MSTR_DISCRETE.RES(CHIPS)':
 C_PATH='@baseboard_fab2_lib.baseboard_fab2(sch_1):page235_i147@mstr_discrete.re~
s(chips)',
 P_PATH='@baseboard_fab2_lib.baseboard_fab2(sch_1):page235_i147@mstr_discrete.re~
s(chips)',
 PATH='I147',
 DRAWING='@BASEBOARD_FAB2_LIB.BASEBOARD_FAB2(SCH_1):PAGE235',
 WATTAGE='1/16W',
 TOLERANCE='1.0%',
 SEC_TYPE='0402',
 MATERIAL='CHIP',
 PHYS_PAGE='235',
 XY='(-7100,4500)',
 ROT='0',
 VER='1',
 VALUE='22.1',
 PACK_TYPE='0402',
 PART_NUMBER='G21796-250',
 LOCATION='R2L16',
 ROOM='PVNN_PCH_STBY',
 SEC='1',
 CDS_LIB='mstr_discrete',
 CDS_PART_NAME='RES_0402-22.1,1.0%,1/16W,CHIP,A',
 PRIM_FILE='./archive_libs/mstr_discrete/res/chips/chips.prt';

PART_NAME
 R2L17 'RES_0402-0.0,5%,1/16W,CHIP,G21A':
 ROOM='PVCCIN_CPU0_VR';

SECTION_NUMBER 1
 '@BASEBOARD_FAB2_LIB.BASEBOARD_FAB2(SCH_1):PAGE235_I221@MSTR_DISCRETE.RES(CHIPS)':
 C_PATH='@baseboard_fab2_lib.baseboard_fab2(sch_1):page235_i221@mstr_discrete.re~
s(chips)',
 P_PATH='@baseboard_fab2_lib.baseboard_fab2(sch_1):page235_i221@mstr_discrete.re~
s(chips)',
 PATH='I221',
 DRAWING='@BASEBOARD_FAB2_LIB.BASEBOARD_FAB2(SCH_1):PAGE235',
 WATTAGE='1/16W',
 TOLERANCE='5%',
 SEC_TYPE='0402',
 MATERIAL='CHIP',
 PHYS_PAGE='235',
 XY='(-11800,4150)',
 ROT='0',
 VER='1',
 VALUE='0.0',
 PACK_TYPE='0402',
 PART_NUMBER='G21497-005',
 LOCATION='R2L17',
 ROOM='PVCCIN_CPU0_VR',
 SEC='1',
 CDS_LIB='mstr_discrete',
 CDS_PART_NAME='RES_0402-0.0,5%,1/16W,CHIP,G21A',
 PRIM_FILE='./archive_libs/mstr_discrete/res/chips/chips.prt';

PART_NAME
 R2L18 'RES_0402-1.00K,1%,1/16W,CHIP,GA':
 ROOM='ST_SATA';

SECTION_NUMBER 1
 '@BASEBOARD_FAB2_LIB.BASEBOARD_FAB2(SCH_1):PAGE173_I266@MSTR_DISCRETE.RES(CHIPS)':
 C_PATH='@baseboard_fab2_lib.baseboard_fab2(sch_1):page173_i266@mstr_discrete.re~
s(chips)',
 P_PATH='@baseboard_fab2_lib.baseboard_fab2(sch_1):page173_i266@mstr_discrete.re~
s(chips)',
 PATH='I266',
 DRAWING='@BASEBOARD_FAB2_LIB.BASEBOARD_FAB2(SCH_1):PAGE173',
 WATTAGE='1/16W',
 TOLERANCE='1%',
 SEC_TYPE='0402',
 MATERIAL='CHIP',
 BOM_COST='ST_SATA',
 PHYS_PAGE='173',
 XY='(1675,3500)',
 ROT='0',
 VER='2',
 VALUE='1.00K',
 PACK_TYPE='0402',
 PART_NUMBER='G21796-026',
 LOCATION='R2L18',
 ROOM='ST_SATA',
 SEC='1',
 CDS_LIB='mstr_discrete',
 CDS_PART_NAME='RES_0402-1.00K,1%,1/16W,CHIP,GA',
 PRIM_FILE='./archive_libs/mstr_discrete/res/chips/chips.prt';

PART_NAME
 R2L19 'RES_0402-49.9K,1%,1/16W,CHIP,GA':
 ROOM='P1V8_PCH_STBY_VR';

SECTION_NUMBER 1
 '@BASEBOARD_FAB2_LIB.BASEBOARD_FAB2(SCH_1):PAGE237_I80@MSTR_DISCRETE.RES(CHIPS)':
 C_PATH='@baseboard_fab2_lib.baseboard_fab2(sch_1):page237_i80@mstr_discrete.res~
(chips)',
 P_PATH='@baseboard_fab2_lib.baseboard_fab2(sch_1):page237_i80@mstr_discrete.res~
(chips)',
 PATH='I80',
 DRAWING='@BASEBOARD_FAB2_LIB.BASEBOARD_FAB2(SCH_1):PAGE237',
 WATTAGE='1/16W',
 TOLERANCE='1%',
 SEC_TYPE='0402',
 MATERIAL='CHIP',
 PHYS_PAGE='237',
 XY='(2325,1700)',
 ROT='0',
 VER='2',
 VALUE='49.9K',
 PACK_TYPE='0402',
 PART_NUMBER='G21796-048',
 LOCATION='R2L19',
 ROOM='P1V8_PCH_STBY_VR',
 SEC='1',
 CDS_LIB='mstr_discrete',
 CDS_PART_NAME='RES_0402-49.9K,1%,1/16W,CHIP,GA',
 PRIM_FILE='./archive_libs/mstr_discrete/res/chips/chips.prt';

PART_NAME
 R2L20 'RES_0402-63.4K,1.0%,1/16W,CHIPA':
 ROOM='P1V8_PCH_STBY_VR';

SECTION_NUMBER 1
 '@BASEBOARD_FAB2_LIB.BASEBOARD_FAB2(SCH_1):PAGE237_I81@MSTR_DISCRETE.RES(CHIPS)':
 C_PATH='@baseboard_fab2_lib.baseboard_fab2(sch_1):page237_i81@mstr_discrete.res~
(chips)',
 P_PATH='@baseboard_fab2_lib.baseboard_fab2(sch_1):page237_i81@mstr_discrete.res~
(chips)',
 PATH='I81',
 DRAWING='@BASEBOARD_FAB2_LIB.BASEBOARD_FAB2(SCH_1):PAGE237',
 WATTAGE='1/16W',
 TOLERANCE='1.0%',
 SEC_TYPE='0402',
 MATERIAL='CHIP',
 PHYS_PAGE='237',
 XY='(2325,2275)',
 ROT='0',
 VER='2',
 VALUE='63.4K',
 PACK_TYPE='0402',
 PART_NUMBER='G21796-327',
 LOCATION='R2L20',
 ROOM='P1V8_PCH_STBY_VR',
 SEC='1',
 CDS_LIB='mstr_discrete',
 CDS_PART_NAME='RES_0402-63.4K,1.0%,1/16W,CHIPA',
 PRIM_FILE='./archive_libs/mstr_discrete/res/chips/chips.prt';

PART_NAME
 R2L21 'RES_0402-2.0K,1%,1/16W,CHIP,G2A':
 ROOM='ST_SATA';

SECTION_NUMBER 1
 '@BASEBOARD_FAB2_LIB.BASEBOARD_FAB2(SCH_1):PAGE173_I263@MSTR_DISCRETE.RES(CHIPS)':
 C_PATH='@baseboard_fab2_lib.baseboard_fab2(sch_1):page173_i263@mstr_discrete.re~
s(chips)',
 P_PATH='@baseboard_fab2_lib.baseboard_fab2(sch_1):page173_i263@mstr_discrete.re~
s(chips)',
 PATH='I263',
 DRAWING='@BASEBOARD_FAB2_LIB.BASEBOARD_FAB2(SCH_1):PAGE173',
 WATTAGE='1/16W',
 TOLERANCE='1%',
 SEC_TYPE='0402',
 MATERIAL='CHIP',
 BOM_COST='ST_SATA',
 PHYS_PAGE='173',
 XY='(-3900,4675)',
 ROT='0',
 VER='2',
 VALUE='2.0K',
 PACK_TYPE='0402',
 PART_NUMBER='G21796-001',
 LOCATION='R2L21',
 ROOM='ST_SATA',
 SEC='1',
 CDS_LIB='mstr_discrete',
 CDS_PART_NAME='RES_0402-2.0K,1%,1/16W,CHIP,G2A',
 PRIM_FILE='./archive_libs/mstr_discrete/res/chips/chips.prt';

PART_NAME
 R2L22 'RES_0402-1.00K,1%,1/16W,CHIP,GA':
 ROOM='ST_SATA';

SECTION_NUMBER 1
 '@BASEBOARD_FAB2_LIB.BASEBOARD_FAB2(SCH_1):PAGE173_I264@MSTR_DISCRETE.RES(CHIPS)':
 C_PATH='@baseboard_fab2_lib.baseboard_fab2(sch_1):page173_i264@mstr_discrete.re~
s(chips)',
 P_PATH='@baseboard_fab2_lib.baseboard_fab2(sch_1):page173_i264@mstr_discrete.re~
s(chips)',
 PATH='I264',
 DRAWING='@BASEBOARD_FAB2_LIB.BASEBOARD_FAB2(SCH_1):PAGE173',
 WATTAGE='1/16W',
 TOLERANCE='1%',
 SEC_TYPE='0402',
 MATERIAL='CHIP',
 BOM_COST='ST_SATA',
 PHYS_PAGE='173',
 XY='(1625,2000)',
 ROT='0',
 VER='2',
 VALUE='1.00K',
 PACK_TYPE='0402',
 PART_NUMBER='G21796-026',
 LOCATION='R2L22',
 ROOM='ST_SATA',
 SEC='1',
 CDS_LIB='mstr_discrete',
 CDS_PART_NAME='RES_0402-1.00K,1%,1/16W,CHIP,GA',
 PRIM_FILE='./archive_libs/mstr_discrete/res/chips/chips.prt';

PART_NAME
 R2L23 'RES_0402-2.0K,1%,1/16W,CHIP,G2A':
 ROOM='ST_SATA';

SECTION_NUMBER 1
 '@BASEBOARD_FAB2_LIB.BASEBOARD_FAB2(SCH_1):PAGE173_I261@MSTR_DISCRETE.RES(CHIPS)':
 C_PATH='@baseboard_fab2_lib.baseboard_fab2(sch_1):page173_i261@mstr_discrete.re~
s(chips)',
 P_PATH='@baseboard_fab2_lib.baseboard_fab2(sch_1):page173_i261@mstr_discrete.re~
s(chips)',
 PATH='I261',
 DRAWING='@BASEBOARD_FAB2_LIB.BASEBOARD_FAB2(SCH_1):PAGE173',
 WATTAGE='1/16W',
 TOLERANCE='1%',
 SEC_TYPE='0402',
 MATERIAL='CHIP',
 BOM_COST='ST_SATA',
 PHYS_PAGE='173',
 XY='(-3900,2200)',
 ROT='0',
 VER='1',
 VALUE='2.0K',
 PACK_TYPE='0402',
 PART_NUMBER='G21796-001',
 LOCATION='R2L23',
 ROOM='ST_SATA',
 SEC='1',
 CDS_LIB='mstr_discrete',
 CDS_PART_NAME='RES_0402-2.0K,1%,1/16W,CHIP,G2A',
 PRIM_FILE='./archive_libs/mstr_discrete/res/chips/chips.prt';

PART_NAME
 R2L24 'RES_0402-2.26K,1.0%,1/16W,EMPTA':
 ROOM='PVNN_PCH_STBY';

SECTION_NUMBER 1
 '@BASEBOARD_FAB2_LIB.BASEBOARD_FAB2(SCH_1):PAGE235_I148@MSTR_DISCRETE.RES(CHIPS)':
 C_PATH='@baseboard_fab2_lib.baseboard_fab2(sch_1):page235_i148@mstr_discrete.re~
s(chips)',
 P_PATH='@baseboard_fab2_lib.baseboard_fab2(sch_1):page235_i148@mstr_discrete.re~
s(chips)',
 PATH='I148',
 DRAWING='@BASEBOARD_FAB2_LIB.BASEBOARD_FAB2(SCH_1):PAGE235',
 WATTAGE='1/16W',
 TOLERANCE='1.0%',
 SEC_TYPE='0402',
 MATERIAL='EMPTY',
 PHYS_PAGE='235',
 XY='(-8400,4950)',
 ROT='0',
 VER='2',
 VALUE='2.26K',
 PACK_TYPE='0402',
 PART_NUMBER='G21796-311',
 LOCATION='R2L24',
 ROOM='PVNN_PCH_STBY',
 SEC='1',
 CDS_LIB='mstr_discrete',
 CDS_PART_NAME='RES_0402-2.26K,1.0%,1/16W,EMPTA',
 PRIM_FILE='./archive_libs/mstr_discrete/res/chips/chips.prt';

PART_NAME
 R2L25 'RES_0402-100.0K,1%,1/16W,CHIP,A':
 ROOM='SB';

SECTION_NUMBER 1
 '@BASEBOARD_FAB2_LIB.BASEBOARD_FAB2(SCH_1):PAGE235_I252@MSTR_DISCRETE.RES(CHIPS)':
 C_PATH='@baseboard_fab2_lib.baseboard_fab2(sch_1):page235_i252@mstr_discrete.re~
s(chips)',
 P_PATH='@baseboard_fab2_lib.baseboard_fab2(sch_1):page235_i252@mstr_discrete.re~
s(chips)',
 PATH='I252',
 DRAWING='@BASEBOARD_FAB2_LIB.BASEBOARD_FAB2(SCH_1):PAGE235',
 WATTAGE='1/16W',
 TOLERANCE='1%',
 SEC_TYPE='0402',
 MATERIAL='CHIP',
 PHYS_PAGE='235',
 XY='(-7750,4950)',
 ROT='0',
 VER='2',
 VALUE='100.0K',
 PACK_TYPE='0402',
 PART_NUMBER='G21796-010',
 LOCATION='R2L25',
 ROOM='SB',
 SEC='1',
 CDS_LIB='mstr_discrete',
 CDS_PART_NAME='RES_0402-100.0K,1%,1/16W,CHIP,A',
 PRIM_FILE='./archive_libs/mstr_discrete/res/chips/chips.prt';

PART_NAME
 R2L26 'RES_0402-100.0K,1%,1/16W,CHIP,A':
 ROOM='SB';

SECTION_NUMBER 1
 '@BASEBOARD_FAB2_LIB.BASEBOARD_FAB2(SCH_1):PAGE235_I253@MSTR_DISCRETE.RES(CHIPS)':
 C_PATH='@baseboard_fab2_lib.baseboard_fab2(sch_1):page235_i253@mstr_discrete.re~
s(chips)',
 P_PATH='@baseboard_fab2_lib.baseboard_fab2(sch_1):page235_i253@mstr_discrete.re~
s(chips)',
 PATH='I253',
 DRAWING='@BASEBOARD_FAB2_LIB.BASEBOARD_FAB2(SCH_1):PAGE235',
 WATTAGE='1/16W',
 TOLERANCE='1%',
 SEC_TYPE='0402',
 MATERIAL='CHIP',
 PHYS_PAGE='235',
 XY='(-7350,4950)',
 ROT='0',
 VER='2',
 VALUE='100.0K',
 PACK_TYPE='0402',
 PART_NUMBER='G21796-010',
 LOCATION='R2L26',
 ROOM='SB',
 SEC='1',
 CDS_LIB='mstr_discrete',
 CDS_PART_NAME='RES_0402-100.0K,1%,1/16W,CHIP,A',
 PRIM_FILE='./archive_libs/mstr_discrete/res/chips/chips.prt';

PART_NAME
 R2M1 'RES_0402-33.2,1%,1/16W,CHIP,G2A':
 ROOM='CPLD';

SECTION_NUMBER 1
 '@BASEBOARD_FAB2_LIB.BASEBOARD_FAB2(SCH_1):PAGE120_I218@MSTR_DISCRETE.RES(CHIPS)':
 C_PATH='@baseboard_fab2_lib.baseboard_fab2(sch_1):page120_i218@mstr_discrete.re~
s(chips)',
 P_PATH='@baseboard_fab2_lib.baseboard_fab2(sch_1):page120_i218@mstr_discrete.re~
s(chips)',
 PATH='I218',
 DRAWING='@BASEBOARD_FAB2_LIB.BASEBOARD_FAB2(SCH_1):PAGE120',
 WATTAGE='1/16W',
 TOLERANCE='1%',
 SEC_TYPE='0402',
 MATERIAL='CHIP',
 PHYS_PAGE='120',
 XY='(-6650,3850)',
 ROT='0',
 VER='1',
 VALUE='33.2',
 PACK_TYPE='0402',
 PART_NUMBER='G21796-074',
 LOCATION='R2M1',
 ROOM='CPLD',
 SEC='1',
 CDS_LIB='mstr_discrete',
 CDS_PART_NAME='RES_0402-33.2,1%,1/16W,CHIP,G2A',
 PRIM_FILE='./archive_libs/mstr_discrete/res/chips/chips.prt';

PART_NAME
 R2M2 'RES_0402-4.75K,1%,1/16W,CHIP,GA':
 ROOM='BMC_MISC';

SECTION_NUMBER 1
 '@BASEBOARD_FAB2_LIB.BASEBOARD_FAB2(SCH_1):PAGE157_I346@MSTR_DISCRETE.RES(CHIPS)':
 C_PATH='@baseboard_fab2_lib.baseboard_fab2(sch_1):page157_i346@mstr_discrete.re~
s(chips)',
 P_PATH='@baseboard_fab2_lib.baseboard_fab2(sch_1):page157_i346@mstr_discrete.re~
s(chips)',
 PATH='I346',
 DRAWING='@BASEBOARD_FAB2_LIB.BASEBOARD_FAB2(SCH_1):PAGE157',
 WATTAGE='1/16W',
 TOLERANCE='1%',
 SEC_TYPE='0402',
 MATERIAL='CHIP',
 BOM_COST='SM_CONTROLLER',
 PHYS_PAGE='157',
 XY='(-7175,2650)',
 ROT='0',
 VER='1',
 VALUE='4.75K',
 PACK_TYPE='0402',
 PART_NUMBER='G21796-072',
 LOCATION='R2M2',
 ROOM='BMC_MISC',
 SEC='1',
 CDS_LIB='mstr_discrete',
 CDS_PART_NAME='RES_0402-4.75K,1%,1/16W,CHIP,GA',
 PRIM_FILE='./archive_libs/mstr_discrete/res/chips/chips.prt';

PART_NAME
 R2M3 'RES_0402-33.2,1%,1/16W,CHIP,G2A':
 ROOM='CPLD';

SECTION_NUMBER 1
 '@BASEBOARD_FAB2_LIB.BASEBOARD_FAB2(SCH_1):PAGE119_I172@MSTR_DISCRETE.RES(CHIPS)':
 C_PATH='@baseboard_fab2_lib.baseboard_fab2(sch_1):page119_i172@mstr_discrete.re~
s(chips)',
 P_PATH='@baseboard_fab2_lib.baseboard_fab2(sch_1):page119_i172@mstr_discrete.re~
s(chips)',
 PATH='I172',
 DRAWING='@BASEBOARD_FAB2_LIB.BASEBOARD_FAB2(SCH_1):PAGE119',
 WATTAGE='1/16W',
 TOLERANCE='1%',
 SEC_TYPE='0402',
 MATERIAL='CHIP',
 PHYS_PAGE='119',
 XY='(-1450,2200)',
 ROT='0',
 VER='1',
 VALUE='33.2',
 PACK_TYPE='0402',
 PART_NUMBER='G21796-074',
 LOCATION='R2M3',
 ROOM='CPLD',
 SEC='1',
 CDS_LIB='mstr_discrete',
 CDS_PART_NAME='RES_0402-33.2,1%,1/16W,CHIP,G2A',
 PRIM_FILE='./archive_libs/mstr_discrete/res/chips/chips.prt';

PART_NAME
 R2M4 'RES_0402-1.00K,1%,1/16W,CHIP,GA':
 ROOM='SB';

SECTION_NUMBER 1
 '@BASEBOARD_FAB2_LIB.BASEBOARD_FAB2(SCH_1):PAGE133_I284@MSTR_DISCRETE.RES(CHIPS)':
 C_PATH='@baseboard_fab2_lib.baseboard_fab2(sch_1):page133_i284@mstr_discrete.re~
s(chips)',
 P_PATH='@baseboard_fab2_lib.baseboard_fab2(sch_1):page133_i284@mstr_discrete.re~
s(chips)',
 PATH='I284',
 DRAWING='@BASEBOARD_FAB2_LIB.BASEBOARD_FAB2(SCH_1):PAGE133',
 WATTAGE='1/16W',
 TOLERANCE='1%',
 SEC_TYPE='0402',
 MATERIAL='CHIP',
 BOM_COST='SB',
 PHYS_PAGE='133',
 XY='(-2600,4900)',
 ROT='0',
 VER='1',
 VALUE='1.00K',
 PACK_TYPE='0402',
 PART_NUMBER='G21796-026',
 LOCATION='R2M4',
 ROOM='SB',
 SEC='1',
 CDS_LIB='mstr_discrete',
 CDS_PART_NAME='RES_0402-1.00K,1%,1/16W,CHIP,GA',
 PRIM_FILE='./archive_libs/mstr_discrete/res/chips/chips.prt';

PART_NAME
 R2M5 'RES_0402-4.75K,1%,1/16W,CHIP,GA':
 ROOM='BMC_MISC';

SECTION_NUMBER 1
 '@BASEBOARD_FAB2_LIB.BASEBOARD_FAB2(SCH_1):PAGE157_I348@MSTR_DISCRETE.RES(CHIPS)':
 C_PATH='@baseboard_fab2_lib.baseboard_fab2(sch_1):page157_i348@mstr_discrete.re~
s(chips)',
 P_PATH='@baseboard_fab2_lib.baseboard_fab2(sch_1):page157_i348@mstr_discrete.re~
s(chips)',
 PATH='I348',
 DRAWING='@BASEBOARD_FAB2_LIB.BASEBOARD_FAB2(SCH_1):PAGE157',
 WATTAGE='1/16W',
 TOLERANCE='1%',
 SEC_TYPE='0402',
 MATERIAL='CHIP',
 BOM_COST='SM_CONTROLLER',
 PHYS_PAGE='157',
 XY='(-7175,2425)',
 ROT='0',
 VER='1',
 VALUE='4.75K',
 PACK_TYPE='0402',
 PART_NUMBER='G21796-072',
 LOCATION='R2M5',
 ROOM='BMC_MISC',
 SEC='1',
 CDS_LIB='mstr_discrete',
 CDS_PART_NAME='RES_0402-4.75K,1%,1/16W,CHIP,GA',
 PRIM_FILE='./archive_libs/mstr_discrete/res/chips/chips.prt';

PART_NAME
 R2M6 'RES_0402-1.0K,0.1%,1/16W,CHIP,A':
 ROOM='SB';

SECTION_NUMBER 1
 '@BASEBOARD_FAB2_LIB.BASEBOARD_FAB2(SCH_1):PAGE118_I99@MSTR_DISCRETE.RES(CHIPS)':
 C_PATH='@baseboard_fab2_lib.baseboard_fab2(sch_1):page118_i99@mstr_discrete.res~
(chips)',
 P_PATH='@baseboard_fab2_lib.baseboard_fab2(sch_1):page118_i99@mstr_discrete.res~
(chips)',
 PATH='I99',
 DRAWING='@BASEBOARD_FAB2_LIB.BASEBOARD_FAB2(SCH_1):PAGE118',
 WATTAGE='1/16W',
 TOLERANCE='0.1%',
 SEC_TYPE='0402',
 MATERIAL='CHIP',
 PHYS_PAGE='118',
 XY='(-1700,1875)',
 ROT='0',
 VER='1',
 VALUE='1.0K',
 PACK_TYPE='0402',
 PART_NUMBER='G85996-004',
 LOCATION='R2M6',
 ROOM='SB',
 SEC='1',
 CDS_LIB='mstr_discrete',
 CDS_PART_NAME='RES_0402-1.0K,0.1%,1/16W,CHIP,A',
 PRIM_FILE='./archive_libs/mstr_discrete/res/chips/chips.prt';

PART_NAME
 R2M7 'RES_0402-33.2,1%,1/16W,CHIP,G2A':
 ROOM='CPLD';

SECTION_NUMBER 1
 '@BASEBOARD_FAB2_LIB.BASEBOARD_FAB2(SCH_1):PAGE119_I174@MSTR_DISCRETE.RES(CHIPS)':
 C_PATH='@baseboard_fab2_lib.baseboard_fab2(sch_1):page119_i174@mstr_discrete.re~
s(chips)',
 P_PATH='@baseboard_fab2_lib.baseboard_fab2(sch_1):page119_i174@mstr_discrete.re~
s(chips)',
 PATH='I174',
 DRAWING='@BASEBOARD_FAB2_LIB.BASEBOARD_FAB2(SCH_1):PAGE119',
 WATTAGE='1/16W',
 TOLERANCE='1%',
 SEC_TYPE='0402',
 MATERIAL='CHIP',
 PHYS_PAGE='119',
 XY='(-1475,2950)',
 ROT='0',
 VER='1',
 VALUE='33.2',
 PACK_TYPE='0402',
 PART_NUMBER='G21796-074',
 LOCATION='R2M7',
 ROOM='CPLD',
 SEC='1',
 CDS_LIB='mstr_discrete',
 CDS_PART_NAME='RES_0402-33.2,1%,1/16W,CHIP,G2A',
 PRIM_FILE='./archive_libs/mstr_discrete/res/chips/chips.prt';

PART_NAME
 R2M8 'RES_0402-1.5K,1%,1/16W,CHIP,G2A':
 ROOM='SB';

SECTION_NUMBER 1
 '@BASEBOARD_FAB2_LIB.BASEBOARD_FAB2(SCH_1):PAGE133_I349@MSTR_DISCRETE.RES(CHIPS)':
 C_PATH='@baseboard_fab2_lib.baseboard_fab2(sch_1):page133_i349@mstr_discrete.re~
s(chips)',
 P_PATH='@baseboard_fab2_lib.baseboard_fab2(sch_1):page133_i349@mstr_discrete.re~
s(chips)',
 PATH='I349',
 DRAWING='@BASEBOARD_FAB2_LIB.BASEBOARD_FAB2(SCH_1):PAGE133',
 WATTAGE='1/16W',
 TOLERANCE='1%',
 SEC_TYPE='0402',
 MATERIAL='CHIP',
 BOM_COST='SB',
 PHYS_PAGE='133',
 XY='(-375,2725)',
 ROT='0',
 VER='1',
 VALUE='1.5K',
 PACK_TYPE='0402',
 PART_NUMBER='G21796-003',
 LOCATION='R2M8',
 ROOM='SB',
 SEC='1',
 CDS_LIB='mstr_discrete',
 CDS_PART_NAME='RES_0402-1.5K,1%,1/16W,CHIP,G2A',
 PRIM_FILE='./archive_libs/mstr_discrete/res/chips/chips.prt';

PART_NAME
 R2N1 'RES_0402-33.2,1%,1/16W,CHIP,G2A':
 ROOM='CPLD';

SECTION_NUMBER 1
 '@BASEBOARD_FAB2_LIB.BASEBOARD_FAB2(SCH_1):PAGE119_I173@MSTR_DISCRETE.RES(CHIPS)':
 C_PATH='@baseboard_fab2_lib.baseboard_fab2(sch_1):page119_i173@mstr_discrete.re~
s(chips)',
 P_PATH='@baseboard_fab2_lib.baseboard_fab2(sch_1):page119_i173@mstr_discrete.re~
s(chips)',
 PATH='I173',
 DRAWING='@BASEBOARD_FAB2_LIB.BASEBOARD_FAB2(SCH_1):PAGE119',
 WATTAGE='1/16W',
 TOLERANCE='1%',
 SEC_TYPE='0402',
 MATERIAL='CHIP',
 PHYS_PAGE='119',
 XY='(-1550,4400)',
 ROT='0',
 VER='1',
 VALUE='33.2',
 PACK_TYPE='0402',
 PART_NUMBER='G21796-074',
 LOCATION='R2N1',
 ROOM='CPLD',
 SEC='1',
 CDS_LIB='mstr_discrete',
 CDS_PART_NAME='RES_0402-33.2,1%,1/16W,CHIP,G2A',
 PRIM_FILE='./archive_libs/mstr_discrete/res/chips/chips.prt';

PART_NAME
 R2N4 'RES_0402-1.0K,0.1%,1/16W,CHIP,A':
 ROOM='SB';

SECTION_NUMBER 1
 '@BASEBOARD_FAB2_LIB.BASEBOARD_FAB2(SCH_1):PAGE118_I96@MSTR_DISCRETE.RES(CHIPS)':
 C_PATH='@baseboard_fab2_lib.baseboard_fab2(sch_1):page118_i96@mstr_discrete.res~
(chips)',
 P_PATH='@baseboard_fab2_lib.baseboard_fab2(sch_1):page118_i96@mstr_discrete.res~
(chips)',
 PATH='I96',
 DRAWING='@BASEBOARD_FAB2_LIB.BASEBOARD_FAB2(SCH_1):PAGE118',
 WATTAGE='1/16W',
 TOLERANCE='0.1%',
 SEC_TYPE='0402',
 MATERIAL='CHIP',
 PHYS_PAGE='118',
 XY='(-7225,2175)',
 ROT='0',
 VER='2',
 VALUE='1.0K',
 PACK_TYPE='0402',
 PART_NUMBER='G85996-004',
 LOCATION='R2N4',
 ROOM='SB',
 SEC='1',
 CDS_LIB='mstr_discrete',
 CDS_PART_NAME='RES_0402-1.0K,0.1%,1/16W,CHIP,A',
 PRIM_FILE='./archive_libs/mstr_discrete/res/chips/chips.prt';

PART_NAME
 R2N5 'RES_0402-665,1.0%,1/16W,CHIP,GA':
 ROOM='SMBUS';

SECTION_NUMBER 1
 '@BASEBOARD_FAB2_LIB.BASEBOARD_FAB2(SCH_1):PAGE138_I90@MSTR_DISCRETE.RES(CHIPS)':
 C_PATH='@baseboard_fab2_lib.baseboard_fab2(sch_1):page138_i90@mstr_discrete.res~
(chips)',
 P_PATH='@baseboard_fab2_lib.baseboard_fab2(sch_1):page138_i90@mstr_discrete.res~
(chips)',
 PATH='I90',
 DRAWING='@BASEBOARD_FAB2_LIB.BASEBOARD_FAB2(SCH_1):PAGE138',
 WATTAGE='1/16W',
 TOLERANCE='1.0%',
 SEC_TYPE='0402',
 MATERIAL='CHIP',
 BOM_COST='SM_CONTROLLER',
 PHYS_PAGE='138',
 XY='(-2775,4900)',
 ROT='0',
 VER='2',
 VALUE='665',
 PACK_TYPE='0402',
 PART_NUMBER='G21796-235',
 LOCATION='R2N5',
 ROOM='SMBUS',
 SEC='1',
 CDS_LIB='mstr_discrete',
 CDS_PART_NAME='RES_0402-665,1.0%,1/16W,CHIP,GA',
 PRIM_FILE='./archive_libs/mstr_discrete/res/chips/chips.prt';

PART_NAME
 R2N6 'RES_0402-10.0K,1%,1/16W,CHIP,GA':
 ROOM='SB';

SECTION_NUMBER 1
 '@BASEBOARD_FAB2_LIB.BASEBOARD_FAB2(SCH_1):PAGE118_I128@MSTR_DISCRETE.RES(CHIPS)':
 C_PATH='@baseboard_fab2_lib.baseboard_fab2(sch_1):page118_i128@mstr_discrete.re~
s(chips)',
 P_PATH='@baseboard_fab2_lib.baseboard_fab2(sch_1):page118_i128@mstr_discrete.re~
s(chips)',
 PATH='I128',
 DRAWING='@BASEBOARD_FAB2_LIB.BASEBOARD_FAB2(SCH_1):PAGE118',
 WATTAGE='1/16W',
 TOLERANCE='1%',
 SEC_TYPE='0402',
 MATERIAL='CHIP',
 BOM_COST='SB',
 PHYS_PAGE='118',
 XY='(-2200,1100)',
 ROT='0',
 VER='2',
 VALUE='10.0K',
 PACK_TYPE='0402',
 PART_NUMBER='G21796-016',
 LOCATION='R2N6',
 ROOM='SB',
 SEC='1',
 CDS_LIB='mstr_discrete',
 CDS_PART_NAME='RES_0402-10.0K,1%,1/16W,CHIP,GA',
 PRIM_FILE='./archive_libs/mstr_discrete/res/chips/chips.prt';

PART_NAME
 R2N7 'RES_0402-4.75K,1%,1/16W,CHIP,GA':
 ROOM='SB_PU_PD';

SECTION_NUMBER 1
 '@BASEBOARD_FAB2_LIB.BASEBOARD_FAB2(SCH_1):PAGE133_I309@MSTR_DISCRETE.RES(CHIPS)':
 C_PATH='@baseboard_fab2_lib.baseboard_fab2(sch_1):page133_i309@mstr_discrete.re~
s(chips)',
 P_PATH='@baseboard_fab2_lib.baseboard_fab2(sch_1):page133_i309@mstr_discrete.re~
s(chips)',
 PATH='I309',
 DRAWING='@BASEBOARD_FAB2_LIB.BASEBOARD_FAB2(SCH_1):PAGE133',
 WATTAGE='1/16W',
 TOLERANCE='1%',
 SEC_TYPE='0402',
 MATERIAL='CHIP',
 PHYS_PAGE='133',
 XY='(-2475,1025)',
 ROT='0',
 VER='1',
 VALUE='4.75K',
 PACK_TYPE='0402',
 PART_NUMBER='G21796-072',
 LOCATION='R2N7',
 ROOM='SB_PU_PD',
 SEC='1',
 CDS_LIB='mstr_discrete',
 CDS_PART_NAME='RES_0402-4.75K,1%,1/16W,CHIP,GA',
 PRIM_FILE='./archive_libs/mstr_discrete/res/chips/chips.prt';

PART_NAME
 R2N8 'RES_0402-665,1.0%,1/16W,CHIP,GA':
 ROOM='SMBUS';

SECTION_NUMBER 1
 '@BASEBOARD_FAB2_LIB.BASEBOARD_FAB2(SCH_1):PAGE138_I89@MSTR_DISCRETE.RES(CHIPS)':
 C_PATH='@baseboard_fab2_lib.baseboard_fab2(sch_1):page138_i89@mstr_discrete.res~
(chips)',
 P_PATH='@baseboard_fab2_lib.baseboard_fab2(sch_1):page138_i89@mstr_discrete.res~
(chips)',
 PATH='I89',
 DRAWING='@BASEBOARD_FAB2_LIB.BASEBOARD_FAB2(SCH_1):PAGE138',
 WATTAGE='1/16W',
 TOLERANCE='1.0%',
 SEC_TYPE='0402',
 MATERIAL='CHIP',
 BOM_COST='SM_CONTROLLER',
 PHYS_PAGE='138',
 XY='(-3175,4950)',
 ROT='0',
 VER='2',
 VALUE='665',
 PACK_TYPE='0402',
 PART_NUMBER='G21796-235',
 LOCATION='R2N8',
 ROOM='SMBUS',
 SEC='1',
 CDS_LIB='mstr_discrete',
 CDS_PART_NAME='RES_0402-665,1.0%,1/16W,CHIP,GA',
 PRIM_FILE='./archive_libs/mstr_discrete/res/chips/chips.prt';

PART_NAME
 R2N9 'RES_0402-10.0K,1%,1/16W,CHIP,GA':
 ROOM='SB';

SECTION_NUMBER 1
 '@BASEBOARD_FAB2_LIB.BASEBOARD_FAB2(SCH_1):PAGE133_I267@MSTR_DISCRETE.RES(CHIPS)':
 C_PATH='@baseboard_fab2_lib.baseboard_fab2(sch_1):page133_i267@mstr_discrete.re~
s(chips)',
 P_PATH='@baseboard_fab2_lib.baseboard_fab2(sch_1):page133_i267@mstr_discrete.re~
s(chips)',
 PATH='I267',
 DRAWING='@BASEBOARD_FAB2_LIB.BASEBOARD_FAB2(SCH_1):PAGE133',
 WATTAGE='1/16W',
 TOLERANCE='1%',
 SEC_TYPE='0402',
 MATERIAL='CHIP',
 PHYS_PAGE='133',
 XY='(-2475,1275)',
 ROT='0',
 VER='1',
 VALUE='10.0K',
 PACK_TYPE='0402',
 PART_NUMBER='G21796-016',
 LOCATION='R2N9',
 ROOM='SB',
 SEC='1',
 CDS_LIB='mstr_discrete',
 CDS_PART_NAME='RES_0402-10.0K,1%,1/16W,CHIP,GA',
 PRIM_FILE='./archive_libs/mstr_discrete/res/chips/chips.prt';

PART_NAME
 R2N10 'RES_0402-4.75K,1%,1/16W,EMPTY,A':
 ROOM='DB1200ZL';

SECTION_NUMBER 1
 '@BASEBOARD_FAB2_LIB.BASEBOARD_FAB2(SCH_1):PAGE126_I27@MSTR_DISCRETE.RES(CHIPS)':
 C_PATH='@baseboard_fab2_lib.baseboard_fab2(sch_1):page126_i27@mstr_discrete.res~
(chips)',
 P_PATH='@baseboard_fab2_lib.baseboard_fab2(sch_1):page126_i27@mstr_discrete.res~
(chips)',
 PATH='I27',
 DRAWING='@BASEBOARD_FAB2_LIB.BASEBOARD_FAB2(SCH_1):PAGE126',
 WATTAGE='1/16W',
 TOLERANCE='1%',
 SEC_TYPE='0402',
 MATERIAL='EMPTY',
 BOM_COST='SYS_CLOCK',
 PHYS_PAGE='126',
 XY='(-6325,4300)',
 ROT='2',
 VER='2',
 VALUE='4.75K',
 PACK_TYPE='0402',
 PART_NUMBER='G21796-072',
 LOCATION='R2N10',
 ROOM='DB1200ZL',
 SEC='1',
 CDS_LIB='mstr_discrete',
 CDS_PART_NAME='RES_0402-4.75K,1%,1/16W,EMPTY,A',
 PRIM_FILE='./archive_libs/mstr_discrete/res/chips/chips.prt';

PART_NAME
 R2N12 'RES_0402-10.0K,1%,1/16W,EMPTY,A':
 ROOM='SB';

SECTION_NUMBER 1
 '@BASEBOARD_FAB2_LIB.BASEBOARD_FAB2(SCH_1):PAGE133_I122@MSTR_DISCRETE.RES(CHIPS)':
 C_PATH='@baseboard_fab2_lib.baseboard_fab2(sch_1):page133_i122@mstr_discrete.re~
s(chips)',
 P_PATH='@baseboard_fab2_lib.baseboard_fab2(sch_1):page133_i122@mstr_discrete.re~
s(chips)',
 PATH='I122',
 DRAWING='@BASEBOARD_FAB2_LIB.BASEBOARD_FAB2(SCH_1):PAGE133',
 WATTAGE='1/16W',
 TOLERANCE='1%',
 MATERIAL='EMPTY',
 BOM_COST='SB',
 PHYS_PAGE='133',
 XY='(-2500,4075)',
 ROT='0',
 VER='1',
 VALUE='10.0K',
 PACK_TYPE='0402',
 PART_NUMBER='G21796-016',
 LOCATION='R2N12',
 ROOM='SB',
 CDS_LIB='mstr_discrete',
 CDS_PART_NAME='RES_0402-10.0K,1%,1/16W,EMPTY,A',
 PRIM_FILE='./archive_libs/mstr_discrete/res/chips/chips.prt';

PART_NAME
 R2N13 'RES_0402-10.0K,1%,1/16W,CHIP,GA':
 ROOM='BMC';

SECTION_NUMBER 1
 '@BASEBOARD_FAB2_LIB.BASEBOARD_FAB2(SCH_1):PAGE147_I75@MSTR_DISCRETE.RES(CHIPS)':
 C_PATH='@baseboard_fab2_lib.baseboard_fab2(sch_1):page147_i75@mstr_discrete.res~
(chips)',
 P_PATH='@baseboard_fab2_lib.baseboard_fab2(sch_1):page147_i75@mstr_discrete.res~
(chips)',
 PATH='I75',
 DRAWING='@BASEBOARD_FAB2_LIB.BASEBOARD_FAB2(SCH_1):PAGE147',
 WATTAGE='1/16W',
 TOLERANCE='1%',
 SEC_TYPE='0402',
 MATERIAL='CHIP',
 BOM_COST='SM_CONTROLLER',
 PHYS_PAGE='147',
 XY='(-150,1950)',
 ROT='0',
 VER='2',
 VALUE='10.0K',
 PACK_TYPE='0402',
 PART_NUMBER='G21796-016',
 LOCATION='R2N13',
 ROOM='BMC',
 SEC='1',
 CDS_LIB='mstr_discrete',
 CDS_PART_NAME='RES_0402-10.0K,1%,1/16W,CHIP,GA',
 PRIM_FILE='./archive_libs/mstr_discrete/res/chips/chips.prt';

PART_NAME
 R2N14 'RES_0402-1.00K,1%,1/16W,EMPTY,A':
 ROOM='SB';

SECTION_NUMBER 1
 '@BASEBOARD_FAB2_LIB.BASEBOARD_FAB2(SCH_1):PAGE125_I83@MSTR_DISCRETE.RES(CHIPS)':
 C_PATH='@baseboard_fab2_lib.baseboard_fab2(sch_1):page125_i83@mstr_discrete.res~
(chips)',
 P_PATH='@baseboard_fab2_lib.baseboard_fab2(sch_1):page125_i83@mstr_discrete.res~
(chips)',
 PATH='I83',
 DRAWING='@BASEBOARD_FAB2_LIB.BASEBOARD_FAB2(SCH_1):PAGE125',
 WATTAGE='1/16W',
 TOLERANCE='1%',
 SEC_TYPE='0402',
 MATERIAL='EMPTY',
 BOM_COST='SB',
 PHYS_PAGE='125',
 XY='(-925,1525)',
 ROT='0',
 VER='2',
 VALUE='1.00K',
 PACK_TYPE='0402',
 PART_NUMBER='G21796-026',
 LOCATION='R2N14',
 ROOM='SB',
 SEC='1',
 CDS_LIB='mstr_discrete',
 CDS_PART_NAME='RES_0402-1.00K,1%,1/16W,EMPTY,A',
 PRIM_FILE='./archive_libs/mstr_discrete/res/chips/chips.prt';

PART_NAME
 R2N16 'RES_0402-10.0K,1%,1/16W,CHIP,GA':
 ROOM='SB';

SECTION_NUMBER 1
 '@BASEBOARD_FAB2_LIB.BASEBOARD_FAB2(SCH_1):PAGE133_I247@MSTR_DISCRETE.RES(CHIPS)':
 C_PATH='@baseboard_fab2_lib.baseboard_fab2(sch_1):page133_i247@mstr_discrete.re~
s(chips)',
 P_PATH='@baseboard_fab2_lib.baseboard_fab2(sch_1):page133_i247@mstr_discrete.re~
s(chips)',
 PATH='I247',
 DRAWING='@BASEBOARD_FAB2_LIB.BASEBOARD_FAB2(SCH_1):PAGE133',
 WATTAGE='1/16W',
 TOLERANCE='1%',
 MATERIAL='CHIP',
 BOM_COST='SB',
 PHYS_PAGE='133',
 XY='(-4650,2725)',
 ROT='0',
 VER='1',
 VALUE='10.0K',
 PACK_TYPE='0402',
 PART_NUMBER='G21796-016',
 LOCATION='R2N16',
 ROOM='SB',
 CDS_LIB='mstr_discrete',
 CDS_PART_NAME='RES_0402-10.0K,1%,1/16W,CHIP,GA',
 PRIM_FILE='./archive_libs/mstr_discrete/res/chips/chips.prt';

PART_NAME
 R2N17 'RES_0402-2.7K,1%,1/16W,CHIP,G2A':
 GROUP='PU_SKU_ID4',
 ROOM='BMC_MISC';

SECTION_NUMBER 1
 '@BASEBOARD_FAB2_LIB.BASEBOARD_FAB2(SCH_1):PAGE164_I46@MSTR_DISCRETE.RES(CHIPS)':
 C_PATH='@baseboard_fab2_lib.baseboard_fab2(sch_1):page164_i46@mstr_discrete.res~
(chips)',
 P_PATH='@baseboard_fab2_lib.baseboard_fab2(sch_1):page164_i46@mstr_discrete.res~
(chips)',
 PATH='I46',
 DRAWING='@BASEBOARD_FAB2_LIB.BASEBOARD_FAB2(SCH_1):PAGE164',
 WATTAGE='1/16W',
 TOLERANCE='1%',
 SEC_TYPE='0402',
 MATERIAL='CHIP',
 BOM_COST='SM_CONTROLLER',
 PHYS_PAGE='164',
 XY='(-7175,4475)',
 ROT='0',
 VER='1',
 VALUE='2.7K',
 PACK_TYPE='0402',
 PART_NUMBER='G21796-344',
 LOCATION='R2N17',
 ROOM='BMC_MISC',
 GROUP='PU_SKU_ID4',
 SEC='1',
 CDS_LIB='mstr_discrete',
 CDS_PART_NAME='RES_0402-2.7K,1%,1/16W,CHIP,G2A',
 PRIM_FILE='./archive_libs/mstr_discrete/res/chips/chips.prt';

PART_NAME
 R2N18 'RES_0402-1.00K,1%,1/16W,CHIP,GA':
 GROUP='PD_SKU_ID4',
 ROOM='BMC_MISC';

SECTION_NUMBER 1
 '@BASEBOARD_FAB2_LIB.BASEBOARD_FAB2(SCH_1):PAGE164_I32@MSTR_DISCRETE.RES(CHIPS)':
 C_PATH='@baseboard_fab2_lib.baseboard_fab2(sch_1):page164_i32@mstr_discrete.res~
(chips)',
 P_PATH='@baseboard_fab2_lib.baseboard_fab2(sch_1):page164_i32@mstr_discrete.res~
(chips)',
 PATH='I32',
 DRAWING='@BASEBOARD_FAB2_LIB.BASEBOARD_FAB2(SCH_1):PAGE164',
 WATTAGE='1/16W',
 TOLERANCE='1%',
 SEC_TYPE='0402',
 MATERIAL='CHIP',
 BOM_COST='SM_CONTROLLER',
 PHYS_PAGE='164',
 XY='(-6625,3350)',
 ROT='0',
 VER='2',
 VALUE='1.00K',
 PACK_TYPE='0402',
 PART_NUMBER='G21796-026',
 LOCATION='R2N18',
 ROOM='BMC_MISC',
 GROUP='PD_SKU_ID4',
 SEC='1',
 CDS_LIB='mstr_discrete',
 CDS_PART_NAME='RES_0402-1.00K,1%,1/16W,CHIP,GA',
 PRIM_FILE='./archive_libs/mstr_discrete/res/chips/chips.prt';

PART_NAME
 R2N19 'RES_0402-49.9,1%,1/16W,CHIP,G2A':
 ROOM='ST_SATA';

SECTION_NUMBER 1
 '@BASEBOARD_FAB2_LIB.BASEBOARD_FAB2(SCH_1):PAGE178_I22@MSTR_DISCRETE.RES(CHIPS)':
 C_PATH='@baseboard_fab2_lib.baseboard_fab2(sch_1):page178_i22@mstr_discrete.res~
(chips)',
 P_PATH='@baseboard_fab2_lib.baseboard_fab2(sch_1):page178_i22@mstr_discrete.res~
(chips)',
 PATH='I22',
 DRAWING='@BASEBOARD_FAB2_LIB.BASEBOARD_FAB2(SCH_1):PAGE178',
 WATTAGE='1/16W',
 TOLERANCE='1%',
 SEC_TYPE='0402',
 MATERIAL='CHIP',
 BOM_COST='ST_SATA',
 PHYS_PAGE='178',
 XY='(-800,1825)',
 ROT='0',
 VER='1',
 VALUE='49.9',
 PACK_TYPE='0402',
 PART_NUMBER='G21796-047',
 LOCATION='R2N19',
 ROOM='ST_SATA',
 SEC='1',
 CDS_LIB='mstr_discrete',
 CDS_PART_NAME='RES_0402-49.9,1%,1/16W,CHIP,G2A',
 PRIM_FILE='./archive_libs/mstr_discrete/res/chips/chips.prt';

PART_NAME
 R2N20 'RES_0402-0.0,5%,1/16W,CHIP,G21A':
 ROOM='SMBUS';

SECTION_NUMBER 1
 '@BASEBOARD_FAB2_LIB.BASEBOARD_FAB2(SCH_1):PAGE138_I171@MSTR_DISCRETE.RES(CHIPS)':
 C_PATH='@baseboard_fab2_lib.baseboard_fab2(sch_1):page138_i171@mstr_discrete.re~
s(chips)',
 P_PATH='@baseboard_fab2_lib.baseboard_fab2(sch_1):page138_i171@mstr_discrete.re~
s(chips)',
 PATH='I171',
 DRAWING='@BASEBOARD_FAB2_LIB.BASEBOARD_FAB2(SCH_1):PAGE138',
 WATTAGE='1/16W',
 TOLERANCE='5%',
 SEC_TYPE='0402',
 MATERIAL='CHIP',
 BOM_COST='SM_CONTROLLER',
 PHYS_PAGE='138',
 XY='(-3975,2150)',
 ROT='0',
 VER='1',
 VALUE='0.0',
 PACK_TYPE='0402',
 PART_NUMBER='G21497-005',
 LOCATION='R2N20',
 ROOM='SMBUS',
 SEC='1',
 CDS_LIB='mstr_discrete',
 CDS_PART_NAME='RES_0402-0.0,5%,1/16W,CHIP,G21A',
 PRIM_FILE='./archive_libs/mstr_discrete/res/chips/chips.prt';

PART_NAME
 R2N21 'RES_0402-0.0,5%,1/16W,CHIP,G21A':
 ROOM='SMBUS';

SECTION_NUMBER 1
 '@BASEBOARD_FAB2_LIB.BASEBOARD_FAB2(SCH_1):PAGE138_I175@MSTR_DISCRETE.RES(CHIPS)':
 C_PATH='@baseboard_fab2_lib.baseboard_fab2(sch_1):page138_i175@mstr_discrete.re~
s(chips)',
 P_PATH='@baseboard_fab2_lib.baseboard_fab2(sch_1):page138_i175@mstr_discrete.re~
s(chips)',
 PATH='I175',
 DRAWING='@BASEBOARD_FAB2_LIB.BASEBOARD_FAB2(SCH_1):PAGE138',
 WATTAGE='1/16W',
 TOLERANCE='5%',
 SEC_TYPE='0402',
 MATERIAL='CHIP',
 BOM_COST='SM_CONTROLLER',
 PHYS_PAGE='138',
 XY='(-3975,2000)',
 ROT='0',
 VER='1',
 VALUE='0.0',
 PACK_TYPE='0402',
 PART_NUMBER='G21497-005',
 LOCATION='R2N21',
 ROOM='SMBUS',
 SEC='1',
 CDS_LIB='mstr_discrete',
 CDS_PART_NAME='RES_0402-0.0,5%,1/16W,CHIP,G21A',
 PRIM_FILE='./archive_libs/mstr_discrete/res/chips/chips.prt';

PART_NAME
 R2N22 'RES_0402-49.9,1%,1/16W,CHIP,G2A':
 ROOM='ST_SATA';

SECTION_NUMBER 1
 '@BASEBOARD_FAB2_LIB.BASEBOARD_FAB2(SCH_1):PAGE178_I23@MSTR_DISCRETE.RES(CHIPS)':
 C_PATH='@baseboard_fab2_lib.baseboard_fab2(sch_1):page178_i23@mstr_discrete.res~
(chips)',
 P_PATH='@baseboard_fab2_lib.baseboard_fab2(sch_1):page178_i23@mstr_discrete.res~
(chips)',
 PATH='I23',
 DRAWING='@BASEBOARD_FAB2_LIB.BASEBOARD_FAB2(SCH_1):PAGE178',
 WATTAGE='1/16W',
 TOLERANCE='1%',
 SEC_TYPE='0402',
 MATERIAL='CHIP',
 BOM_COST='ST_SATA',
 PHYS_PAGE='178',
 XY='(-800,1525)',
 ROT='0',
 VER='1',
 VALUE='49.9',
 PACK_TYPE='0402',
 PART_NUMBER='G21796-047',
 LOCATION='R2N22',
 ROOM='ST_SATA',
 SEC='1',
 CDS_LIB='mstr_discrete',
 CDS_PART_NAME='RES_0402-49.9,1%,1/16W,CHIP,G2A',
 PRIM_FILE='./archive_libs/mstr_discrete/res/chips/chips.prt';

PART_NAME
 R2N23 'RES_0402-10.0K,1%,1/16W,CHIP,GA':
 ROOM='SB';

SECTION_NUMBER 1
 '@BASEBOARD_FAB2_LIB.BASEBOARD_FAB2(SCH_1):PAGE135_I112@MSTR_DISCRETE.RES(CHIPS)':
 C_PATH='@baseboard_fab2_lib.baseboard_fab2(sch_1):page135_i112@mstr_discrete.re~
s(chips)',
 P_PATH='@baseboard_fab2_lib.baseboard_fab2(sch_1):page135_i112@mstr_discrete.re~
s(chips)',
 PATH='I112',
 DRAWING='@BASEBOARD_FAB2_LIB.BASEBOARD_FAB2(SCH_1):PAGE135',
 WATTAGE='1/16W',
 TOLERANCE='1%',
 MATERIAL='CHIP',
 PHYS_PAGE='135',
 XY='(-2150,4775)',
 ROT='0',
 VER='2',
 VALUE='10.0K',
 PACK_TYPE='0402',
 PART_NUMBER='G21796-016',
 LOCATION='R2N23',
 ROOM='SB',
 CDS_LIB='mstr_discrete',
 CDS_PART_NAME='RES_0402-10.0K,1%,1/16W,CHIP,GA',
 PRIM_FILE='./archive_libs/mstr_discrete/res/chips/chips.prt';

PART_NAME
 R2N24 'RES_0402-1.00K,1%,1/16W,EMPTY,A':
 ROOM='SB';

SECTION_NUMBER 1
 '@BASEBOARD_FAB2_LIB.BASEBOARD_FAB2(SCH_1):PAGE135_I113@MSTR_DISCRETE.RES(CHIPS)':
 C_PATH='@baseboard_fab2_lib.baseboard_fab2(sch_1):page135_i113@mstr_discrete.re~
s(chips)',
 P_PATH='@baseboard_fab2_lib.baseboard_fab2(sch_1):page135_i113@mstr_discrete.re~
s(chips)',
 PATH='I113',
 DRAWING='@BASEBOARD_FAB2_LIB.BASEBOARD_FAB2(SCH_1):PAGE135',
 WATTAGE='1/16W',
 TOLERANCE='1%',
 SEC_TYPE='0402',
 MATERIAL='EMPTY',
 PHYS_PAGE='135',
 XY='(-2150,4325)',
 ROT='0',
 VER='2',
 VALUE='1.00K',
 PACK_TYPE='0402',
 PART_NUMBER='G21796-026',
 LOCATION='R2N24',
 ROOM='SB',
 SEC='1',
 CDS_LIB='mstr_discrete',
 CDS_PART_NAME='RES_0402-1.00K,1%,1/16W,EMPTY,A',
 PRIM_FILE='./archive_libs/mstr_discrete/res/chips/chips.prt';

PART_NAME
 R2N25 'RES_0402-51.1,1.0%,1/16W,CHIP,A':
 ROOM='BMC_MISC';

SECTION_NUMBER 1
 '@BASEBOARD_FAB2_LIB.BASEBOARD_FAB2(SCH_1):PAGE157_I302@MSTR_DISCRETE.RES(CHIPS)':
 C_PATH='@baseboard_fab2_lib.baseboard_fab2(sch_1):page157_i302@mstr_discrete.re~
s(chips)',
 P_PATH='@baseboard_fab2_lib.baseboard_fab2(sch_1):page157_i302@mstr_discrete.re~
s(chips)',
 PATH='I302',
 DRAWING='@BASEBOARD_FAB2_LIB.BASEBOARD_FAB2(SCH_1):PAGE157',
 WATTAGE='1/16W',
 TOLERANCE='1.0%',
 SEC_TYPE='0402',
 MATERIAL='CHIP',
 BOM_COST='SM_CONTROLLER',
 PHYS_PAGE='157',
 XY='(-2050,3825)',
 ROT='0',
 VER='1',
 VALUE='51.1',
 PACK_TYPE='0402',
 PART_NUMBER='G21796-208',
 LOCATION='R2N25',
 ROOM='BMC_MISC',
 SEC='1',
 CDS_LIB='mstr_discrete',
 CDS_PART_NAME='RES_0402-51.1,1.0%,1/16W,CHIP,A',
 PRIM_FILE='./archive_libs/mstr_discrete/res/chips/chips.prt';

PART_NAME
 R2N26 'RES_0402-33.2,1%,1/16W,CHIP,G2A':
 ROOM='CPLD';

SECTION_NUMBER 1
 '@BASEBOARD_FAB2_LIB.BASEBOARD_FAB2(SCH_1):PAGE120_I219@MSTR_DISCRETE.RES(CHIPS)':
 C_PATH='@baseboard_fab2_lib.baseboard_fab2(sch_1):page120_i219@mstr_discrete.re~
s(chips)',
 P_PATH='@baseboard_fab2_lib.baseboard_fab2(sch_1):page120_i219@mstr_discrete.re~
s(chips)',
 PATH='I219',
 DRAWING='@BASEBOARD_FAB2_LIB.BASEBOARD_FAB2(SCH_1):PAGE120',
 WATTAGE='1/16W',
 TOLERANCE='1%',
 SEC_TYPE='0402',
 MATERIAL='CHIP',
 PHYS_PAGE='120',
 XY='(-6100,2050)',
 ROT='0',
 VER='1',
 VALUE='33.2',
 PACK_TYPE='0402',
 PART_NUMBER='G21796-074',
 LOCATION='R2N26',
 ROOM='CPLD',
 SEC='1',
 CDS_LIB='mstr_discrete',
 CDS_PART_NAME='RES_0402-33.2,1%,1/16W,CHIP,G2A',
 PRIM_FILE='./archive_libs/mstr_discrete/res/chips/chips.prt';

PART_NAME
 R2N27 'RES_0402-4.75K,1%,1/16W,CHIP,GA':
 ROOM='BMC_MISC';

SECTION_NUMBER 1
 '@BASEBOARD_FAB2_LIB.BASEBOARD_FAB2(SCH_1):PAGE157_I97@MSTR_DISCRETE.RES(CHIPS)':
 C_PATH='@baseboard_fab2_lib.baseboard_fab2(sch_1):page157_i97@mstr_discrete.res~
(chips)',
 P_PATH='@baseboard_fab2_lib.baseboard_fab2(sch_1):page157_i97@mstr_discrete.res~
(chips)',
 PATH='I97',
 DRAWING='@BASEBOARD_FAB2_LIB.BASEBOARD_FAB2(SCH_1):PAGE157',
 WATTAGE='1/16W',
 TOLERANCE='1%',
 SEC_TYPE='0402',
 MATERIAL='CHIP',
 BOM_COST='SM_CONTROLLER',
 PHYS_PAGE='157',
 XY='(-1850,4025)',
 ROT='0',
 VER='2',
 VALUE='4.75K',
 PACK_TYPE='0402',
 PART_NUMBER='G21796-072',
 LOCATION='R2N27',
 ROOM='BMC_MISC',
 SEC='1',
 CDS_LIB='mstr_discrete',
 CDS_PART_NAME='RES_0402-4.75K,1%,1/16W,CHIP,GA',
 PRIM_FILE='./archive_libs/mstr_discrete/res/chips/chips.prt';

PART_NAME
 R2N28 'RES_0402-10.0K,1%,1/16W,CHIP,GA':
 ROOM='SB';

SECTION_NUMBER 1
 '@BASEBOARD_FAB2_LIB.BASEBOARD_FAB2(SCH_1):PAGE136_I147@MSTR_DISCRETE.RES(CHIPS)':
 C_PATH='@baseboard_fab2_lib.baseboard_fab2(sch_1):page136_i147@mstr_discrete.re~
s(chips)',
 P_PATH='@baseboard_fab2_lib.baseboard_fab2(sch_1):page136_i147@mstr_discrete.re~
s(chips)',
 PATH='I147',
 DRAWING='@BASEBOARD_FAB2_LIB.BASEBOARD_FAB2(SCH_1):PAGE136',
 WATTAGE='1/16W',
 TOLERANCE='1%',
 SEC_TYPE='0402',
 MATERIAL='CHIP',
 BOM_COST='SB',
 PHYS_PAGE='136',
 XY='(-2500,4800)',
 ROT='2',
 VER='2',
 VALUE='10.0K',
 PACK_TYPE='0402',
 PART_NUMBER='G21796-016',
 LOCATION='R2N28',
 ROOM='SB',
 SEC='1',
 CDS_LIB='mstr_discrete',
 CDS_PART_NAME='RES_0402-10.0K,1%,1/16W,CHIP,GA',
 PRIM_FILE='./archive_libs/mstr_discrete/res/chips/chips.prt';

PART_NAME
 R2N29 'RES_0402-1.5K,1%,1/16W,CHIP,G2A':
 ROOM='SB';

SECTION_NUMBER 1
 '@BASEBOARD_FAB2_LIB.BASEBOARD_FAB2(SCH_1):PAGE133_I352@MSTR_DISCRETE.RES(CHIPS)':
 C_PATH='@baseboard_fab2_lib.baseboard_fab2(sch_1):page133_i352@mstr_discrete.re~
s(chips)',
 P_PATH='@baseboard_fab2_lib.baseboard_fab2(sch_1):page133_i352@mstr_discrete.re~
s(chips)',
 PATH='I352',
 DRAWING='@BASEBOARD_FAB2_LIB.BASEBOARD_FAB2(SCH_1):PAGE133',
 WATTAGE='1/16W',
 TOLERANCE='1%',
 SEC_TYPE='0402',
 MATERIAL='CHIP',
 BOM_COST='SB',
 PHYS_PAGE='133',
 XY='(-375,2475)',
 ROT='0',
 VER='1',
 VALUE='1.5K',
 PACK_TYPE='0402',
 PART_NUMBER='G21796-003',
 LOCATION='R2N29',
 ROOM='SB',
 SEC='1',
 CDS_LIB='mstr_discrete',
 CDS_PART_NAME='RES_0402-1.5K,1%,1/16W,CHIP,G2A',
 PRIM_FILE='./archive_libs/mstr_discrete/res/chips/chips.prt';

PART_NAME
 R2N31 'RES_0402-49.9,1%,1/16W,CHIP,G2A':
 ROOM='ST_SATA';

SECTION_NUMBER 1
 '@BASEBOARD_FAB2_LIB.BASEBOARD_FAB2(SCH_1):PAGE178_I11@MSTR_DISCRETE.RES(CHIPS)':
 C_PATH='@baseboard_fab2_lib.baseboard_fab2(sch_1):page178_i11@mstr_discrete.res~
(chips)',
 P_PATH='@baseboard_fab2_lib.baseboard_fab2(sch_1):page178_i11@mstr_discrete.res~
(chips)',
 PATH='I11',
 DRAWING='@BASEBOARD_FAB2_LIB.BASEBOARD_FAB2(SCH_1):PAGE178',
 WATTAGE='1/16W',
 TOLERANCE='1%',
 SEC_TYPE='0402',
 MATERIAL='CHIP',
 BOM_COST='ST_SATA',
 PHYS_PAGE='178',
 XY='(-800,3425)',
 ROT='0',
 VER='1',
 VALUE='49.9',
 PACK_TYPE='0402',
 PART_NUMBER='G21796-047',
 LOCATION='R2N31',
 ROOM='ST_SATA',
 SEC='1',
 CDS_LIB='mstr_discrete',
 CDS_PART_NAME='RES_0402-49.9,1%,1/16W,CHIP,G2A',
 PRIM_FILE='./archive_libs/mstr_discrete/res/chips/chips.prt';

PART_NAME
 R2N32 'RES_0402-4.75K,1%,1/16W,CHIP,GA':
 ROOM='SB';

SECTION_NUMBER 1
 '@BASEBOARD_FAB2_LIB.BASEBOARD_FAB2(SCH_1):PAGE133_I341@MSTR_DISCRETE.RES(CHIPS)':
 C_PATH='@baseboard_fab2_lib.baseboard_fab2(sch_1):page133_i341@mstr_discrete.re~
s(chips)',
 P_PATH='@baseboard_fab2_lib.baseboard_fab2(sch_1):page133_i341@mstr_discrete.re~
s(chips)',
 PATH='I341',
 DRAWING='@BASEBOARD_FAB2_LIB.BASEBOARD_FAB2(SCH_1):PAGE133',
 WATTAGE='1/16W',
 TOLERANCE='1%',
 SEC_TYPE='0402',
 MATERIAL='CHIP',
 BOM_COST='SB',
 PHYS_PAGE='133',
 XY='(-2475,2700)',
 ROT='0',
 VER='1',
 VALUE='4.75K',
 PACK_TYPE='0402',
 PART_NUMBER='G21796-072',
 LOCATION='R2N32',
 ROOM='SB',
 SEC='1',
 CDS_LIB='mstr_discrete',
 CDS_PART_NAME='RES_0402-4.75K,1%,1/16W,CHIP,GA',
 PRIM_FILE='./archive_libs/mstr_discrete/res/chips/chips.prt';

PART_NAME
 R2P1 'RES_0402-0.0,5%,1/16W,CHIP,G21A':;

SECTION_NUMBER 1
 '@BASEBOARD_FAB2_LIB.BASEBOARD_FAB2(SCH_1):PAGE121_I91@MSTR_DISCRETE.RES(CHIPS)':
 C_PATH='@baseboard_fab2_lib.baseboard_fab2(sch_1):page121_i91@mstr_discrete.res~
(chips)',
 P_PATH='@baseboard_fab2_lib.baseboard_fab2(sch_1):page121_i91@mstr_discrete.res~
(chips)',
 PATH='I91',
 DRAWING='@BASEBOARD_FAB2_LIB.BASEBOARD_FAB2(SCH_1):PAGE121',
 WATTAGE='1/16W',
 TOLERANCE='5%',
 SEC_TYPE='0402',
 MATERIAL='CHIP',
 PHYS_PAGE='121',
 XY='(-5100,700)',
 ROT='0',
 VER='1',
 VALUE='0.0',
 PACK_TYPE='0402',
 PART_NUMBER='G21497-005',
 LOCATION='R2P1',
 SEC='1',
 CDS_LIB='mstr_discrete',
 CDS_PART_NAME='RES_0402-0.0,5%,1/16W,CHIP,G21A',
 PRIM_FILE='./archive_libs/mstr_discrete/res/chips/chips.prt';

PART_NAME
 R2P2 'RES_0402-1.00K,1%,1/16W,CHIP,GA':
 ROOM='DEBUG';

SECTION_NUMBER 1
 '@BASEBOARD_FAB2_LIB.BASEBOARD_FAB2(SCH_1):PAGE111_I37@MSTR_DISCRETE.RES(CHIPS)':
 C_PATH='@baseboard_fab2_lib.baseboard_fab2(sch_1):page111_i37@mstr_discrete.res~
(chips)',
 P_PATH='@baseboard_fab2_lib.baseboard_fab2(sch_1):page111_i37@mstr_discrete.res~
(chips)',
 PATH='I37',
 DRAWING='@BASEBOARD_FAB2_LIB.BASEBOARD_FAB2(SCH_1):PAGE111',
 WATTAGE='1/16W',
 TOLERANCE='1%',
 SEC_TYPE='0402',
 MATERIAL='CHIP',
 BOM_COST='DEBUG',
 PHYS_PAGE='111',
 XY='(-2100,4650)',
 ROT='0',
 VER='1',
 VALUE='1.00K',
 PACK_TYPE='0402',
 PART_NUMBER='G21796-026',
 LOCATION='R2P2',
 ROOM='DEBUG',
 SEC='1',
 CDS_LIB='mstr_discrete',
 CDS_PART_NAME='RES_0402-1.00K,1%,1/16W,CHIP,GA',
 PRIM_FILE='./archive_libs/mstr_discrete/res/chips/chips.prt';

PART_NAME
 R2P3 'RES_0402-4.75K,1%,1/16W,CHIP,GA':
 ROOM='FAST_PROCHOT';

SECTION_NUMBER 1
 '@BASEBOARD_FAB2_LIB.BASEBOARD_FAB2(SCH_1):PAGE170_I2@MSTR_DISCRETE.RES(CHIPS)':
 C_PATH='@baseboard_fab2_lib.baseboard_fab2(sch_1):page170_i2@mstr_discrete.res(~
chips)',
 P_PATH='@baseboard_fab2_lib.baseboard_fab2(sch_1):page170_i2@mstr_discrete.res(~
chips)',
 PATH='I2',
 DRAWING='@BASEBOARD_FAB2_LIB.BASEBOARD_FAB2(SCH_1):PAGE170',
 WATTAGE='1/16W',
 TOLERANCE='1%',
 SEC_TYPE='0402',
 MATERIAL='CHIP',
 BOM_COST='FAST_PROCHOT',
 PHYS_PAGE='170',
 XY='(-2125,5250)',
 ROT='0',
 VER='2',
 VALUE='4.75K',
 PACK_TYPE='0402',
 PART_NUMBER='G21796-072',
 LOCATION='R2P3',
 ROOM='FAST_PROCHOT',
 SEC='1',
 CDS_LIB='mstr_discrete',
 CDS_PART_NAME='RES_0402-4.75K,1%,1/16W,CHIP,GA',
 PRIM_FILE='./archive_libs/mstr_discrete/res/chips/chips.prt';

PART_NAME
 R2P4 'RES_0402-33.2,1%,1/16W,CHIP,G2A':;

SECTION_NUMBER 1
 '@BASEBOARD_FAB2_LIB.BASEBOARD_FAB2(SCH_1):PAGE170_I74@MSTR_DISCRETE.RES(CHIPS)':
 C_PATH='@baseboard_fab2_lib.baseboard_fab2(sch_1):page170_i74@mstr_discrete.res~
(chips)',
 P_PATH='@baseboard_fab2_lib.baseboard_fab2(sch_1):page170_i74@mstr_discrete.res~
(chips)',
 PATH='I74',
 DRAWING='@BASEBOARD_FAB2_LIB.BASEBOARD_FAB2(SCH_1):PAGE170',
 WATTAGE='1/16W',
 TOLERANCE='1%',
 SEC_TYPE='0402',
 MATERIAL='CHIP',
 PHYS_PAGE='170',
 XY='(-1675,4775)',
 ROT='0',
 VER='1',
 VALUE='33.2',
 PACK_TYPE='0402',
 PART_NUMBER='G21796-074',
 LOCATION='R2P4',
 SEC='1',
 CDS_LIB='mstr_discrete',
 CDS_PART_NAME='RES_0402-33.2,1%,1/16W,CHIP,G2A',
 PRIM_FILE='./archive_libs/mstr_discrete/res/chips/chips.prt';

PART_NAME
 R2P5 'RES_0402-4.75K,1%,1/16W,CHIP,GA':
 ROOM='PROC_SIDEBAND';

SECTION_NUMBER 1
 '@BASEBOARD_FAB2_LIB.BASEBOARD_FAB2(SCH_1):PAGE170_I56@MSTR_DISCRETE.RES(CHIPS)':
 C_PATH='@baseboard_fab2_lib.baseboard_fab2(sch_1):page170_i56@mstr_discrete.res~
(chips)',
 P_PATH='@baseboard_fab2_lib.baseboard_fab2(sch_1):page170_i56@mstr_discrete.res~
(chips)',
 PATH='I56',
 DRAWING='@BASEBOARD_FAB2_LIB.BASEBOARD_FAB2(SCH_1):PAGE170',
 WATTAGE='1/16W',
 TOLERANCE='1%',
 SEC_TYPE='0402',
 MATERIAL='CHIP',
 BOM_COST='PROC_SIDEBAND',
 PHYS_PAGE='170',
 XY='(-4150,5100)',
 ROT='0',
 VER='2',
 VALUE='4.75K',
 PACK_TYPE='0402',
 PART_NUMBER='G21796-072',
 LOCATION='R2P5',
 ROOM='PROC_SIDEBAND',
 SEC='1',
 CDS_LIB='mstr_discrete',
 CDS_PART_NAME='RES_0402-4.75K,1%,1/16W,CHIP,GA',
 PRIM_FILE='./archive_libs/mstr_discrete/res/chips/chips.prt';

PART_NAME
 R2P8 'RES_0402-4.75K,1%,1/16W,CHIP,GA':
 ROOM='PROC_SIDEBAND';

SECTION_NUMBER 1
 '@BASEBOARD_FAB2_LIB.BASEBOARD_FAB2(SCH_1):PAGE170_I75@MSTR_DISCRETE.RES(CHIPS)':
 C_PATH='@baseboard_fab2_lib.baseboard_fab2(sch_1):page170_i75@mstr_discrete.res~
(chips)',
 P_PATH='@baseboard_fab2_lib.baseboard_fab2(sch_1):page170_i75@mstr_discrete.res~
(chips)',
 PATH='I75',
 DRAWING='@BASEBOARD_FAB2_LIB.BASEBOARD_FAB2(SCH_1):PAGE170',
 WATTAGE='1/16W',
 TOLERANCE='1%',
 SEC_TYPE='0402',
 MATERIAL='CHIP',
 BOM_COST='PROC_SIDEBAND',
 PHYS_PAGE='170',
 XY='(-3825,5100)',
 ROT='0',
 VER='2',
 VALUE='4.75K',
 PACK_TYPE='0402',
 PART_NUMBER='G21796-072',
 LOCATION='R2P8',
 ROOM='PROC_SIDEBAND',
 SEC='1',
 CDS_LIB='mstr_discrete',
 CDS_PART_NAME='RES_0402-4.75K,1%,1/16W,CHIP,GA',
 PRIM_FILE='./archive_libs/mstr_discrete/res/chips/chips.prt';

PART_NAME
 R2P11 'RES_0402-1.00K,1%,1/16W,EMPTY,A':
 ROOM='PROC_SIDEBAND';

SECTION_NUMBER 1
 '@BASEBOARD_FAB2_LIB.BASEBOARD_FAB2(SCH_1):PAGE170_I63@MSTR_DISCRETE.RES(CHIPS)':
 C_PATH='@baseboard_fab2_lib.baseboard_fab2(sch_1):page170_i63@mstr_discrete.res~
(chips)',
 P_PATH='@baseboard_fab2_lib.baseboard_fab2(sch_1):page170_i63@mstr_discrete.res~
(chips)',
 PATH='I63',
 DRAWING='@BASEBOARD_FAB2_LIB.BASEBOARD_FAB2(SCH_1):PAGE170',
 WATTAGE='1/16W',
 TOLERANCE='1%',
 SEC_TYPE='0402',
 MATERIAL='EMPTY',
 BOM_COST='PROC_SIDEBAND',
 PHYS_PAGE='170',
 XY='(-4525,3925)',
 ROT='0',
 VER='2',
 VALUE='1.00K',
 PACK_TYPE='0402',
 PART_NUMBER='G21796-026',
 LOCATION='R2P11',
 ROOM='PROC_SIDEBAND',
 SEC='1',
 CDS_LIB='mstr_discrete',
 CDS_PART_NAME='RES_0402-1.00K,1%,1/16W,EMPTY,A',
 PRIM_FILE='./archive_libs/mstr_discrete/res/chips/chips.prt';

PART_NAME
 R2P12 'RES_0402-0.0,5%,1/16W,EMPTY,G2A':
 ROOM='NV_DIMM';

SECTION_NUMBER 1
 '@BASEBOARD_FAB2_LIB.BASEBOARD_FAB2(SCH_1):PAGE89_I23@MSTR_DISCRETE.RES(CHIPS)':
 C_PATH='@baseboard_fab2_lib.baseboard_fab2(sch_1):page89_i23@mstr_discrete.res(~
chips)',
 P_PATH='@baseboard_fab2_lib.baseboard_fab2(sch_1):page89_i23@mstr_discrete.res(~
chips)',
 PATH='I23',
 DRAWING='@BASEBOARD_FAB2_LIB.BASEBOARD_FAB2(SCH_1):PAGE89',
 WATTAGE='1/16W',
 TOLERANCE='5%',
 MATERIAL='EMPTY',
 BOM_COST='MEM_NV',
 PHYS_PAGE='89',
 XY='(3225,3525)',
 ROT='0',
 VER='1',
 VALUE='0.0',
 PACK_TYPE='0402',
 PART_NUMBER='G21497-005',
 LOCATION='R2P12',
 ROOM='NV_DIMM',
 CDS_LIB='mstr_discrete',
 CDS_PART_NAME='RES_0402-0.0,5%,1/16W,EMPTY,G2A',
 PRIM_FILE='./archive_libs/mstr_discrete/res/chips/chips.prt';

PART_NAME
 R2P13 'RES_0402-4.75K,1%,1/16W,CHIP,GA':
 ROOM='PROC_SIDEBAND';

SECTION_NUMBER 1
 '@BASEBOARD_FAB2_LIB.BASEBOARD_FAB2(SCH_1):PAGE170_I61@MSTR_DISCRETE.RES(CHIPS)':
 C_PATH='@baseboard_fab2_lib.baseboard_fab2(sch_1):page170_i61@mstr_discrete.res~
(chips)',
 P_PATH='@baseboard_fab2_lib.baseboard_fab2(sch_1):page170_i61@mstr_discrete.res~
(chips)',
 PATH='I61',
 DRAWING='@BASEBOARD_FAB2_LIB.BASEBOARD_FAB2(SCH_1):PAGE170',
 WATTAGE='1/16W',
 TOLERANCE='1%',
 SEC_TYPE='0402',
 MATERIAL='CHIP',
 BOM_COST='PROC_SIDEBAND',
 PHYS_PAGE='170',
 XY='(-4600,4350)',
 ROT='0',
 VER='2',
 VALUE='4.75K',
 PACK_TYPE='0402',
 PART_NUMBER='G21796-072',
 LOCATION='R2P13',
 ROOM='PROC_SIDEBAND',
 SEC='1',
 CDS_LIB='mstr_discrete',
 CDS_PART_NAME='RES_0402-4.75K,1%,1/16W,CHIP,GA',
 PRIM_FILE='./archive_libs/mstr_discrete/res/chips/chips.prt';

PART_NAME
 R2P14 'RES_0402-0.0,5%,1/16W,CHIP,G21A':
 ROOM='M_2';

SECTION_NUMBER 1
 '@BASEBOARD_FAB2_LIB.BASEBOARD_FAB2(SCH_1):PAGE185_I115@MSTR_DISCRETE.RES(CHIPS)':
 C_PATH='@baseboard_fab2_lib.baseboard_fab2(sch_1):page185_i115@mstr_discrete.re~
s(chips)',
 P_PATH='@baseboard_fab2_lib.baseboard_fab2(sch_1):page185_i115@mstr_discrete.re~
s(chips)',
 PATH='I115',
 DRAWING='@BASEBOARD_FAB2_LIB.BASEBOARD_FAB2(SCH_1):PAGE185',
 WATTAGE='1/16W',
 TOLERANCE='5%',
 SEC_TYPE='0402',
 MATERIAL='CHIP',
 BOM_COST='ST_FLASH',
 PHYS_PAGE='185',
 XY='(-4250,2500)',
 ROT='0',
 VER='1',
 VALUE='0.0',
 PACK_TYPE='0402',
 PART_NUMBER='G21497-005',
 LOCATION='R2P14',
 ROOM='M_2',
 SEC='1',
 CDS_LIB='mstr_discrete',
 CDS_PART_NAME='RES_0402-0.0,5%,1/16W,CHIP,G21A',
 PRIM_FILE='./archive_libs/mstr_discrete/res/chips/chips.prt';

PART_NAME
 R2P15 'RES_0402-10.0K,1%,1/16W,CHIP,GA':
 ROOM='M_2';

SECTION_NUMBER 1
 '@BASEBOARD_FAB2_LIB.BASEBOARD_FAB2(SCH_1):PAGE185_I111@MSTR_DISCRETE.RES(CHIPS)':
 C_PATH='@baseboard_fab2_lib.baseboard_fab2(sch_1):page185_i111@mstr_discrete.re~
s(chips)',
 P_PATH='@baseboard_fab2_lib.baseboard_fab2(sch_1):page185_i111@mstr_discrete.re~
s(chips)',
 PATH='I111',
 DRAWING='@BASEBOARD_FAB2_LIB.BASEBOARD_FAB2(SCH_1):PAGE185',
 WATTAGE='1/16W',
 TOLERANCE='1%',
 SEC_TYPE='0402',
 MATERIAL='CHIP',
 BOM_COST='ST_FLASH',
 PHYS_PAGE='185',
 XY='(-5500,2700)',
 ROT='0',
 VER='2',
 VALUE='10.0K',
 PACK_TYPE='0402',
 PART_NUMBER='G21796-016',
 LOCATION='R2P15',
 ROOM='M_2',
 SEC='1',
 CDS_LIB='mstr_discrete',
 CDS_PART_NAME='RES_0402-10.0K,1%,1/16W,CHIP,GA',
 PRIM_FILE='./archive_libs/mstr_discrete/res/chips/chips.prt';

PART_NAME
 R2P16 'RES_0402-10.0K,1%,1/16W,CHIP,GA':
 ROOM='M_2';

SECTION_NUMBER 1
 '@BASEBOARD_FAB2_LIB.BASEBOARD_FAB2(SCH_1):PAGE185_I113@MSTR_DISCRETE.RES(CHIPS)':
 C_PATH='@baseboard_fab2_lib.baseboard_fab2(sch_1):page185_i113@mstr_discrete.re~
s(chips)',
 P_PATH='@baseboard_fab2_lib.baseboard_fab2(sch_1):page185_i113@mstr_discrete.re~
s(chips)',
 PATH='I113',
 DRAWING='@BASEBOARD_FAB2_LIB.BASEBOARD_FAB2(SCH_1):PAGE185',
 WATTAGE='1/16W',
 TOLERANCE='1%',
 SEC_TYPE='0402',
 MATERIAL='CHIP',
 BOM_COST='ST_FLASH',
 PHYS_PAGE='185',
 XY='(-4400,2800)',
 ROT='0',
 VER='2',
 VALUE='10.0K',
 PACK_TYPE='0402',
 PART_NUMBER='G21796-016',
 LOCATION='R2P16',
 ROOM='M_2',
 SEC='1',
 CDS_LIB='mstr_discrete',
 CDS_PART_NAME='RES_0402-10.0K,1%,1/16W,CHIP,GA',
 PRIM_FILE='./archive_libs/mstr_discrete/res/chips/chips.prt';

PART_NAME
 R2P17 'RES_0402-4.75K,1%,1/16W,CHIP,GA':
 ROOM='THERMTRIP_PCH';

SECTION_NUMBER 1
 '@BASEBOARD_FAB2_LIB.BASEBOARD_FAB2(SCH_1):PAGE134_I3@MSTR_DISCRETE.RES(CHIPS)':
 C_PATH='@baseboard_fab2_lib.baseboard_fab2(sch_1):page134_i3@mstr_discrete.res(~
chips)',
 P_PATH='@baseboard_fab2_lib.baseboard_fab2(sch_1):page134_i3@mstr_discrete.res(~
chips)',
 PATH='I3',
 DRAWING='@BASEBOARD_FAB2_LIB.BASEBOARD_FAB2(SCH_1):PAGE134',
 WATTAGE='1/16W',
 TOLERANCE='1%',
 SEC_TYPE='0402',
 MATERIAL='CHIP',
 BOM_COST='SB',
 PHYS_PAGE='134',
 XY='(700,4925)',
 ROT='0',
 VER='2',
 VALUE='4.75K',
 PACK_TYPE='0402',
 PART_NUMBER='G21796-072',
 LOCATION='R2P17',
 ROOM='THERMTRIP_PCH',
 SEC='1',
 CDS_LIB='mstr_discrete',
 CDS_PART_NAME='RES_0402-4.75K,1%,1/16W,CHIP,GA',
 PRIM_FILE='./archive_libs/mstr_discrete/res/chips/chips.prt';

PART_NAME
 R2P18 'RES_0402-10.0K,1%,1/16W,CHIP,GA':
 ROOM='V_SUPER';

SECTION_NUMBER 1
 '@BASEBOARD_FAB2_LIB.BASEBOARD_FAB2(SCH_1):PAGE196_I121@MSTR_DISCRETE.RES(CHIPS)':
 C_PATH='@baseboard_fab2_lib.baseboard_fab2(sch_1):page196_i121@mstr_discrete.re~
s(chips)',
 P_PATH='@baseboard_fab2_lib.baseboard_fab2(sch_1):page196_i121@mstr_discrete.re~
s(chips)',
 PATH='I121',
 DRAWING='@BASEBOARD_FAB2_LIB.BASEBOARD_FAB2(SCH_1):PAGE196',
 WATTAGE='1/16W',
 TOLERANCE='1%',
 SEC_TYPE='0402',
 MATERIAL='CHIP',
 PHYS_PAGE='196',
 XY='(250,2000)',
 ROT='0',
 VER='2',
 VALUE='10.0K',
 PACK_TYPE='0402',
 PART_NUMBER='G21796-016',
 LOCATION='R2P18',
 ROOM='V_SUPER',
 SEC='1',
 CDS_LIB='mstr_discrete',
 CDS_PART_NAME='RES_0402-10.0K,1%,1/16W,CHIP,GA',
 PRIM_FILE='./archive_libs/mstr_discrete/res/chips/chips.prt';

PART_NAME
 R2P19 'RES_0402-10.0K,1%,1/16W,CHIP,GA':
 ROOM='CPLD';

SECTION_NUMBER 1
 '@BASEBOARD_FAB2_LIB.BASEBOARD_FAB2(SCH_1):PAGE135_I107@MSTR_DISCRETE.RES(CHIPS)':
 C_PATH='@baseboard_fab2_lib.baseboard_fab2(sch_1):page135_i107@mstr_discrete.re~
s(chips)',
 P_PATH='@baseboard_fab2_lib.baseboard_fab2(sch_1):page135_i107@mstr_discrete.re~
s(chips)',
 PATH='I107',
 DRAWING='@BASEBOARD_FAB2_LIB.BASEBOARD_FAB2(SCH_1):PAGE135',
 WATTAGE='1/16W',
 TOLERANCE='1%',
 SEC_TYPE='0402',
 MATERIAL='CHIP',
 BOM_COST='CPLD',
 PHYS_PAGE='135',
 XY='(200,2225)',
 ROT='0',
 VER='2',
 VALUE='10.0K',
 PACK_TYPE='0402',
 PART_NUMBER='G21796-016',
 LOCATION='R2P19',
 ROOM='CPLD',
 SEC='1',
 CDS_LIB='mstr_discrete',
 CDS_PART_NAME='RES_0402-10.0K,1%,1/16W,CHIP,GA',
 PRIM_FILE='./archive_libs/mstr_discrete/res/chips/chips.prt';

PART_NAME
 R2P20 'RES_0402-100.0,1%,1/16W,CHIP,GA':
 ROOM='V_SUPER';

SECTION_NUMBER 1
 '@BASEBOARD_FAB2_LIB.BASEBOARD_FAB2(SCH_1):PAGE196_I65@MSTR_DISCRETE.RES(CHIPS)':
 C_PATH='@baseboard_fab2_lib.baseboard_fab2(sch_1):page196_i65@mstr_discrete.res~
(chips)',
 P_PATH='@baseboard_fab2_lib.baseboard_fab2(sch_1):page196_i65@mstr_discrete.res~
(chips)',
 PATH='I65',
 DRAWING='@BASEBOARD_FAB2_LIB.BASEBOARD_FAB2(SCH_1):PAGE196',
 WATTAGE='1/16W',
 TOLERANCE='1%',
 SEC_TYPE='0402',
 MATERIAL='CHIP',
 PHYS_PAGE='196',
 XY='(1350,2000)',
 ROT='0',
 VER='1',
 VALUE='100.0',
 PACK_TYPE='0402',
 PART_NUMBER='G21796-017',
 LOCATION='R2P20',
 ROOM='V_SUPER',
 SEC='1',
 CDS_LIB='mstr_discrete',
 CDS_PART_NAME='RES_0402-100.0,1%,1/16W,CHIP,GA',
 PRIM_FILE='./archive_libs/mstr_discrete/res/chips/chips.prt';

PART_NAME
 R2P21 'RES_0402-10.0K,1%,1/16W,CHIP,GA':
 ROOM='V_SUPER';

SECTION_NUMBER 1
 '@BASEBOARD_FAB2_LIB.BASEBOARD_FAB2(SCH_1):PAGE196_I122@MSTR_DISCRETE.RES(CHIPS)':
 C_PATH='@baseboard_fab2_lib.baseboard_fab2(sch_1):page196_i122@mstr_discrete.re~
s(chips)',
 P_PATH='@baseboard_fab2_lib.baseboard_fab2(sch_1):page196_i122@mstr_discrete.re~
s(chips)',
 PATH='I122',
 DRAWING='@BASEBOARD_FAB2_LIB.BASEBOARD_FAB2(SCH_1):PAGE196',
 WATTAGE='1/16W',
 TOLERANCE='1%',
 SEC_TYPE='0402',
 MATERIAL='CHIP',
 PHYS_PAGE='196',
 XY='(750,2200)',
 ROT='0',
 VER='2',
 VALUE='10.0K',
 PACK_TYPE='0402',
 PART_NUMBER='G21796-016',
 LOCATION='R2P21',
 ROOM='V_SUPER',
 SEC='1',
 CDS_LIB='mstr_discrete',
 CDS_PART_NAME='RES_0402-10.0K,1%,1/16W,CHIP,GA',
 PRIM_FILE='./archive_libs/mstr_discrete/res/chips/chips.prt';

PART_NAME
 R2P22 'RES_0402-10.0K,1%,1/16W,CHIP,GA':
 ROOM='SB';

SECTION_NUMBER 1
 '@BASEBOARD_FAB2_LIB.BASEBOARD_FAB2(SCH_1):PAGE133_I360@MSTR_DISCRETE.RES(CHIPS)':
 C_PATH='@baseboard_fab2_lib.baseboard_fab2(sch_1):page133_i360@mstr_discrete.re~
s(chips)',
 P_PATH='@baseboard_fab2_lib.baseboard_fab2(sch_1):page133_i360@mstr_discrete.re~
s(chips)',
 PATH='I360',
 DRAWING='@BASEBOARD_FAB2_LIB.BASEBOARD_FAB2(SCH_1):PAGE133',
 WATTAGE='1/16W',
 TOLERANCE='1%',
 SEC_TYPE='0402',
 MATERIAL='CHIP',
 BOM_COST='SB',
 PHYS_PAGE='133',
 XY='(-4800,1500)',
 ROT='0',
 VER='1',
 VALUE='10.0K',
 PACK_TYPE='0402',
 PART_NUMBER='G21796-016',
 LOCATION='R2P22',
 ROOM='SB',
 SEC='1',
 CDS_LIB='mstr_discrete',
 CDS_PART_NAME='RES_0402-10.0K,1%,1/16W,CHIP,GA',
 PRIM_FILE='./archive_libs/mstr_discrete/res/chips/chips.prt';

PART_NAME
 R2R1 'RES_0402-10.0K,1%,1/16W,CHIP,GA':
 ROOM='CPLD';

SECTION_NUMBER 1
 '@BASEBOARD_FAB2_LIB.BASEBOARD_FAB2(SCH_1):PAGE192_I34@MSTR_DISCRETE.RES(CHIPS)':
 C_PATH='@baseboard_fab2_lib.baseboard_fab2(sch_1):page192_i34@mstr_discrete.res~
(chips)',
 P_PATH='@baseboard_fab2_lib.baseboard_fab2(sch_1):page192_i34@mstr_discrete.res~
(chips)',
 PATH='I34',
 DRAWING='@BASEBOARD_FAB2_LIB.BASEBOARD_FAB2(SCH_1):PAGE192',
 WATTAGE='1/16W',
 TOLERANCE='1%',
 SEC_TYPE='0402',
 MATERIAL='CHIP',
 BOM_COST='CPLD',
 PHYS_PAGE='192',
 XY='(-5750,4400)',
 ROT='0',
 VER='2',
 VALUE='10.0K',
 PACK_TYPE='0402',
 PART_NUMBER='G21796-016',
 LOCATION='R2R1',
 ROOM='CPLD',
 SEC='1',
 CDS_LIB='mstr_discrete',
 CDS_PART_NAME='RES_0402-10.0K,1%,1/16W,CHIP,GA',
 PRIM_FILE='./archive_libs/mstr_discrete/res/chips/chips.prt';

PART_NAME
 R2R2 'RES_0402-33.2,1%,1/16W,CHIP,G2A':
 ROOM='CPLD';

SECTION_NUMBER 1
 '@BASEBOARD_FAB2_LIB.BASEBOARD_FAB2(SCH_1):PAGE190_I338@MSTR_DISCRETE.RES(CHIPS)':
 C_PATH='@baseboard_fab2_lib.baseboard_fab2(sch_1):page190_i338@mstr_discrete.re~
s(chips)',
 P_PATH='@baseboard_fab2_lib.baseboard_fab2(sch_1):page190_i338@mstr_discrete.re~
s(chips)',
 PATH='I338',
 DRAWING='@BASEBOARD_FAB2_LIB.BASEBOARD_FAB2(SCH_1):PAGE190',
 WATTAGE='1/16W',
 TOLERANCE='1%',
 MATERIAL='CHIP',
 BOM_COST='CPLD',
 PHYS_PAGE='190',
 XY='(-1350,5200)',
 ROT='0',
 VER='1',
 VALUE='33.2',
 PACK_TYPE='0402',
 PART_NUMBER='G21796-074',
 LOCATION='R2R2',
 ROOM='CPLD',
 CDS_LIB='mstr_discrete',
 CDS_PART_NAME='RES_0402-33.2,1%,1/16W,CHIP,G2A',
 PRIM_FILE='./archive_libs/mstr_discrete/res/chips/chips.prt';

PART_NAME
 R2R3 'RES_0402-10.0K,1%,1/16W,CHIP,GA':
 ROOM='CPLD';

SECTION_NUMBER 1
 '@BASEBOARD_FAB2_LIB.BASEBOARD_FAB2(SCH_1):PAGE192_I41@MSTR_DISCRETE.RES(CHIPS)':
 C_PATH='@baseboard_fab2_lib.baseboard_fab2(sch_1):page192_i41@mstr_discrete.res~
(chips)',
 P_PATH='@baseboard_fab2_lib.baseboard_fab2(sch_1):page192_i41@mstr_discrete.res~
(chips)',
 PATH='I41',
 DRAWING='@BASEBOARD_FAB2_LIB.BASEBOARD_FAB2(SCH_1):PAGE192',
 WATTAGE='1/16W',
 TOLERANCE='1%',
 MATERIAL='CHIP',
 BOM_COST='CPLD',
 PHYS_PAGE='192',
 XY='(-6950,4400)',
 ROT='0',
 VER='2',
 VALUE='10.0K',
 PACK_TYPE='0402',
 PART_NUMBER='G21796-016',
 LOCATION='R2R3',
 ROOM='CPLD',
 CDS_LIB='mstr_discrete',
 CDS_PART_NAME='RES_0402-10.0K,1%,1/16W,CHIP,GA',
 PRIM_FILE='./archive_libs/mstr_discrete/res/chips/chips.prt';

PART_NAME
 R2R4 'RES_0402-0.0,5%,1/16W,CHIP,G21A':
 ROOM='CPLD';

SECTION_NUMBER 1
 '@BASEBOARD_FAB2_LIB.BASEBOARD_FAB2(SCH_1):PAGE191_I184@MSTR_DISCRETE.RES(CHIPS)':
 C_PATH='@baseboard_fab2_lib.baseboard_fab2(sch_1):page191_i184@mstr_discrete.re~
s(chips)',
 P_PATH='@baseboard_fab2_lib.baseboard_fab2(sch_1):page191_i184@mstr_discrete.re~
s(chips)',
 PATH='I184',
 DRAWING='@BASEBOARD_FAB2_LIB.BASEBOARD_FAB2(SCH_1):PAGE191',
 WATTAGE='1/16W',
 TOLERANCE='5%',
 MATERIAL='CHIP',
 BOM_COST='CPLD',
 PHYS_PAGE='191',
 XY='(-3175,4325)',
 ROT='0',
 VER='1',
 VALUE='0.0',
 PACK_TYPE='0402',
 PART_NUMBER='G21497-005',
 LOCATION='R2R4',
 ROOM='CPLD',
 CDS_LIB='mstr_discrete',
 CDS_PART_NAME='RES_0402-0.0,5%,1/16W,CHIP,G21A',
 PRIM_FILE='./archive_libs/mstr_discrete/res/chips/chips.prt';

PART_NAME
 R2R5 'RES_0402-1.00K,1%,1/16W,CHIP,GA':
 ROOM='SB';

SECTION_NUMBER 1
 '@BASEBOARD_FAB2_LIB.BASEBOARD_FAB2(SCH_1):PAGE133_I258@MSTR_DISCRETE.RES(CHIPS)':
 C_PATH='@baseboard_fab2_lib.baseboard_fab2(sch_1):page133_i258@mstr_discrete.re~
s(chips)',
 P_PATH='@baseboard_fab2_lib.baseboard_fab2(sch_1):page133_i258@mstr_discrete.re~
s(chips)',
 PATH='I258',
 DRAWING='@BASEBOARD_FAB2_LIB.BASEBOARD_FAB2(SCH_1):PAGE133',
 WATTAGE='1/16W',
 TOLERANCE='1%',
 SEC_TYPE='0402',
 MATERIAL='CHIP',
 BOM_COST='SB',
 PHYS_PAGE='133',
 XY='(-2600,5125)',
 ROT='0',
 VER='1',
 VALUE='1.00K',
 PACK_TYPE='0402',
 PART_NUMBER='G21796-026',
 LOCATION='R2R5',
 ROOM='SB',
 SEC='1',
 CDS_LIB='mstr_discrete',
 CDS_PART_NAME='RES_0402-1.00K,1%,1/16W,CHIP,GA',
 PRIM_FILE='./archive_libs/mstr_discrete/res/chips/chips.prt';

PART_NAME
 R2R6 'RES_0402-51,5.0%,1/16W,CHIP,G2A':
 ROOM='CPLD';

SECTION_NUMBER 1
 '@BASEBOARD_FAB2_LIB.BASEBOARD_FAB2(SCH_1):PAGE191_I166@MSTR_DISCRETE.RES(CHIPS)':
 C_PATH='@baseboard_fab2_lib.baseboard_fab2(sch_1):page191_i166@mstr_discrete.re~
s(chips)',
 P_PATH='@baseboard_fab2_lib.baseboard_fab2(sch_1):page191_i166@mstr_discrete.re~
s(chips)',
 PATH='I166',
 DRAWING='@BASEBOARD_FAB2_LIB.BASEBOARD_FAB2(SCH_1):PAGE191',
 WATTAGE='1/16W',
 TOLERANCE='5.0%',
 SEC_TYPE='0402',
 MATERIAL='CHIP',
 PHYS_PAGE='191',
 XY='(-1425,2675)',
 ROT='0',
 VER='1',
 VALUE='51',
 PACK_TYPE='0402',
 PART_NUMBER='G21497-048',
 LOCATION='R2R6',
 ROOM='CPLD',
 SEC='1',
 CDS_LIB='mstr_discrete',
 CDS_PART_NAME='RES_0402-51,5.0%,1/16W,CHIP,G2A',
 PRIM_FILE='./archive_libs/mstr_discrete/res/chips/chips.prt';

PART_NAME
 R2R7 'RES_0402-4.75K,1%,1/16W,CHIP,GA':
 ROOM='CPLD',
 SIGNAL_MODEL='DEFAULT_RESISTOR_47000OHM_2_1';

SECTION_NUMBER 1
 '@BASEBOARD_FAB2_LIB.BASEBOARD_FAB2(SCH_1):PAGE191_I172@MSTR_DISCRETE.RES(CHIPS)':
 C_PATH='@baseboard_fab2_lib.baseboard_fab2(sch_1):page191_i172@mstr_discrete.re~
s(chips)',
 P_PATH='@baseboard_fab2_lib.baseboard_fab2(sch_1):page191_i172@mstr_discrete.re~
s(chips)',
 PATH='I172',
 DRAWING='@BASEBOARD_FAB2_LIB.BASEBOARD_FAB2(SCH_1):PAGE191',
 WATTAGE='1/16W',
 TOLERANCE='1%',
 SEC_TYPE='0402',
 MATERIAL='CHIP',
 BOM_COST='CPLD',
 PHYS_PAGE='191',
 XY='(-1375,3550)',
 ROT='2',
 VER='2',
 VALUE='4.75K',
 PACK_TYPE='0402',
 PART_NUMBER='G21796-072',
 LOCATION='R2R7',
 SIGNAL_MODEL='DEFAULT_RESISTOR_47000OHM_2_1',
 ROOM='CPLD',
 SEC='1',
 CDS_LIB='mstr_discrete',
 CDS_PART_NAME='RES_0402-4.75K,1%,1/16W,CHIP,GA',
 PRIM_FILE='./archive_libs/mstr_discrete/res/chips/chips.prt';

PART_NAME
 R2R8 '887R2F-L-GP_SMD-RG-887R2F-L-GPA':;

SECTION_NUMBER 1
 '@BASEBOARD_FAB2_LIB.BASEBOARD_FAB2(SCH_1):PAGE187_I175@W_HDL.887R2F-L-GP(CHIPS)':
 C_PATH='@baseboard_fab2_lib.baseboard_fab2(sch_1):page187_i175@w_hdl.\887r2f-l-~
gp\(chips)',
 P_PATH='@baseboard_fab2_lib.baseboard_fab2(sch_1):page187_i175@w_hdl.\887r2f-l-~
gp\(chips)',
 PATH='I175',
 DRAWING='@BASEBOARD_FAB2_LIB.BASEBOARD_FAB2(SCH_1):PAGE187',
 PACK_SIZE='0402',
 RATED='1/16W',
 ATTRIBUTE='887OHM',
 TOLERANCE='1%',
 SEC_TYPE='SMD-RG',
 PHYS_PAGE='187',
 XY='(1950,4325)',
 ROT='0',
 VER='1',
 VALUE='887R2F-L-GP',
 PACK_TYPE='SMD-RG',
 PART_NUMBER='64.88705.6DL',
 LOCATION='R2R8',
 SEC='1',
 CDS_LIB='w_hdl',
 CDS_PART_NAME='887R2F-L-GP_SMD-RG-887R2F-L-GPA',
 PRIM_FILE='C:/<user>/w_hdl/887r2f#2dl#2dgp/chips/chips.prt';

PART_NAME
 R2R9 'RES_0402-200.0,1%,1/16W,CHIP,GA':
 ROOM='MIO_CHASSIS';

SECTION_NUMBER 1
 '@BASEBOARD_FAB2_LIB.BASEBOARD_FAB2(SCH_1):PAGE157_I352@MSTR_DISCRETE.RES(CHIPS)':
 C_PATH='@baseboard_fab2_lib.baseboard_fab2(sch_1):page157_i352@mstr_discrete.re~
s(chips)',
 P_PATH='@baseboard_fab2_lib.baseboard_fab2(sch_1):page157_i352@mstr_discrete.re~
s(chips)',
 PATH='I352',
 DRAWING='@BASEBOARD_FAB2_LIB.BASEBOARD_FAB2(SCH_1):PAGE157',
 WATTAGE='1/16W',
 TOLERANCE='1%',
 SEC_TYPE='0402',
 MATERIAL='CHIP',
 BOM_COST='MIO_CHASSIS',
 PHYS_PAGE='157',
 XY='(-3675,2675)',
 ROT='0',
 VER='1',
 VALUE='200.0',
 PACK_TYPE='0402',
 PART_NUMBER='G21796-004',
 LOCATION='R2R9',
 ROOM='MIO_CHASSIS',
 SEC='1',
 CDS_LIB='mstr_discrete',
 CDS_PART_NAME='RES_0402-200.0,1%,1/16W,CHIP,GA',
 PRIM_FILE='./archive_libs/mstr_discrete/res/chips/chips.prt';

PART_NAME
 R2R10 'RES_0402-33.2,1%,1/16W,CHIP,G2A':
 ROOM='MIO_CHASSIS';

SECTION_NUMBER 1
 '@BASEBOARD_FAB2_LIB.BASEBOARD_FAB2(SCH_1):PAGE157_I391@MSTR_DISCRETE.RES(CHIPS)':
 C_PATH='@baseboard_fab2_lib.baseboard_fab2(sch_1):page157_i391@mstr_discrete.re~
s(chips)',
 P_PATH='@baseboard_fab2_lib.baseboard_fab2(sch_1):page157_i391@mstr_discrete.re~
s(chips)',
 PATH='I391',
 DRAWING='@BASEBOARD_FAB2_LIB.BASEBOARD_FAB2(SCH_1):PAGE157',
 WATTAGE='1/16W',
 TOLERANCE='1%',
 SEC_TYPE='0402',
 MATERIAL='CHIP',
 BOM_COST='MIO_CHASSIS',
 PHYS_PAGE='157',
 XY='(-1250,2925)',
 ROT='0',
 VER='1',
 VALUE='33.2',
 PACK_TYPE='0402',
 PART_NUMBER='G21796-074',
 LOCATION='R2R10',
 ROOM='MIO_CHASSIS',
 SEC='1',
 CDS_LIB='mstr_discrete',
 CDS_PART_NAME='RES_0402-33.2,1%,1/16W,CHIP,G2A',
 PRIM_FILE='./archive_libs/mstr_discrete/res/chips/chips.prt';

PART_NAME
 R2R11 'RES_0402-1.00K,1%,1/16W,EMPTY,A':
 ROOM='SB';

SECTION_NUMBER 1
 '@BASEBOARD_FAB2_LIB.BASEBOARD_FAB2(SCH_1):PAGE125_I11@MSTR_DISCRETE.RES(CHIPS)':
 C_PATH='@baseboard_fab2_lib.baseboard_fab2(sch_1):page125_i11@mstr_discrete.res~
(chips)',
 P_PATH='@baseboard_fab2_lib.baseboard_fab2(sch_1):page125_i11@mstr_discrete.res~
(chips)',
 PATH='I11',
 DRAWING='@BASEBOARD_FAB2_LIB.BASEBOARD_FAB2(SCH_1):PAGE125',
 WATTAGE='1/16W',
 TOLERANCE='1%',
 MATERIAL='EMPTY',
 BOM_COST='SB',
 PHYS_PAGE='125',
 XY='(1750,3050)',
 ROT='0',
 VER='2',
 VALUE='1.00K',
 PACK_TYPE='0402',
 PART_NUMBER='G21796-026',
 LOCATION='R2R11',
 ROOM='SB',
 CDS_LIB='mstr_discrete',
 CDS_PART_NAME='RES_0402-1.00K,1%,1/16W,EMPTY,A',
 PRIM_FILE='./archive_libs/mstr_discrete/res/chips/chips.prt';

PART_NAME
 R2R12 'RES_0402-0.0,5%,1/16W,CHIP,G21A':
 ROOM='SB_BMC_SPI_MUX';

SECTION_NUMBER 1
 '@BASEBOARD_FAB2_LIB.BASEBOARD_FAB2(SCH_1):PAGE154_I93@MSTR_DISCRETE.RES(CHIPS)':
 C_PATH='@baseboard_fab2_lib.baseboard_fab2(sch_1):page154_i93@mstr_discrete.res~
(chips)',
 P_PATH='@baseboard_fab2_lib.baseboard_fab2(sch_1):page154_i93@mstr_discrete.res~
(chips)',
 PATH='I93',
 DRAWING='@BASEBOARD_FAB2_LIB.BASEBOARD_FAB2(SCH_1):PAGE154',
 WATTAGE='1/16W',
 TOLERANCE='5%',
 SEC_TYPE='0402',
 MATERIAL='CHIP',
 BOM_COST='MIO_BIOS_MEM',
 PHYS_PAGE='154',
 XY='(-3200,4075)',
 ROT='0',
 VER='1',
 VALUE='0.0',
 PACK_TYPE='0402',
 PART_NUMBER='G21497-005',
 LOCATION='R2R12',
 ROOM='SB_BMC_SPI_MUX',
 SEC='1',
 CDS_LIB='mstr_discrete',
 CDS_PART_NAME='RES_0402-0.0,5%,1/16W,CHIP,G21A',
 PRIM_FILE='./archive_libs/mstr_discrete/res/chips/chips.prt';

PART_NAME
 R2T1 'RES_0402-1.00K,1%,1/16W,EMPTY,A':
 ROOM='SB';

SECTION_NUMBER 1
 '@BASEBOARD_FAB2_LIB.BASEBOARD_FAB2(SCH_1):PAGE125_I89@MSTR_DISCRETE.RES(CHIPS)':
 C_PATH='@baseboard_fab2_lib.baseboard_fab2(sch_1):page125_i89@mstr_discrete.res~
(chips)',
 P_PATH='@baseboard_fab2_lib.baseboard_fab2(sch_1):page125_i89@mstr_discrete.res~
(chips)',
 PATH='I89',
 DRAWING='@BASEBOARD_FAB2_LIB.BASEBOARD_FAB2(SCH_1):PAGE125',
 WATTAGE='1/16W',
 TOLERANCE='1%',
 SEC_TYPE='0402',
 MATERIAL='EMPTY',
 BOM_COST='SB',
 PHYS_PAGE='125',
 XY='(1850,1475)',
 ROT='0',
 VER='2',
 VALUE='1.00K',
 PACK_TYPE='0402',
 PART_NUMBER='G21796-026',
 LOCATION='R2T1',
 ROOM='SB',
 SEC='1',
 CDS_LIB='mstr_discrete',
 CDS_PART_NAME='RES_0402-1.00K,1%,1/16W,EMPTY,A',
 PRIM_FILE='./archive_libs/mstr_discrete/res/chips/chips.prt';

PART_NAME
 R2T2 'RES_0402-0.0,5%,1/16W,CHIP,G21A':
 ROOM='SB_BMC_SPI_MUX';

SECTION_NUMBER 1
 '@BASEBOARD_FAB2_LIB.BASEBOARD_FAB2(SCH_1):PAGE154_I92@MSTR_DISCRETE.RES(CHIPS)':
 C_PATH='@baseboard_fab2_lib.baseboard_fab2(sch_1):page154_i92@mstr_discrete.res~
(chips)',
 P_PATH='@baseboard_fab2_lib.baseboard_fab2(sch_1):page154_i92@mstr_discrete.res~
(chips)',
 PATH='I92',
 DRAWING='@BASEBOARD_FAB2_LIB.BASEBOARD_FAB2(SCH_1):PAGE154',
 WATTAGE='1/16W',
 TOLERANCE='5%',
 SEC_TYPE='0402',
 MATERIAL='CHIP',
 BOM_COST='MIO_BIOS_MEM',
 PHYS_PAGE='154',
 XY='(-3200,3975)',
 ROT='0',
 VER='1',
 VALUE='0.0',
 PACK_TYPE='0402',
 PART_NUMBER='G21497-005',
 LOCATION='R2T2',
 ROOM='SB_BMC_SPI_MUX',
 SEC='1',
 CDS_LIB='mstr_discrete',
 CDS_PART_NAME='RES_0402-0.0,5%,1/16W,CHIP,G21A',
 PRIM_FILE='./archive_libs/mstr_discrete/res/chips/chips.prt';

PART_NAME
 R2T3 'RES_0402-4.75K,1%,1/16W,CHIP,GA':
 ROOM='FAST_PROCHOT';

SECTION_NUMBER 1
 '@BASEBOARD_FAB2_LIB.BASEBOARD_FAB2(SCH_1):PAGE170_I54@MSTR_DISCRETE.RES(CHIPS)':
 C_PATH='@baseboard_fab2_lib.baseboard_fab2(sch_1):page170_i54@mstr_discrete.res~
(chips)',
 P_PATH='@baseboard_fab2_lib.baseboard_fab2(sch_1):page170_i54@mstr_discrete.res~
(chips)',
 PATH='I54',
 DRAWING='@BASEBOARD_FAB2_LIB.BASEBOARD_FAB2(SCH_1):PAGE170',
 WATTAGE='1/16W',
 TOLERANCE='1%',
 SEC_TYPE='0402',
 MATERIAL='CHIP',
 BOM_COST='FAST_PROCHOT',
 PHYS_PAGE='170',
 XY='(-3450,2075)',
 ROT='0',
 VER='2',
 VALUE='4.75K',
 PACK_TYPE='0402',
 PART_NUMBER='G21796-072',
 LOCATION='R2T3',
 ROOM='FAST_PROCHOT',
 SEC='1',
 CDS_LIB='mstr_discrete',
 CDS_PART_NAME='RES_0402-4.75K,1%,1/16W,CHIP,GA',
 PRIM_FILE='./archive_libs/mstr_discrete/res/chips/chips.prt';

PART_NAME
 R2T4 'RES_0402-1.0K,0.1%,1/16W,CHIP,A':
 ROOM='P3V3_STBY_VR',
 REUSE_ID='34';

SECTION_NUMBER 1
 '@BASEBOARD_FAB2_LIB.BASEBOARD_FAB2(SCH_1):PAGE240_I152@MSTR_DISCRETE.RES(CHIPS)':
 C_PATH='@baseboard_fab2_lib.baseboard_fab2(sch_1):page240_i152@mstr_discrete.re~
s(chips)',
 P_PATH='@baseboard_fab2_lib.baseboard_fab2(sch_1):page240_i152@mstr_discrete.re~
s(chips)',
 PATH='I152',
 DRAWING='@BASEBOARD_FAB2_LIB.BASEBOARD_FAB2(SCH_1):PAGE240',
 WATTAGE='1/16W',
 TOLERANCE='0.1%',
 MATERIAL='CHIP',
 BOM_COST='P3V3_STBY_VR',
 PHYS_PAGE='240',
 REUSE_ID='34',
 XY='(10750,3800)',
 ROT='0',
 VER='2',
 VALUE='1.0K',
 PACK_TYPE='0402',
 PART_NUMBER='G85996-004',
 LOCATION='R2T4',
 ROOM='P3V3_STBY_VR',
 CDS_LIB='mstr_discrete',
 CDS_PART_NAME='RES_0402-1.0K,0.1%,1/16W,CHIP,A',
 PRIM_FILE='./archive_libs/mstr_discrete/res/chips/chips.prt';

PART_NAME
 R2T5 'RES_0402-1.00K,1%,1/16W,CHIP,GA':
 ROOM='PROC_SIDEBAND';

SECTION_NUMBER 1
 '@BASEBOARD_FAB2_LIB.BASEBOARD_FAB2(SCH_1):PAGE157_I326@MSTR_DISCRETE.RES(CHIPS)':
 C_PATH='@baseboard_fab2_lib.baseboard_fab2(sch_1):page157_i326@mstr_discrete.re~
s(chips)',
 P_PATH='@baseboard_fab2_lib.baseboard_fab2(sch_1):page157_i326@mstr_discrete.re~
s(chips)',
 PATH='I326',
 DRAWING='@BASEBOARD_FAB2_LIB.BASEBOARD_FAB2(SCH_1):PAGE157',
 WATTAGE='1/16W',
 TOLERANCE='1%',
 SEC_TYPE='0402',
 MATERIAL='CHIP',
 BOM_COST='PROC_SIDEBAND',
 PHYS_PAGE='157',
 XY='(-6150,1250)',
 ROT='0',
 VER='2',
 VALUE='1.00K',
 PACK_TYPE='0402',
 PART_NUMBER='G21796-026',
 LOCATION='R2T5',
 ROOM='PROC_SIDEBAND',
 SEC='1',
 CDS_LIB='mstr_discrete',
 CDS_PART_NAME='RES_0402-1.00K,1%,1/16W,CHIP,GA',
 PRIM_FILE='./archive_libs/mstr_discrete/res/chips/chips.prt';

PART_NAME
 R2T6 'RES_0402-4.75K,1%,1/16W,CHIP,GA':
 ROOM='SB_BMC_SPI_MUX';

SECTION_NUMBER 1
 '@BASEBOARD_FAB2_LIB.BASEBOARD_FAB2(SCH_1):PAGE154_I127@MSTR_DISCRETE.RES(CHIPS)':
 C_PATH='@baseboard_fab2_lib.baseboard_fab2(sch_1):page154_i127@mstr_discrete.re~
s(chips)',
 P_PATH='@baseboard_fab2_lib.baseboard_fab2(sch_1):page154_i127@mstr_discrete.re~
s(chips)',
 PATH='I127',
 DRAWING='@BASEBOARD_FAB2_LIB.BASEBOARD_FAB2(SCH_1):PAGE154',
 WATTAGE='1/16W',
 TOLERANCE='1%',
 SEC_TYPE='0402',
 MATERIAL='CHIP',
 BOM_COST='MIO_BIOS_MEM',
 PHYS_PAGE='154',
 XY='(-3400,1750)',
 ROT='2',
 VER='2',
 VALUE='4.75K',
 PACK_TYPE='0402',
 PART_NUMBER='G21796-072',
 LOCATION='R2T6',
 ROOM='SB_BMC_SPI_MUX',
 SEC='1',
 CDS_LIB='mstr_discrete',
 CDS_PART_NAME='RES_0402-4.75K,1%,1/16W,CHIP,GA',
 PRIM_FILE='./archive_libs/mstr_discrete/res/chips/chips.prt';

PART_NAME
 R2T7 'RES_0402-1.00K,1%,1/16W,CHIP,GA':
 ROOM='PROC_SIDEBAND';

SECTION_NUMBER 1
 '@BASEBOARD_FAB2_LIB.BASEBOARD_FAB2(SCH_1):PAGE157_I327@MSTR_DISCRETE.RES(CHIPS)':
 C_PATH='@baseboard_fab2_lib.baseboard_fab2(sch_1):page157_i327@mstr_discrete.re~
s(chips)',
 P_PATH='@baseboard_fab2_lib.baseboard_fab2(sch_1):page157_i327@mstr_discrete.re~
s(chips)',
 PATH='I327',
 DRAWING='@BASEBOARD_FAB2_LIB.BASEBOARD_FAB2(SCH_1):PAGE157',
 WATTAGE='1/16W',
 TOLERANCE='1%',
 SEC_TYPE='0402',
 MATERIAL='CHIP',
 BOM_COST='PROC_SIDEBAND',
 PHYS_PAGE='157',
 XY='(-5500,1650)',
 ROT='0',
 VER='2',
 VALUE='1.00K',
 PACK_TYPE='0402',
 PART_NUMBER='G21796-026',
 LOCATION='R2T7',
 ROOM='PROC_SIDEBAND',
 SEC='1',
 CDS_LIB='mstr_discrete',
 CDS_PART_NAME='RES_0402-1.00K,1%,1/16W,CHIP,GA',
 PRIM_FILE='./archive_libs/mstr_discrete/res/chips/chips.prt';

PART_NAME
 R2T8 'RES_0402-10.0K,1%,1/16W,CHIP,GA':
 GROUP='NI_BIOS_ROM2',
 ROOM='SB_BMC_SPI_MUX';

SECTION_NUMBER 1
 '@BASEBOARD_FAB2_LIB.BASEBOARD_FAB2(SCH_1):PAGE154_I106@MSTR_DISCRETE.RES(CHIPS)':
 C_PATH='@baseboard_fab2_lib.baseboard_fab2(sch_1):page154_i106@mstr_discrete.re~
s(chips)',
 P_PATH='@baseboard_fab2_lib.baseboard_fab2(sch_1):page154_i106@mstr_discrete.re~
s(chips)',
 PATH='I106',
 DRAWING='@BASEBOARD_FAB2_LIB.BASEBOARD_FAB2(SCH_1):PAGE154',
 WATTAGE='1/16W',
 TOLERANCE='1%',
 SEC_TYPE='0402',
 MATERIAL='CHIP',
 BOM_COST='MIO_BIOS_MEM',
 PHYS_PAGE='154',
 XY='(-3775,1750)',
 ROT='2',
 VER='2',
 VALUE='10.0K',
 PACK_TYPE='0402',
 PART_NUMBER='G21796-016',
 LOCATION='R2T8',
 ROOM='SB_BMC_SPI_MUX',
 GROUP='NI_BIOS_ROM2',
 SEC='1',
 CDS_LIB='mstr_discrete',
 CDS_PART_NAME='RES_0402-10.0K,1%,1/16W,CHIP,GA',
 PRIM_FILE='./archive_libs/mstr_discrete/res/chips/chips.prt';

PART_NAME
 R2T9 'RES_0402-75,1.0%,1/16W,CHIP,G2A':
 GROUP='NI_BIOS_ROM2',
 ROOM='SB_BMC_SPI_MUX';

SECTION_NUMBER 1
 '@BASEBOARD_FAB2_LIB.BASEBOARD_FAB2(SCH_1):PAGE154_I62@MSTR_DISCRETE.RES(CHIPS)':
 C_PATH='@baseboard_fab2_lib.baseboard_fab2(sch_1):page154_i62@mstr_discrete.res~
(chips)',
 P_PATH='@baseboard_fab2_lib.baseboard_fab2(sch_1):page154_i62@mstr_discrete.res~
(chips)',
 PATH='I62',
 DRAWING='@BASEBOARD_FAB2_LIB.BASEBOARD_FAB2(SCH_1):PAGE154',
 WATTAGE='1/16W',
 TOLERANCE='1.0%',
 SEC_TYPE='0402',
 MATERIAL='CHIP',
 BOM_COST='MIO_BIOS_MEM',
 PHYS_PAGE='154',
 XY='(-1450,1150)',
 ROT='0',
 VER='1',
 VALUE='75',
 PACK_TYPE='0402',
 PART_NUMBER='G21796-267',
 LOCATION='R2T9',
 ROOM='SB_BMC_SPI_MUX',
 GROUP='NI_BIOS_ROM2',
 SEC='1',
 CDS_LIB='mstr_discrete',
 CDS_PART_NAME='RES_0402-75,1.0%,1/16W,CHIP,G2A',
 PRIM_FILE='./archive_libs/mstr_discrete/res/chips/chips.prt';

PART_NAME
 R2T11 'RES_0402-4.75K,1%,1/16W,CHIP,GA':
 GROUP='NI_BIOS_ROM2',
 ROOM='SB_BMC_SPI_MUX';

SECTION_NUMBER 1
 '@BASEBOARD_FAB2_LIB.BASEBOARD_FAB2(SCH_1):PAGE154_I105@MSTR_DISCRETE.RES(CHIPS)':
 C_PATH='@baseboard_fab2_lib.baseboard_fab2(sch_1):page154_i105@mstr_discrete.re~
s(chips)',
 P_PATH='@baseboard_fab2_lib.baseboard_fab2(sch_1):page154_i105@mstr_discrete.re~
s(chips)',
 PATH='I105',
 DRAWING='@BASEBOARD_FAB2_LIB.BASEBOARD_FAB2(SCH_1):PAGE154',
 WATTAGE='1/16W',
 TOLERANCE='1%',
 SEC_TYPE='0402',
 MATERIAL='CHIP',
 BOM_COST='MIO_BIOS_MEM',
 PHYS_PAGE='154',
 XY='(-3100,2200)',
 ROT='0',
 VER='2',
 VALUE='4.75K',
 PACK_TYPE='0402',
 PART_NUMBER='G21796-072',
 LOCATION='R2T11',
 ROOM='SB_BMC_SPI_MUX',
 GROUP='NI_BIOS_ROM2',
 SEC='1',
 CDS_LIB='mstr_discrete',
 CDS_PART_NAME='RES_0402-4.75K,1%,1/16W,CHIP,GA',
 PRIM_FILE='./archive_libs/mstr_discrete/res/chips/chips.prt';

PART_NAME
 R2T13 'RES_0402-200.0,1%,1/16W,CHIP,GA':
 GROUP='NI_BIOS_ROM2',
 ROOM='SB_BMC_SPI_MUX';

SECTION_NUMBER 1
 '@BASEBOARD_FAB2_LIB.BASEBOARD_FAB2(SCH_1):PAGE154_I101@MSTR_DISCRETE.RES(CHIPS)':
 C_PATH='@baseboard_fab2_lib.baseboard_fab2(sch_1):page154_i101@mstr_discrete.re~
s(chips)',
 P_PATH='@baseboard_fab2_lib.baseboard_fab2(sch_1):page154_i101@mstr_discrete.re~
s(chips)',
 PATH='I101',
 DRAWING='@BASEBOARD_FAB2_LIB.BASEBOARD_FAB2(SCH_1):PAGE154',
 WATTAGE='1/16W',
 TOLERANCE='1%',
 SEC_TYPE='0402',
 MATERIAL='CHIP',
 BOM_COST='MIO_BIOS_MEM',
 PHYS_PAGE='154',
 XY='(-1450,1875)',
 ROT='0',
 VER='1',
 VALUE='200.0',
 PACK_TYPE='0402',
 PART_NUMBER='G21796-004',
 LOCATION='R2T13',
 ROOM='SB_BMC_SPI_MUX',
 GROUP='NI_BIOS_ROM2',
 SEC='1',
 CDS_LIB='mstr_discrete',
 CDS_PART_NAME='RES_0402-200.0,1%,1/16W,CHIP,GA',
 PRIM_FILE='./archive_libs/mstr_discrete/res/chips/chips.prt';

PART_NAME
 R2T16 'RES_0402-75,1.0%,1/16W,CHIP,G2A':
 ROOM='PROC_SIDEBAND';

SECTION_NUMBER 1
 '@BASEBOARD_FAB2_LIB.BASEBOARD_FAB2(SCH_1):PAGE93_I67@MSTR_DISCRETE.RES(CHIPS)':
 C_PATH='@baseboard_fab2_lib.baseboard_fab2(sch_1):page93_i67@mstr_discrete.res(~
chips)',
 P_PATH='@baseboard_fab2_lib.baseboard_fab2(sch_1):page93_i67@mstr_discrete.res(~
chips)',
 PATH='I67',
 DRAWING='@BASEBOARD_FAB2_LIB.BASEBOARD_FAB2(SCH_1):PAGE93',
 WATTAGE='1/16W',
 TOLERANCE='1.0%',
 SEC_TYPE='0402',
 MATERIAL='CHIP',
 PHYS_PAGE='93',
 XY='(-925,3825)',
 ROT='0',
 VER='1',
 VALUE='75',
 PACK_TYPE='0402',
 PART_NUMBER='G21796-267',
 LOCATION='R2T16',
 ROOM='PROC_SIDEBAND',
 SEC='1',
 CDS_LIB='mstr_discrete',
 CDS_PART_NAME='RES_0402-75,1.0%,1/16W,CHIP,G2A',
 PRIM_FILE='./archive_libs/mstr_discrete/res/chips/chips.prt';

PART_NAME
 R2T17 'RES_0402-0.0,5%,1/16W,CHIP,G21A':
 ROOM='PROC_SIDEBAND';

SECTION_NUMBER 1
 '@BASEBOARD_FAB2_LIB.BASEBOARD_FAB2(SCH_1):PAGE93_I23@MSTR_DISCRETE.RES(CHIPS)':
 C_PATH='@baseboard_fab2_lib.baseboard_fab2(sch_1):page93_i23@mstr_discrete.res(~
chips)',
 P_PATH='@baseboard_fab2_lib.baseboard_fab2(sch_1):page93_i23@mstr_discrete.res(~
chips)',
 PATH='I23',
 DRAWING='@BASEBOARD_FAB2_LIB.BASEBOARD_FAB2(SCH_1):PAGE93',
 WATTAGE='1/16W',
 TOLERANCE='5%',
 SEC_TYPE='0402',
 MATERIAL='CHIP',
 BOM_COST='PROC',
 PHYS_PAGE='93',
 XY='(-2750,3975)',
 ROT='0',
 VER='1',
 VALUE='0.0',
 PACK_TYPE='0402',
 PART_NUMBER='G21497-005',
 LOCATION='R2T17',
 ROOM='PROC_SIDEBAND',
 SEC='1',
 CDS_LIB='mstr_discrete',
 CDS_PART_NAME='RES_0402-0.0,5%,1/16W,CHIP,G21A',
 PRIM_FILE='./archive_libs/mstr_discrete/res/chips/chips.prt';

PART_NAME
 R2T18 'RES_0402-49.9,1%,1/16W,CHIP,G2A':
 ROOM='BMC_MISC';

SECTION_NUMBER 1
 '@BASEBOARD_FAB2_LIB.BASEBOARD_FAB2(SCH_1):PAGE156_I288@MSTR_DISCRETE.RES(CHIPS)':
 C_PATH='@baseboard_fab2_lib.baseboard_fab2(sch_1):page156_i288@mstr_discrete.re~
s(chips)',
 P_PATH='@baseboard_fab2_lib.baseboard_fab2(sch_1):page156_i288@mstr_discrete.re~
s(chips)',
 PATH='I288',
 DRAWING='@BASEBOARD_FAB2_LIB.BASEBOARD_FAB2(SCH_1):PAGE156',
 WATTAGE='1/16W',
 TOLERANCE='1%',
 SEC_TYPE='0402',
 MATERIAL='CHIP',
 BOM_COST='SM_CONTROLLER',
 PHYS_PAGE='156',
 XY='(-1700,4200)',
 ROT='0',
 VER='1',
 VALUE='49.9',
 PACK_TYPE='0402',
 PART_NUMBER='G21796-047',
 LOCATION='R2T18',
 ROOM='BMC_MISC',
 SEC='1',
 CDS_LIB='mstr_discrete',
 CDS_PART_NAME='RES_0402-49.9,1%,1/16W,CHIP,G2A',
 PRIM_FILE='./archive_libs/mstr_discrete/res/chips/chips.prt';

PART_NAME
 R2T19 'RES_0402-200.0,1%,1/16W,CHIP,GA':
 ROOM='PROC_SIDEBAND';

SECTION_NUMBER 1
 '@BASEBOARD_FAB2_LIB.BASEBOARD_FAB2(SCH_1):PAGE93_I63@MSTR_DISCRETE.RES(CHIPS)':
 C_PATH='@baseboard_fab2_lib.baseboard_fab2(sch_1):page93_i63@mstr_discrete.res(~
chips)',
 P_PATH='@baseboard_fab2_lib.baseboard_fab2(sch_1):page93_i63@mstr_discrete.res(~
chips)',
 PATH='I63',
 DRAWING='@BASEBOARD_FAB2_LIB.BASEBOARD_FAB2(SCH_1):PAGE93',
 WATTAGE='1/16W',
 TOLERANCE='1%',
 SEC_TYPE='0402',
 MATERIAL='CHIP',
 BOM_COST='PROC',
 PHYS_PAGE='93',
 XY='(-2325,4050)',
 ROT='0',
 VER='2',
 VALUE='200.0',
 PACK_TYPE='0402',
 PART_NUMBER='G21796-004',
 LOCATION='R2T19',
 ROOM='PROC_SIDEBAND',
 SEC='1',
 CDS_LIB='mstr_discrete',
 CDS_PART_NAME='RES_0402-200.0,1%,1/16W,CHIP,GA',
 PRIM_FILE='./archive_libs/mstr_discrete/res/chips/chips.prt';

PART_NAME
 R2T20 'RES_0402-0.0,5%,1/16W,CHIP,G21A':
 ROOM='PROC_SIDEBAND';

SECTION_NUMBER 1
 '@BASEBOARD_FAB2_LIB.BASEBOARD_FAB2(SCH_1):PAGE93_I16@MSTR_DISCRETE.RES(CHIPS)':
 C_PATH='@baseboard_fab2_lib.baseboard_fab2(sch_1):page93_i16@mstr_discrete.res(~
chips)',
 P_PATH='@baseboard_fab2_lib.baseboard_fab2(sch_1):page93_i16@mstr_discrete.res(~
chips)',
 PATH='I16',
 DRAWING='@BASEBOARD_FAB2_LIB.BASEBOARD_FAB2(SCH_1):PAGE93',
 WATTAGE='1/16W',
 TOLERANCE='5%',
 SEC_TYPE='0402',
 MATERIAL='CHIP',
 BOM_COST='PROC',
 PHYS_PAGE='93',
 XY='(-2750,3725)',
 ROT='0',
 VER='1',
 VALUE='0.0',
 PACK_TYPE='0402',
 PART_NUMBER='G21497-005',
 LOCATION='R2T20',
 ROOM='PROC_SIDEBAND',
 SEC='1',
 CDS_LIB='mstr_discrete',
 CDS_PART_NAME='RES_0402-0.0,5%,1/16W,CHIP,G21A',
 PRIM_FILE='./archive_libs/mstr_discrete/res/chips/chips.prt';

PART_NAME
 R2T21 'RES_0603-2.2,1.0%,1/10W,CHIP,GA':
 ROOM='SYS_CLOCK';

SECTION_NUMBER 1
 '@BASEBOARD_FAB2_LIB.BASEBOARD_FAB2(SCH_1):PAGE101_I105@MSTR_DISCRETE.RES(CHIPS)':
 C_PATH='@baseboard_fab2_lib.baseboard_fab2(sch_1):page101_i105@mstr_discrete.re~
s(chips)',
 P_PATH='@baseboard_fab2_lib.baseboard_fab2(sch_1):page101_i105@mstr_discrete.re~
s(chips)',
 PATH='I105',
 DRAWING='@BASEBOARD_FAB2_LIB.BASEBOARD_FAB2(SCH_1):PAGE101',
 WATTAGE='1/10W',
 TOLERANCE='1.0%',
 SEC_TYPE='0603',
 MATERIAL='CHIP',
 BOM_COST='SM_CONTROLLER',
 PHYS_PAGE='101',
 XY='(-5825,4150)',
 ROT='0',
 VER='1',
 VALUE='2.2',
 PACK_TYPE='0603',
 PART_NUMBER='G22026-127',
 LOCATION='R2T21',
 ROOM='SYS_CLOCK',
 SEC='1',
 CDS_LIB='mstr_discrete',
 CDS_PART_NAME='RES_0603-2.2,1.0%,1/10W,CHIP,GA',
 PRIM_FILE='./archive_libs/mstr_discrete/res/chips/chips.prt';

PART_NAME
 R2T22 'RES_0402-10.0K,1%,1/16W,CHIP,GA':
 ROOM='BMC_MISC';

SECTION_NUMBER 1
 '@BASEBOARD_FAB2_LIB.BASEBOARD_FAB2(SCH_1):PAGE156_I210@MSTR_DISCRETE.RES(CHIPS)':
 C_PATH='@baseboard_fab2_lib.baseboard_fab2(sch_1):page156_i210@mstr_discrete.re~
s(chips)',
 P_PATH='@baseboard_fab2_lib.baseboard_fab2(sch_1):page156_i210@mstr_discrete.re~
s(chips)',
 PATH='I210',
 DRAWING='@BASEBOARD_FAB2_LIB.BASEBOARD_FAB2(SCH_1):PAGE156',
 WATTAGE='1/16W',
 TOLERANCE='1%',
 SEC_TYPE='0402',
 MATERIAL='CHIP',
 BOM_COST='SM_CONTROLLER',
 PHYS_PAGE='156',
 XY='(-2275,4425)',
 ROT='0',
 VER='2',
 VALUE='10.0K',
 PACK_TYPE='0402',
 PART_NUMBER='G21796-016',
 LOCATION='R2T22',
 ROOM='BMC_MISC',
 SEC='1',
 CDS_LIB='mstr_discrete',
 CDS_PART_NAME='RES_0402-10.0K,1%,1/16W,CHIP,GA',
 PRIM_FILE='./archive_libs/mstr_discrete/res/chips/chips.prt';

PART_NAME
 R2T23 'RES_0603-2.2,1.0%,1/10W,CHIP,GA':
 ROOM='SYS_CLOCK';

SECTION_NUMBER 1
 '@BASEBOARD_FAB2_LIB.BASEBOARD_FAB2(SCH_1):PAGE101_I94@MSTR_DISCRETE.RES(CHIPS)':
 C_PATH='@baseboard_fab2_lib.baseboard_fab2(sch_1):page101_i94@mstr_discrete.res~
(chips)',
 P_PATH='@baseboard_fab2_lib.baseboard_fab2(sch_1):page101_i94@mstr_discrete.res~
(chips)',
 PATH='I94',
 DRAWING='@BASEBOARD_FAB2_LIB.BASEBOARD_FAB2(SCH_1):PAGE101',
 WATTAGE='1/10W',
 TOLERANCE='1.0%',
 MATERIAL='CHIP',
 BOM_COST='SM_CONTROLLER',
 PHYS_PAGE='101',
 XY='(-4325,4150)',
 ROT='0',
 VER='1',
 VALUE='2.2',
 PACK_TYPE='0603',
 PART_NUMBER='G22026-127',
 LOCATION='R2T23',
 ROOM='SYS_CLOCK',
 CDS_LIB='mstr_discrete',
 CDS_PART_NAME='RES_0603-2.2,1.0%,1/10W,CHIP,GA',
 PRIM_FILE='./archive_libs/mstr_discrete/res/chips/chips.prt';

PART_NAME
 R2T25 'RES_0402-1.00K,1%,1/16W,CHIP,GA':
 ROOM='SYS_CLOCK';

SECTION_NUMBER 1
 '@BASEBOARD_FAB2_LIB.BASEBOARD_FAB2(SCH_1):PAGE101_I48@MSTR_DISCRETE.RES(CHIPS)':
 C_PATH='@baseboard_fab2_lib.baseboard_fab2(sch_1):page101_i48@mstr_discrete.res~
(chips)',
 P_PATH='@baseboard_fab2_lib.baseboard_fab2(sch_1):page101_i48@mstr_discrete.res~
(chips)',
 PATH='I48',
 DRAWING='@BASEBOARD_FAB2_LIB.BASEBOARD_FAB2(SCH_1):PAGE101',
 WATTAGE='1/16W',
 TOLERANCE='1%',
 SEC_TYPE='0402',
 MATERIAL='CHIP',
 BOM_COST='SM_CONTROLLER',
 PHYS_PAGE='101',
 XY='(-7925,1225)',
 ROT='0',
 VER='2',
 VALUE='1.00K',
 PACK_TYPE='0402',
 PART_NUMBER='G21796-026',
 LOCATION='R2T25',
 ROOM='SYS_CLOCK',
 SEC='1',
 CDS_LIB='mstr_discrete',
 CDS_PART_NAME='RES_0402-1.00K,1%,1/16W,CHIP,GA',
 PRIM_FILE='./archive_libs/mstr_discrete/res/chips/chips.prt';

PART_NAME
 R2T26 'RES_0402-200.0,1%,1/16W,CHIP,GA':
 ROOM='PROC_SIDEBAND';

SECTION_NUMBER 1
 '@BASEBOARD_FAB2_LIB.BASEBOARD_FAB2(SCH_1):PAGE93_I87@MSTR_DISCRETE.RES(CHIPS)':
 C_PATH='@baseboard_fab2_lib.baseboard_fab2(sch_1):page93_i87@mstr_discrete.res(~
chips)',
 P_PATH='@baseboard_fab2_lib.baseboard_fab2(sch_1):page93_i87@mstr_discrete.res(~
chips)',
 PATH='I87',
 DRAWING='@BASEBOARD_FAB2_LIB.BASEBOARD_FAB2(SCH_1):PAGE93',
 WATTAGE='1/16W',
 TOLERANCE='1%',
 SEC_TYPE='0402',
 MATERIAL='CHIP',
 BOM_COST='PROC',
 PHYS_PAGE='93',
 XY='(-2025,4050)',
 ROT='0',
 VER='2',
 VALUE='200.0',
 PACK_TYPE='0402',
 PART_NUMBER='G21796-004',
 LOCATION='R2T26',
 ROOM='PROC_SIDEBAND',
 SEC='1',
 CDS_LIB='mstr_discrete',
 CDS_PART_NAME='RES_0402-200.0,1%,1/16W,CHIP,GA',
 PRIM_FILE='./archive_libs/mstr_discrete/res/chips/chips.prt';

PART_NAME
 R2T27 'RES_0402-0.0,5%,1/16W,CHIP,G21A':
 ROOM='PROC_SIDEBAND';

SECTION_NUMBER 1
 '@BASEBOARD_FAB2_LIB.BASEBOARD_FAB2(SCH_1):PAGE93_I13@MSTR_DISCRETE.RES(CHIPS)':
 C_PATH='@baseboard_fab2_lib.baseboard_fab2(sch_1):page93_i13@mstr_discrete.res(~
chips)',
 P_PATH='@baseboard_fab2_lib.baseboard_fab2(sch_1):page93_i13@mstr_discrete.res(~
chips)',
 PATH='I13',
 DRAWING='@BASEBOARD_FAB2_LIB.BASEBOARD_FAB2(SCH_1):PAGE93',
 WATTAGE='1/16W',
 TOLERANCE='5%',
 SEC_TYPE='0402',
 MATERIAL='CHIP',
 BOM_COST='PROC',
 PHYS_PAGE='93',
 XY='(-2750,3200)',
 ROT='0',
 VER='1',
 VALUE='0.0',
 PACK_TYPE='0402',
 PART_NUMBER='G21497-005',
 LOCATION='R2T27',
 ROOM='PROC_SIDEBAND',
 SEC='1',
 CDS_LIB='mstr_discrete',
 CDS_PART_NAME='RES_0402-0.0,5%,1/16W,CHIP,G21A',
 PRIM_FILE='./archive_libs/mstr_discrete/res/chips/chips.prt';

PART_NAME
 R2T28 'RES_0402-33.2,1%,1/16W,CHIP,G2A':
 ROOM='BMC_MISC';

SECTION_NUMBER 1
 '@BASEBOARD_FAB2_LIB.BASEBOARD_FAB2(SCH_1):PAGE156_I289@MSTR_DISCRETE.RES(CHIPS)':
 C_PATH='@baseboard_fab2_lib.baseboard_fab2(sch_1):page156_i289@mstr_discrete.re~
s(chips)',
 P_PATH='@baseboard_fab2_lib.baseboard_fab2(sch_1):page156_i289@mstr_discrete.re~
s(chips)',
 PATH='I289',
 DRAWING='@BASEBOARD_FAB2_LIB.BASEBOARD_FAB2(SCH_1):PAGE156',
 WATTAGE='1/16W',
 TOLERANCE='1%',
 SEC_TYPE='0402',
 MATERIAL='CHIP',
 BOM_COST='SM_CONTROLLER',
 PHYS_PAGE='156',
 XY='(-1700,4100)',
 ROT='6',
 VER='1',
 VALUE='33.2',
 PACK_TYPE='0402',
 PART_NUMBER='G21796-074',
 LOCATION='R2T28',
 ROOM='BMC_MISC',
 SEC='1',
 CDS_LIB='mstr_discrete',
 CDS_PART_NAME='RES_0402-33.2,1%,1/16W,CHIP,G2A',
 PRIM_FILE='./archive_libs/mstr_discrete/res/chips/chips.prt';

PART_NAME
 R2T29 'RES_0402-2.21K,1%,1/16W,CHIP,GA':
 ROOM='BMC_MISC';

SECTION_NUMBER 1
 '@BASEBOARD_FAB2_LIB.BASEBOARD_FAB2(SCH_1):PAGE157_I298@MSTR_DISCRETE.RES(CHIPS)':
 C_PATH='@baseboard_fab2_lib.baseboard_fab2(sch_1):page157_i298@mstr_discrete.re~
s(chips)',
 P_PATH='@baseboard_fab2_lib.baseboard_fab2(sch_1):page157_i298@mstr_discrete.re~
s(chips)',
 PATH='I298',
 DRAWING='@BASEBOARD_FAB2_LIB.BASEBOARD_FAB2(SCH_1):PAGE157',
 WATTAGE='1/16W',
 TOLERANCE='1%',
 SEC_TYPE='0402',
 MATERIAL='CHIP',
 BOM_COST='SM_CONTROLLER',
 PHYS_PAGE='157',
 XY='(-7175,3975)',
 ROT='0',
 VER='1',
 VALUE='2.21K',
 PACK_TYPE='0402',
 PART_NUMBER='G21796-112',
 LOCATION='R2T29',
 ROOM='BMC_MISC',
 SEC='1',
 CDS_LIB='mstr_discrete',
 CDS_PART_NAME='RES_0402-2.21K,1%,1/16W,CHIP,GA',
 PRIM_FILE='./archive_libs/mstr_discrete/res/chips/chips.prt';

PART_NAME
 R2T30 'RES_0402-33.2,1%,1/16W,CHIP,G2A':
 ROOM='PROC_SIDEBAND';

SECTION_NUMBER 1
 '@BASEBOARD_FAB2_LIB.BASEBOARD_FAB2(SCH_1):PAGE93_I42@MSTR_DISCRETE.RES(CHIPS)':
 C_PATH='@baseboard_fab2_lib.baseboard_fab2(sch_1):page93_i42@mstr_discrete.res(~
chips)',
 P_PATH='@baseboard_fab2_lib.baseboard_fab2(sch_1):page93_i42@mstr_discrete.res(~
chips)',
 PATH='I42',
 DRAWING='@BASEBOARD_FAB2_LIB.BASEBOARD_FAB2(SCH_1):PAGE93',
 WATTAGE='1/16W',
 TOLERANCE='1%',
 SEC_TYPE='0402',
 MATERIAL='CHIP',
 BOM_COST='PROC',
 PHYS_PAGE='93',
 XY='(2950,3350)',
 ROT='0',
 VER='1',
 VALUE='33.2',
 PACK_TYPE='0402',
 PART_NUMBER='G21796-074',
 LOCATION='R2T30',
 ROOM='PROC_SIDEBAND',
 SEC='1',
 CDS_LIB='mstr_discrete',
 CDS_PART_NAME='RES_0402-33.2,1%,1/16W,CHIP,G2A',
 PRIM_FILE='./archive_libs/mstr_discrete/res/chips/chips.prt';

PART_NAME
 R2T31 'RES_0402-75,1.0%,1/16W,CHIP,G2A':
 ROOM='PROC_SIDEBAND';

SECTION_NUMBER 1
 '@BASEBOARD_FAB2_LIB.BASEBOARD_FAB2(SCH_1):PAGE93_I68@MSTR_DISCRETE.RES(CHIPS)':
 C_PATH='@baseboard_fab2_lib.baseboard_fab2(sch_1):page93_i68@mstr_discrete.res(~
chips)',
 P_PATH='@baseboard_fab2_lib.baseboard_fab2(sch_1):page93_i68@mstr_discrete.res(~
chips)',
 PATH='I68',
 DRAWING='@BASEBOARD_FAB2_LIB.BASEBOARD_FAB2(SCH_1):PAGE93',
 WATTAGE='1/16W',
 TOLERANCE='1.0%',
 SEC_TYPE='0402',
 MATERIAL='CHIP',
 PHYS_PAGE='93',
 XY='(-925,3300)',
 ROT='0',
 VER='1',
 VALUE='75',
 PACK_TYPE='0402',
 PART_NUMBER='G21796-267',
 LOCATION='R2T31',
 ROOM='PROC_SIDEBAND',
 SEC='1',
 CDS_LIB='mstr_discrete',
 CDS_PART_NAME='RES_0402-75,1.0%,1/16W,CHIP,G2A',
 PRIM_FILE='./archive_libs/mstr_discrete/res/chips/chips.prt';

PART_NAME
 R2T32 'RES_0402-0.0,5%,1/16W,CHIP,G21A':
 ROOM='PROC_SIDEBAND';

SECTION_NUMBER 1
 '@BASEBOARD_FAB2_LIB.BASEBOARD_FAB2(SCH_1):PAGE93_I15@MSTR_DISCRETE.RES(CHIPS)':
 C_PATH='@baseboard_fab2_lib.baseboard_fab2(sch_1):page93_i15@mstr_discrete.res(~
chips)',
 P_PATH='@baseboard_fab2_lib.baseboard_fab2(sch_1):page93_i15@mstr_discrete.res(~
chips)',
 PATH='I15',
 DRAWING='@BASEBOARD_FAB2_LIB.BASEBOARD_FAB2(SCH_1):PAGE93',
 WATTAGE='1/16W',
 TOLERANCE='5%',
 SEC_TYPE='0402',
 MATERIAL='CHIP',
 BOM_COST='PROC',
 PHYS_PAGE='93',
 XY='(-2750,3425)',
 ROT='0',
 VER='1',
 VALUE='0.0',
 PACK_TYPE='0402',
 PART_NUMBER='G21497-005',
 LOCATION='R2T32',
 ROOM='PROC_SIDEBAND',
 SEC='1',
 CDS_LIB='mstr_discrete',
 CDS_PART_NAME='RES_0402-0.0,5%,1/16W,CHIP,G21A',
 PRIM_FILE='./archive_libs/mstr_discrete/res/chips/chips.prt';

PART_NAME
 R2T33 'RES_0402-33.2,1%,1/16W,CHIP,G2A':
 ROOM='PROC_SIDEBAND';

SECTION_NUMBER 1
 '@BASEBOARD_FAB2_LIB.BASEBOARD_FAB2(SCH_1):PAGE93_I40@MSTR_DISCRETE.RES(CHIPS)':
 C_PATH='@baseboard_fab2_lib.baseboard_fab2(sch_1):page93_i40@mstr_discrete.res(~
chips)',
 P_PATH='@baseboard_fab2_lib.baseboard_fab2(sch_1):page93_i40@mstr_discrete.res(~
chips)',
 PATH='I40',
 DRAWING='@BASEBOARD_FAB2_LIB.BASEBOARD_FAB2(SCH_1):PAGE93',
 WATTAGE='1/16W',
 TOLERANCE='1%',
 SEC_TYPE='0402',
 MATERIAL='CHIP',
 BOM_COST='PROC',
 PHYS_PAGE='93',
 XY='(2950,3100)',
 ROT='0',
 VER='1',
 VALUE='33.2',
 PACK_TYPE='0402',
 PART_NUMBER='G21796-074',
 LOCATION='R2T33',
 ROOM='PROC_SIDEBAND',
 SEC='1',
 CDS_LIB='mstr_discrete',
 CDS_PART_NAME='RES_0402-33.2,1%,1/16W,CHIP,G2A',
 PRIM_FILE='./archive_libs/mstr_discrete/res/chips/chips.prt';

PART_NAME
 R2T34 'RES_0402-4.75K,1%,1/16W,CHIP,GA':
 ROOM='BMC_MISC';

SECTION_NUMBER 1
 '@BASEBOARD_FAB2_LIB.BASEBOARD_FAB2(SCH_1):PAGE156_I206@MSTR_DISCRETE.RES(CHIPS)':
 C_PATH='@baseboard_fab2_lib.baseboard_fab2(sch_1):page156_i206@mstr_discrete.re~
s(chips)',
 P_PATH='@baseboard_fab2_lib.baseboard_fab2(sch_1):page156_i206@mstr_discrete.re~
s(chips)',
 PATH='I206',
 DRAWING='@BASEBOARD_FAB2_LIB.BASEBOARD_FAB2(SCH_1):PAGE156',
 WATTAGE='1/16W',
 TOLERANCE='1%',
 SEC_TYPE='0402',
 MATERIAL='CHIP',
 BOM_COST='SM_CONTROLLER',
 PHYS_PAGE='156',
 XY='(-4150,4450)',
 ROT='0',
 VER='2',
 VALUE='4.75K',
 PACK_TYPE='0402',
 PART_NUMBER='G21796-072',
 LOCATION='R2T34',
 ROOM='BMC_MISC',
 SEC='1',
 CDS_LIB='mstr_discrete',
 CDS_PART_NAME='RES_0402-4.75K,1%,1/16W,CHIP,GA',
 PRIM_FILE='./archive_libs/mstr_discrete/res/chips/chips.prt';

PART_NAME
 R2T35 'RES_0402-4.75K,1%,1/16W,CHIP,GA':
 ROOM='BMC_MISC';

SECTION_NUMBER 1
 '@BASEBOARD_FAB2_LIB.BASEBOARD_FAB2(SCH_1):PAGE156_I207@MSTR_DISCRETE.RES(CHIPS)':
 C_PATH='@baseboard_fab2_lib.baseboard_fab2(sch_1):page156_i207@mstr_discrete.re~
s(chips)',
 P_PATH='@baseboard_fab2_lib.baseboard_fab2(sch_1):page156_i207@mstr_discrete.re~
s(chips)',
 PATH='I207',
 DRAWING='@BASEBOARD_FAB2_LIB.BASEBOARD_FAB2(SCH_1):PAGE156',
 WATTAGE='1/16W',
 TOLERANCE='1%',
 SEC_TYPE='0402',
 MATERIAL='CHIP',
 BOM_COST='SM_CONTROLLER',
 PHYS_PAGE='156',
 XY='(-3825,4450)',
 ROT='0',
 VER='2',
 VALUE='4.75K',
 PACK_TYPE='0402',
 PART_NUMBER='G21796-072',
 LOCATION='R2T35',
 ROOM='BMC_MISC',
 SEC='1',
 CDS_LIB='mstr_discrete',
 CDS_PART_NAME='RES_0402-4.75K,1%,1/16W,CHIP,GA',
 PRIM_FILE='./archive_libs/mstr_discrete/res/chips/chips.prt';

PART_NAME
 R2T36 '374R2F-1-GP_SMD-RG-374R2F-1-GPA':;

SECTION_NUMBER 1
 '@BASEBOARD_FAB2_LIB.BASEBOARD_FAB2(SCH_1):PAGE93_I148@W_HDL.374R2F-1-GP(CHIPS)':
 C_PATH='@baseboard_fab2_lib.baseboard_fab2(sch_1):page93_i148@w_hdl.\374r2f-1-g~
p\(chips)',
 P_PATH='@baseboard_fab2_lib.baseboard_fab2(sch_1):page93_i148@w_hdl.\374r2f-1-g~
p\(chips)',
 PATH='I148',
 DRAWING='@BASEBOARD_FAB2_LIB.BASEBOARD_FAB2(SCH_1):PAGE93',
 PACK_SIZE='0402',
 RATED='1/16W',
 ATTRIBUTE='374 OHM',
 TOLERANCE='1%',
 PHYS_PAGE='93',
 XY='(2300,1075)',
 ROT='0',
 VER='1',
 VALUE='374R2F-1-GP',
 PACK_TYPE='SMD-RG',
 PART_NUMBER='64.37405.6DL',
 LOCATION='R2T36',
 CDS_LIB='w_hdl',
 CDS_PART_NAME='374R2F-1-GP_SMD-RG-374R2F-1-GPA',
 PRIM_FILE='C:/<user>/w_hdl/374r2f#2d1#2dgp/chips/chips.prt';

PART_NAME
 R2T37 'RES_0402-200.0,1%,1/16W,CHIP,GA':
 ROOM='PROC_SIDEBAND';

SECTION_NUMBER 1
 '@BASEBOARD_FAB2_LIB.BASEBOARD_FAB2(SCH_1):PAGE92_I94@MSTR_DISCRETE.RES(CHIPS)':
 C_PATH='@baseboard_fab2_lib.baseboard_fab2(sch_1):page92_i94@mstr_discrete.res(~
chips)',
 P_PATH='@baseboard_fab2_lib.baseboard_fab2(sch_1):page92_i94@mstr_discrete.res(~
chips)',
 PATH='I94',
 DRAWING='@BASEBOARD_FAB2_LIB.BASEBOARD_FAB2(SCH_1):PAGE92',
 WATTAGE='1/16W',
 TOLERANCE='1%',
 MATERIAL='CHIP',
 BOM_COST='PROC',
 PHYS_PAGE='92',
 XY='(-4000,2950)',
 ROT='0',
 VER='2',
 VALUE='200.0',
 PACK_TYPE='0402',
 PART_NUMBER='G21796-004',
 LOCATION='R2T37',
 ROOM='PROC_SIDEBAND',
 CDS_LIB='mstr_discrete',
 CDS_PART_NAME='RES_0402-200.0,1%,1/16W,CHIP,GA',
 PRIM_FILE='./archive_libs/mstr_discrete/res/chips/chips.prt';

PART_NAME
 R2T38 'RES_0402-33.2,1%,1/16W,CHIP,G2A':
 ROOM='PROC_SIDEBAND';

SECTION_NUMBER 1
 '@BASEBOARD_FAB2_LIB.BASEBOARD_FAB2(SCH_1):PAGE93_I39@MSTR_DISCRETE.RES(CHIPS)':
 C_PATH='@baseboard_fab2_lib.baseboard_fab2(sch_1):page93_i39@mstr_discrete.res(~
chips)',
 P_PATH='@baseboard_fab2_lib.baseboard_fab2(sch_1):page93_i39@mstr_discrete.res(~
chips)',
 PATH='I39',
 DRAWING='@BASEBOARD_FAB2_LIB.BASEBOARD_FAB2(SCH_1):PAGE93',
 WATTAGE='1/16W',
 TOLERANCE='1%',
 SEC_TYPE='0402',
 MATERIAL='CHIP',
 BOM_COST='PROC',
 PHYS_PAGE='93',
 XY='(2950,2850)',
 ROT='0',
 VER='1',
 VALUE='33.2',
 PACK_TYPE='0402',
 PART_NUMBER='G21796-074',
 LOCATION='R2T38',
 ROOM='PROC_SIDEBAND',
 SEC='1',
 CDS_LIB='mstr_discrete',
 CDS_PART_NAME='RES_0402-33.2,1%,1/16W,CHIP,G2A',
 PRIM_FILE='./archive_libs/mstr_discrete/res/chips/chips.prt';

PART_NAME
 R2T39 'RES_0402-100.0,1%,1/16W,CHIP,GA':
 ROOM='PROC_SIDEBAND';

SECTION_NUMBER 1
 '@BASEBOARD_FAB2_LIB.BASEBOARD_FAB2(SCH_1):PAGE93_I98@MSTR_DISCRETE.RES(CHIPS)':
 C_PATH='@baseboard_fab2_lib.baseboard_fab2(sch_1):page93_i98@mstr_discrete.res(~
chips)',
 P_PATH='@baseboard_fab2_lib.baseboard_fab2(sch_1):page93_i98@mstr_discrete.res(~
chips)',
 PATH='I98',
 DRAWING='@BASEBOARD_FAB2_LIB.BASEBOARD_FAB2(SCH_1):PAGE93',
 WATTAGE='1/16W',
 TOLERANCE='1%',
 SEC_TYPE='0402',
 MATERIAL='CHIP',
 BOM_COST='PROC',
 PHYS_PAGE='93',
 XY='(2300,600)',
 ROT='0',
 VER='2',
 VALUE='100.0',
 PACK_TYPE='0402',
 PART_NUMBER='G21796-017',
 LOCATION='R2T39',
 ROOM='PROC_SIDEBAND',
 SEC='1',
 CDS_LIB='mstr_discrete',
 CDS_PART_NAME='RES_0402-100.0,1%,1/16W,CHIP,GA',
 PRIM_FILE='./archive_libs/mstr_discrete/res/chips/chips.prt';

PART_NAME
 R2T40 'RES_0402-0.0,5%,1/16W,CHIP,G21A':
 ROOM='PROC_SIDEBAND';

SECTION_NUMBER 1
 '@BASEBOARD_FAB2_LIB.BASEBOARD_FAB2(SCH_1):PAGE92_I93@MSTR_DISCRETE.RES(CHIPS)':
 C_PATH='@baseboard_fab2_lib.baseboard_fab2(sch_1):page92_i93@mstr_discrete.res(~
chips)',
 P_PATH='@baseboard_fab2_lib.baseboard_fab2(sch_1):page92_i93@mstr_discrete.res(~
chips)',
 PATH='I93',
 DRAWING='@BASEBOARD_FAB2_LIB.BASEBOARD_FAB2(SCH_1):PAGE92',
 WATTAGE='1/16W',
 TOLERANCE='5%',
 MATERIAL='CHIP',
 BOM_COST='PROC',
 PHYS_PAGE='92',
 XY='(-4750,2800)',
 ROT='0',
 VER='1',
 VALUE='0.0',
 PACK_TYPE='0402',
 PART_NUMBER='G21497-005',
 LOCATION='R2T40',
 ROOM='PROC_SIDEBAND',
 CDS_LIB='mstr_discrete',
 CDS_PART_NAME='RES_0402-0.0,5%,1/16W,CHIP,G21A',
 PRIM_FILE='./archive_libs/mstr_discrete/res/chips/chips.prt';

PART_NAME
 R2T41 'RES_0402-22.1,1.0%,1/16W,CHIP,A':
 ROOM='BMC';

SECTION_NUMBER 1
 '@BASEBOARD_FAB2_LIB.BASEBOARD_FAB2(SCH_1):PAGE145_I136@MSTR_DISCRETE.RES(CHIPS)':
 C_PATH='@baseboard_fab2_lib.baseboard_fab2(sch_1):page145_i136@mstr_discrete.re~
s(chips)',
 P_PATH='@baseboard_fab2_lib.baseboard_fab2(sch_1):page145_i136@mstr_discrete.re~
s(chips)',
 PATH='I136',
 DRAWING='@BASEBOARD_FAB2_LIB.BASEBOARD_FAB2(SCH_1):PAGE145',
 WATTAGE='1/16W',
 TOLERANCE='1.0%',
 SEC_TYPE='0402',
 MATERIAL='CHIP',
 BOM_COST='SM_CONTROLLER',
 PHYS_PAGE='145',
 XY='(-6450,-2950)',
 ROT='0',
 VER='1',
 VALUE='22.1',
 PACK_TYPE='0402',
 PART_NUMBER='G21796-250',
 LOCATION='R2T41',
 ROOM='BMC',
 SEC='1',
 CDS_LIB='mstr_discrete',
 CDS_PART_NAME='RES_0402-22.1,1.0%,1/16W,CHIP,A',
 PRIM_FILE='./archive_libs/mstr_discrete/res/chips/chips.prt';

PART_NAME
 R2T42 'RES_0402-22.1,1.0%,1/16W,CHIP,A':
 ROOM='SYS_CLOCK';

SECTION_NUMBER 1
 '@BASEBOARD_FAB2_LIB.BASEBOARD_FAB2(SCH_1):PAGE101_I124@MSTR_DISCRETE.RES(CHIPS)':
 C_PATH='@baseboard_fab2_lib.baseboard_fab2(sch_1):page101_i124@mstr_discrete.re~
s(chips)',
 P_PATH='@baseboard_fab2_lib.baseboard_fab2(sch_1):page101_i124@mstr_discrete.re~
s(chips)',
 PATH='I124',
 DRAWING='@BASEBOARD_FAB2_LIB.BASEBOARD_FAB2(SCH_1):PAGE101',
 WATTAGE='1/16W',
 TOLERANCE='1.0%',
 SEC_TYPE='0402',
 MATERIAL='CHIP',
 BOM_COST='SM_CONTROLLER',
 PHYS_PAGE='101',
 XY='(-3050,1550)',
 ROT='0',
 VER='1',
 VALUE='22.1',
 PACK_TYPE='0402',
 PART_NUMBER='G21796-250',
 LOCATION='R2T42',
 ROOM='SYS_CLOCK',
 SEC='1',
 CDS_LIB='mstr_discrete',
 CDS_PART_NAME='RES_0402-22.1,1.0%,1/16W,CHIP,A',
 PRIM_FILE='./archive_libs/mstr_discrete/res/chips/chips.prt';

PART_NAME
 R2T43 'RES_0402-75,1.0%,1/16W,CHIP,G2A':
 ROOM='PROC_SIDEBAND';

SECTION_NUMBER 1
 '@BASEBOARD_FAB2_LIB.BASEBOARD_FAB2(SCH_1):PAGE92_I96@MSTR_DISCRETE.RES(CHIPS)':
 C_PATH='@baseboard_fab2_lib.baseboard_fab2(sch_1):page92_i96@mstr_discrete.res(~
chips)',
 P_PATH='@baseboard_fab2_lib.baseboard_fab2(sch_1):page92_i96@mstr_discrete.res(~
chips)',
 PATH='I96',
 DRAWING='@BASEBOARD_FAB2_LIB.BASEBOARD_FAB2(SCH_1):PAGE92',
 WATTAGE='1/16W',
 TOLERANCE='1.0%',
 MATERIAL='CHIP',
 BOM_COST='PROC',
 PHYS_PAGE='92',
 XY='(-3675,2675)',
 ROT='0',
 VER='1',
 VALUE='75',
 PACK_TYPE='0402',
 PART_NUMBER='G21796-267',
 LOCATION='R2T43',
 ROOM='PROC_SIDEBAND',
 CDS_LIB='mstr_discrete',
 CDS_PART_NAME='RES_0402-75,1.0%,1/16W,CHIP,G2A',
 PRIM_FILE='./archive_libs/mstr_discrete/res/chips/chips.prt';

PART_NAME
 R2T44 'RES_0402-0.0,5%,1/16W,CHIP,G21A':
 ROOM='PROC_SIDEBAND';

SECTION_NUMBER 1
 '@BASEBOARD_FAB2_LIB.BASEBOARD_FAB2(SCH_1):PAGE92_I92@MSTR_DISCRETE.RES(CHIPS)':
 C_PATH='@baseboard_fab2_lib.baseboard_fab2(sch_1):page92_i92@mstr_discrete.res(~
chips)',
 P_PATH='@baseboard_fab2_lib.baseboard_fab2(sch_1):page92_i92@mstr_discrete.res(~
chips)',
 PATH='I92',
 DRAWING='@BASEBOARD_FAB2_LIB.BASEBOARD_FAB2(SCH_1):PAGE92',
 WATTAGE='1/16W',
 TOLERANCE='5%',
 MATERIAL='CHIP',
 BOM_COST='PROC',
 PHYS_PAGE='92',
 XY='(-4725,2550)',
 ROT='0',
 VER='1',
 VALUE='0.0',
 PACK_TYPE='0402',
 PART_NUMBER='G21497-005',
 LOCATION='R2T44',
 ROOM='PROC_SIDEBAND',
 CDS_LIB='mstr_discrete',
 CDS_PART_NAME='RES_0402-0.0,5%,1/16W,CHIP,G21A',
 PRIM_FILE='./archive_libs/mstr_discrete/res/chips/chips.prt';

PART_NAME
 R2T46 'RES_0402-22.1,1.0%,1/16W,CHIP,A':
 ROOM='SYS_CLOCK';

SECTION_NUMBER 1
 '@BASEBOARD_FAB2_LIB.BASEBOARD_FAB2(SCH_1):PAGE101_I125@MSTR_DISCRETE.RES(CHIPS)':
 C_PATH='@baseboard_fab2_lib.baseboard_fab2(sch_1):page101_i125@mstr_discrete.re~
s(chips)',
 P_PATH='@baseboard_fab2_lib.baseboard_fab2(sch_1):page101_i125@mstr_discrete.re~
s(chips)',
 PATH='I125',
 DRAWING='@BASEBOARD_FAB2_LIB.BASEBOARD_FAB2(SCH_1):PAGE101',
 WATTAGE='1/16W',
 TOLERANCE='1.0%',
 SEC_TYPE='0402',
 MATERIAL='CHIP',
 BOM_COST='SM_CONTROLLER',
 PHYS_PAGE='101',
 XY='(-3050,1700)',
 ROT='0',
 VER='1',
 VALUE='22.1',
 PACK_TYPE='0402',
 PART_NUMBER='G21796-250',
 LOCATION='R2T46',
 ROOM='SYS_CLOCK',
 SEC='1',
 CDS_LIB='mstr_discrete',
 CDS_PART_NAME='RES_0402-22.1,1.0%,1/16W,CHIP,A',
 PRIM_FILE='./archive_libs/mstr_discrete/res/chips/chips.prt';

PART_NAME
 R2T47 'RES_0402-33.2,1%,1/16W,CHIP,G2A':
 ROOM='SYS_CLOCK';

SECTION_NUMBER 1
 '@BASEBOARD_FAB2_LIB.BASEBOARD_FAB2(SCH_1):PAGE101_I130@MSTR_DISCRETE.RES(CHIPS)':
 C_PATH='@baseboard_fab2_lib.baseboard_fab2(sch_1):page101_i130@mstr_discrete.re~
s(chips)',
 P_PATH='@baseboard_fab2_lib.baseboard_fab2(sch_1):page101_i130@mstr_discrete.re~
s(chips)',
 PATH='I130',
 DRAWING='@BASEBOARD_FAB2_LIB.BASEBOARD_FAB2(SCH_1):PAGE101',
 WATTAGE='1/16W',
 TOLERANCE='1%',
 SEC_TYPE='0402',
 MATERIAL='CHIP',
 BOM_COST='SM_CONTROLLER',
 PHYS_PAGE='101',
 XY='(-3050,2600)',
 ROT='0',
 VER='1',
 VALUE='33.2',
 PACK_TYPE='0402',
 PART_NUMBER='G21796-074',
 LOCATION='R2T47',
 ROOM='SYS_CLOCK',
 SEC='1',
 CDS_LIB='mstr_discrete',
 CDS_PART_NAME='RES_0402-33.2,1%,1/16W,CHIP,G2A',
 PRIM_FILE='./archive_libs/mstr_discrete/res/chips/chips.prt';

PART_NAME
 R2T49 'RES_0402-20.0,1%,1/16W,CHIP,G2A':
 ROOM='SMBUS';

SECTION_NUMBER 1
 '@BASEBOARD_FAB2_LIB.BASEBOARD_FAB2(SCH_1):PAGE159_I219@MSTR_DISCRETE.RES(CHIPS)':
 C_PATH='@baseboard_fab2_lib.baseboard_fab2(sch_1):page159_i219@mstr_discrete.re~
s(chips)',
 P_PATH='@baseboard_fab2_lib.baseboard_fab2(sch_1):page159_i219@mstr_discrete.re~
s(chips)',
 PATH='I219',
 DRAWING='@BASEBOARD_FAB2_LIB.BASEBOARD_FAB2(SCH_1):PAGE159',
 WATTAGE='1/16W',
 TOLERANCE='1%',
 MATERIAL='CHIP',
 BOM_COST='SM_CONTROLLER',
 PHYS_PAGE='159',
 XY='(700,3550)',
 ROT='0',
 VER='1',
 VALUE='20.0',
 PACK_TYPE='0402',
 PART_NUMBER='G21796-173',
 LOCATION='R2T49',
 ROOM='SMBUS',
 CDS_LIB='mstr_discrete',
 CDS_PART_NAME='RES_0402-20.0,1%,1/16W,CHIP,G2A',
 PRIM_FILE='./archive_libs/mstr_discrete/res/chips/chips.prt';

PART_NAME
 R2T50 'RES_0402-1.00K,1%,1/16W,CHIP,GA':
 ROOM='PROC_SIDEBAND';

SECTION_NUMBER 1
 '@BASEBOARD_FAB2_LIB.BASEBOARD_FAB2(SCH_1):PAGE93_I127@MSTR_DISCRETE.RES(CHIPS)':
 C_PATH='@baseboard_fab2_lib.baseboard_fab2(sch_1):page93_i127@mstr_discrete.res~
(chips)',
 P_PATH='@baseboard_fab2_lib.baseboard_fab2(sch_1):page93_i127@mstr_discrete.res~
(chips)',
 PATH='I127',
 DRAWING='@BASEBOARD_FAB2_LIB.BASEBOARD_FAB2(SCH_1):PAGE93',
 WATTAGE='1/16W',
 TOLERANCE='1%',
 SEC_TYPE='0402',
 MATERIAL='CHIP',
 BOM_COST='PROC',
 PHYS_PAGE='93',
 XY='(3700,425)',
 ROT='0',
 VER='2',
 VALUE='1.00K',
 PACK_TYPE='0402',
 PART_NUMBER='G21796-026',
 LOCATION='R2T50',
 ROOM='PROC_SIDEBAND',
 SEC='1',
 CDS_LIB='mstr_discrete',
 CDS_PART_NAME='RES_0402-1.00K,1%,1/16W,CHIP,GA',
 PRIM_FILE='./archive_libs/mstr_discrete/res/chips/chips.prt';

PART_NAME
 R2T52 'RES_0603-2.2,1.0%,1/10W,CHIP,GA':
 ROOM='SYS_CLOCK';

SECTION_NUMBER 1
 '@BASEBOARD_FAB2_LIB.BASEBOARD_FAB2(SCH_1):PAGE101_I95@MSTR_DISCRETE.RES(CHIPS)':
 C_PATH='@baseboard_fab2_lib.baseboard_fab2(sch_1):page101_i95@mstr_discrete.res~
(chips)',
 P_PATH='@baseboard_fab2_lib.baseboard_fab2(sch_1):page101_i95@mstr_discrete.res~
(chips)',
 PATH='I95',
 DRAWING='@BASEBOARD_FAB2_LIB.BASEBOARD_FAB2(SCH_1):PAGE101',
 WATTAGE='1/10W',
 TOLERANCE='1.0%',
 MATERIAL='CHIP',
 BOM_COST='SM_CONTROLLER',
 PHYS_PAGE='101',
 XY='(-2825,4200)',
 ROT='0',
 VER='1',
 VALUE='2.2',
 PACK_TYPE='0603',
 PART_NUMBER='G22026-127',
 LOCATION='R2T52',
 ROOM='SYS_CLOCK',
 CDS_LIB='mstr_discrete',
 CDS_PART_NAME='RES_0603-2.2,1.0%,1/10W,CHIP,GA',
 PRIM_FILE='./archive_libs/mstr_discrete/res/chips/chips.prt';

PART_NAME
 R2T53 'RES_0402-665,1.0%,1/16W,CHIP,GA':
 ROOM='SMBUS';

SECTION_NUMBER 1
 '@BASEBOARD_FAB2_LIB.BASEBOARD_FAB2(SCH_1):PAGE138_I83@MSTR_DISCRETE.RES(CHIPS)':
 C_PATH='@baseboard_fab2_lib.baseboard_fab2(sch_1):page138_i83@mstr_discrete.res~
(chips)',
 P_PATH='@baseboard_fab2_lib.baseboard_fab2(sch_1):page138_i83@mstr_discrete.res~
(chips)',
 PATH='I83',
 DRAWING='@BASEBOARD_FAB2_LIB.BASEBOARD_FAB2(SCH_1):PAGE138',
 WATTAGE='1/16W',
 TOLERANCE='1.0%',
 SEC_TYPE='0402',
 MATERIAL='CHIP',
 BOM_COST='SM_CONTROLLER',
 PHYS_PAGE='138',
 XY='(500,4450)',
 ROT='0',
 VER='2',
 VALUE='665',
 PACK_TYPE='0402',
 PART_NUMBER='G21796-235',
 LOCATION='R2T53',
 ROOM='SMBUS',
 SEC='1',
 CDS_LIB='mstr_discrete',
 CDS_PART_NAME='RES_0402-665,1.0%,1/16W,CHIP,GA',
 PRIM_FILE='./archive_libs/mstr_discrete/res/chips/chips.prt';

PART_NAME
 R2T54 'RES_0402-665,1.0%,1/16W,CHIP,GA':
 ROOM='SMBUS';

SECTION_NUMBER 1
 '@BASEBOARD_FAB2_LIB.BASEBOARD_FAB2(SCH_1):PAGE138_I84@MSTR_DISCRETE.RES(CHIPS)':
 C_PATH='@baseboard_fab2_lib.baseboard_fab2(sch_1):page138_i84@mstr_discrete.res~
(chips)',
 P_PATH='@baseboard_fab2_lib.baseboard_fab2(sch_1):page138_i84@mstr_discrete.res~
(chips)',
 PATH='I84',
 DRAWING='@BASEBOARD_FAB2_LIB.BASEBOARD_FAB2(SCH_1):PAGE138',
 WATTAGE='1/16W',
 TOLERANCE='1.0%',
 SEC_TYPE='0402',
 MATERIAL='CHIP',
 BOM_COST='SM_CONTROLLER',
 PHYS_PAGE='138',
 XY='(850,4400)',
 ROT='0',
 VER='2',
 VALUE='665',
 PACK_TYPE='0402',
 PART_NUMBER='G21796-235',
 LOCATION='R2T54',
 ROOM='SMBUS',
 SEC='1',
 CDS_LIB='mstr_discrete',
 CDS_PART_NAME='RES_0402-665,1.0%,1/16W,CHIP,GA',
 PRIM_FILE='./archive_libs/mstr_discrete/res/chips/chips.prt';

PART_NAME
 R2T57 'RES_0402-0.0,5%,1/16W,EMPTY,G2A':;

SECTION_NUMBER 1
 '@BASEBOARD_FAB2_LIB.BASEBOARD_FAB2(SCH_1):PAGE93_I88@MSTR_DISCRETE.RES(CHIPS)':
 C_PATH='@baseboard_fab2_lib.baseboard_fab2(sch_1):page93_i88@mstr_discrete.res(~
chips)',
 P_PATH='@baseboard_fab2_lib.baseboard_fab2(sch_1):page93_i88@mstr_discrete.res(~
chips)',
 PATH='I88',
 DRAWING='@BASEBOARD_FAB2_LIB.BASEBOARD_FAB2(SCH_1):PAGE93',
 WATTAGE='1/16W',
 TOLERANCE='5%',
 SEC_TYPE='0402',
 MATERIAL='EMPTY',
 PHYS_PAGE='93',
 XY='(-1375,4125)',
 ROT='0',
 VER='2',
 VALUE='0.0',
 PACK_TYPE='0402',
 PART_NUMBER='G21497-005',
 LOCATION='R2T57',
 SEC='1',
 CDS_LIB='mstr_discrete',
 CDS_PART_NAME='RES_0402-0.0,5%,1/16W,EMPTY,G2A',
 PRIM_FILE='./archive_libs/mstr_discrete/res/chips/chips.prt';

PART_NAME
 R2T58 'RES_0402-0.0,5%,1/16W,EMPTY,G2A':;

SECTION_NUMBER 1
 '@BASEBOARD_FAB2_LIB.BASEBOARD_FAB2(SCH_1):PAGE93_I94@MSTR_DISCRETE.RES(CHIPS)':
 C_PATH='@baseboard_fab2_lib.baseboard_fab2(sch_1):page93_i94@mstr_discrete.res(~
chips)',
 P_PATH='@baseboard_fab2_lib.baseboard_fab2(sch_1):page93_i94@mstr_discrete.res(~
chips)',
 PATH='I94',
 DRAWING='@BASEBOARD_FAB2_LIB.BASEBOARD_FAB2(SCH_1):PAGE93',
 WATTAGE='1/16W',
 TOLERANCE='5%',
 SEC_TYPE='0402',
 MATERIAL='EMPTY',
 PHYS_PAGE='93',
 XY='(2400,3850)',
 ROT='0',
 VER='2',
 VALUE='0.0',
 PACK_TYPE='0402',
 PART_NUMBER='G21497-005',
 LOCATION='R2T58',
 SEC='1',
 CDS_LIB='mstr_discrete',
 CDS_PART_NAME='RES_0402-0.0,5%,1/16W,EMPTY,G2A',
 PRIM_FILE='./archive_libs/mstr_discrete/res/chips/chips.prt';

PART_NAME
 R2T59 'RES_0402-0.0,5%,1/16W,EMPTY,G2A':;

SECTION_NUMBER 1
 '@BASEBOARD_FAB2_LIB.BASEBOARD_FAB2(SCH_1):PAGE93_I107@MSTR_DISCRETE.RES(CHIPS)':
 C_PATH='@baseboard_fab2_lib.baseboard_fab2(sch_1):page93_i107@mstr_discrete.res~
(chips)',
 P_PATH='@baseboard_fab2_lib.baseboard_fab2(sch_1):page93_i107@mstr_discrete.res~
(chips)',
 PATH='I107',
 DRAWING='@BASEBOARD_FAB2_LIB.BASEBOARD_FAB2(SCH_1):PAGE93',
 WATTAGE='1/16W',
 TOLERANCE='5%',
 SEC_TYPE='0402',
 MATERIAL='EMPTY',
 PHYS_PAGE='93',
 XY='(-1100,1900)',
 ROT='0',
 VER='2',
 VALUE='0.0',
 PACK_TYPE='0402',
 PART_NUMBER='G21497-005',
 LOCATION='R2T59',
 SEC='1',
 CDS_LIB='mstr_discrete',
 CDS_PART_NAME='RES_0402-0.0,5%,1/16W,EMPTY,G2A',
 PRIM_FILE='./archive_libs/mstr_discrete/res/chips/chips.prt';

PART_NAME
 R2T60 'RES_0402-0.0,5%,1/16W,CHIP,G21A':;

SECTION_NUMBER 1
 '@BASEBOARD_FAB2_LIB.BASEBOARD_FAB2(SCH_1):PAGE93_I103@MSTR_DISCRETE.RES(CHIPS)':
 C_PATH='@baseboard_fab2_lib.baseboard_fab2(sch_1):page93_i103@mstr_discrete.res~
(chips)',
 P_PATH='@baseboard_fab2_lib.baseboard_fab2(sch_1):page93_i103@mstr_discrete.res~
(chips)',
 PATH='I103',
 DRAWING='@BASEBOARD_FAB2_LIB.BASEBOARD_FAB2(SCH_1):PAGE93',
 WATTAGE='1/16W',
 TOLERANCE='5%',
 SEC_TYPE='0402',
 MATERIAL='CHIP',
 PHYS_PAGE='93',
 XY='(-825,2300)',
 ROT='0',
 VER='1',
 VALUE='0.0',
 PACK_TYPE='0402',
 PART_NUMBER='G21497-005',
 LOCATION='R2T60',
 SEC='1',
 CDS_LIB='mstr_discrete',
 CDS_PART_NAME='RES_0402-0.0,5%,1/16W,CHIP,G21A',
 PRIM_FILE='./archive_libs/mstr_discrete/res/chips/chips.prt';

PART_NAME
 R2T61 'RES_0402-0.0,5%,1/16W,EMPTY,G2A':;

SECTION_NUMBER 1
 '@BASEBOARD_FAB2_LIB.BASEBOARD_FAB2(SCH_1):PAGE93_I89@MSTR_DISCRETE.RES(CHIPS)':
 C_PATH='@baseboard_fab2_lib.baseboard_fab2(sch_1):page93_i89@mstr_discrete.res(~
chips)',
 P_PATH='@baseboard_fab2_lib.baseboard_fab2(sch_1):page93_i89@mstr_discrete.res(~
chips)',
 PATH='I89',
 DRAWING='@BASEBOARD_FAB2_LIB.BASEBOARD_FAB2(SCH_1):PAGE93',
 WATTAGE='1/16W',
 TOLERANCE='5%',
 SEC_TYPE='0402',
 MATERIAL='EMPTY',
 PHYS_PAGE='93',
 XY='(-1100,4125)',
 ROT='0',
 VER='2',
 VALUE='0.0',
 PACK_TYPE='0402',
 PART_NUMBER='G21497-005',
 LOCATION='R2T61',
 SEC='1',
 CDS_LIB='mstr_discrete',
 CDS_PART_NAME='RES_0402-0.0,5%,1/16W,EMPTY,G2A',
 PRIM_FILE='./archive_libs/mstr_discrete/res/chips/chips.prt';

PART_NAME
 R2T62 'RES_0402-0.0,5%,1/16W,EMPTY,G2A':;

SECTION_NUMBER 1
 '@BASEBOARD_FAB2_LIB.BASEBOARD_FAB2(SCH_1):PAGE93_I93@MSTR_DISCRETE.RES(CHIPS)':
 C_PATH='@baseboard_fab2_lib.baseboard_fab2(sch_1):page93_i93@mstr_discrete.res(~
chips)',
 P_PATH='@baseboard_fab2_lib.baseboard_fab2(sch_1):page93_i93@mstr_discrete.res(~
chips)',
 PATH='I93',
 DRAWING='@BASEBOARD_FAB2_LIB.BASEBOARD_FAB2(SCH_1):PAGE93',
 WATTAGE='1/16W',
 TOLERANCE='5%',
 SEC_TYPE='0402',
 MATERIAL='EMPTY',
 PHYS_PAGE='93',
 XY='(2025,3850)',
 ROT='0',
 VER='2',
 VALUE='0.0',
 PACK_TYPE='0402',
 PART_NUMBER='G21497-005',
 LOCATION='R2T62',
 SEC='1',
 CDS_LIB='mstr_discrete',
 CDS_PART_NAME='RES_0402-0.0,5%,1/16W,EMPTY,G2A',
 PRIM_FILE='./archive_libs/mstr_discrete/res/chips/chips.prt';

PART_NAME
 R2T63 'RES_0402-0.0,5%,1/16W,EMPTY,G2A':;

SECTION_NUMBER 1
 '@BASEBOARD_FAB2_LIB.BASEBOARD_FAB2(SCH_1):PAGE93_I133@MSTR_DISCRETE.RES(CHIPS)':
 C_PATH='@baseboard_fab2_lib.baseboard_fab2(sch_1):page93_i133@mstr_discrete.res~
(chips)',
 P_PATH='@baseboard_fab2_lib.baseboard_fab2(sch_1):page93_i133@mstr_discrete.res~
(chips)',
 PATH='I133',
 DRAWING='@BASEBOARD_FAB2_LIB.BASEBOARD_FAB2(SCH_1):PAGE93',
 WATTAGE='1/16W',
 TOLERANCE='5%',
 SEC_TYPE='0402',
 MATERIAL='EMPTY',
 PHYS_PAGE='93',
 XY='(-2225,850)',
 ROT='0',
 VER='1',
 VALUE='0.0',
 PACK_TYPE='0402',
 PART_NUMBER='G21497-005',
 LOCATION='R2T63',
 SEC='1',
 CDS_LIB='mstr_discrete',
 CDS_PART_NAME='RES_0402-0.0,5%,1/16W,EMPTY,G2A',
 PRIM_FILE='./archive_libs/mstr_discrete/res/chips/chips.prt';

PART_NAME
 R2T64 'RES_0402-0.0,5%,1/16W,CHIP,G21A':;

SECTION_NUMBER 1
 '@BASEBOARD_FAB2_LIB.BASEBOARD_FAB2(SCH_1):PAGE93_I121@MSTR_DISCRETE.RES(CHIPS)':
 C_PATH='@baseboard_fab2_lib.baseboard_fab2(sch_1):page93_i121@mstr_discrete.res~
(chips)',
 P_PATH='@baseboard_fab2_lib.baseboard_fab2(sch_1):page93_i121@mstr_discrete.res~
(chips)',
 PATH='I121',
 DRAWING='@BASEBOARD_FAB2_LIB.BASEBOARD_FAB2(SCH_1):PAGE93',
 WATTAGE='1/16W',
 TOLERANCE='5%',
 SEC_TYPE='0402',
 MATERIAL='CHIP',
 PHYS_PAGE='93',
 XY='(-2225,1050)',
 ROT='0',
 VER='1',
 VALUE='0.0',
 PACK_TYPE='0402',
 PART_NUMBER='G21497-005',
 LOCATION='R2T64',
 SEC='1',
 CDS_LIB='mstr_discrete',
 CDS_PART_NAME='RES_0402-0.0,5%,1/16W,CHIP,G21A',
 PRIM_FILE='./archive_libs/mstr_discrete/res/chips/chips.prt';

PART_NAME
 R2T65 'RES_0402-0.0,5%,1/16W,CHIP,G21A':;

SECTION_NUMBER 1
 '@BASEBOARD_FAB2_LIB.BASEBOARD_FAB2(SCH_1):PAGE93_I111@MSTR_DISCRETE.RES(CHIPS)':
 C_PATH='@baseboard_fab2_lib.baseboard_fab2(sch_1):page93_i111@mstr_discrete.res~
(chips)',
 P_PATH='@baseboard_fab2_lib.baseboard_fab2(sch_1):page93_i111@mstr_discrete.res~
(chips)',
 PATH='I111',
 DRAWING='@BASEBOARD_FAB2_LIB.BASEBOARD_FAB2(SCH_1):PAGE93',
 WATTAGE='1/16W',
 TOLERANCE='5%',
 SEC_TYPE='0402',
 MATERIAL='CHIP',
 PHYS_PAGE='93',
 XY='(1875,3350)',
 ROT='0',
 VER='1',
 VALUE='0.0',
 PACK_TYPE='0402',
 PART_NUMBER='G21497-005',
 LOCATION='R2T65',
 SEC='1',
 CDS_LIB='mstr_discrete',
 CDS_PART_NAME='RES_0402-0.0,5%,1/16W,CHIP,G21A',
 PRIM_FILE='./archive_libs/mstr_discrete/res/chips/chips.prt';

PART_NAME
 R2T66 'RES_0402-0.0,5%,1/16W,CHIP,G21A':;

SECTION_NUMBER 1
 '@BASEBOARD_FAB2_LIB.BASEBOARD_FAB2(SCH_1):PAGE93_I112@MSTR_DISCRETE.RES(CHIPS)':
 C_PATH='@baseboard_fab2_lib.baseboard_fab2(sch_1):page93_i112@mstr_discrete.res~
(chips)',
 P_PATH='@baseboard_fab2_lib.baseboard_fab2(sch_1):page93_i112@mstr_discrete.res~
(chips)',
 PATH='I112',
 DRAWING='@BASEBOARD_FAB2_LIB.BASEBOARD_FAB2(SCH_1):PAGE93',
 WATTAGE='1/16W',
 TOLERANCE='5%',
 SEC_TYPE='0402',
 MATERIAL='CHIP',
 PHYS_PAGE='93',
 XY='(1875,3100)',
 ROT='0',
 VER='1',
 VALUE='0.0',
 PACK_TYPE='0402',
 PART_NUMBER='G21497-005',
 LOCATION='R2T66',
 SEC='1',
 CDS_LIB='mstr_discrete',
 CDS_PART_NAME='RES_0402-0.0,5%,1/16W,CHIP,G21A',
 PRIM_FILE='./archive_libs/mstr_discrete/res/chips/chips.prt';

PART_NAME
 R2T67 'RES_0402-0.0,5%,1/16W,CHIP,G21A':;

SECTION_NUMBER 1
 '@BASEBOARD_FAB2_LIB.BASEBOARD_FAB2(SCH_1):PAGE93_I113@MSTR_DISCRETE.RES(CHIPS)':
 C_PATH='@baseboard_fab2_lib.baseboard_fab2(sch_1):page93_i113@mstr_discrete.res~
(chips)',
 P_PATH='@baseboard_fab2_lib.baseboard_fab2(sch_1):page93_i113@mstr_discrete.res~
(chips)',
 PATH='I113',
 DRAWING='@BASEBOARD_FAB2_LIB.BASEBOARD_FAB2(SCH_1):PAGE93',
 WATTAGE='1/16W',
 TOLERANCE='5%',
 SEC_TYPE='0402',
 MATERIAL='CHIP',
 PHYS_PAGE='93',
 XY='(1875,2850)',
 ROT='0',
 VER='1',
 VALUE='0.0',
 PACK_TYPE='0402',
 PART_NUMBER='G21497-005',
 LOCATION='R2T67',
 SEC='1',
 CDS_LIB='mstr_discrete',
 CDS_PART_NAME='RES_0402-0.0,5%,1/16W,CHIP,G21A',
 PRIM_FILE='./archive_libs/mstr_discrete/res/chips/chips.prt';

PART_NAME
 R2T68 'RES_0402-0.0,5%,1/16W,CHIP,G21A':;

SECTION_NUMBER 1
 '@BASEBOARD_FAB2_LIB.BASEBOARD_FAB2(SCH_1):PAGE93_I102@MSTR_DISCRETE.RES(CHIPS)':
 C_PATH='@baseboard_fab2_lib.baseboard_fab2(sch_1):page93_i102@mstr_discrete.res~
(chips)',
 P_PATH='@baseboard_fab2_lib.baseboard_fab2(sch_1):page93_i102@mstr_discrete.res~
(chips)',
 PATH='I102',
 DRAWING='@BASEBOARD_FAB2_LIB.BASEBOARD_FAB2(SCH_1):PAGE93',
 WATTAGE='1/16W',
 TOLERANCE='5%',
 SEC_TYPE='0402',
 MATERIAL='CHIP',
 PHYS_PAGE='93',
 XY='(-825,2175)',
 ROT='0',
 VER='1',
 VALUE='0.0',
 PACK_TYPE='0402',
 PART_NUMBER='G21497-005',
 LOCATION='R2T68',
 SEC='1',
 CDS_LIB='mstr_discrete',
 CDS_PART_NAME='RES_0402-0.0,5%,1/16W,CHIP,G21A',
 PRIM_FILE='./archive_libs/mstr_discrete/res/chips/chips.prt';

PART_NAME
 R2T69 'RES_0402-0.0,5%,1/16W,EMPTY,G2A':;

SECTION_NUMBER 1
 '@BASEBOARD_FAB2_LIB.BASEBOARD_FAB2(SCH_1):PAGE93_I108@MSTR_DISCRETE.RES(CHIPS)':
 C_PATH='@baseboard_fab2_lib.baseboard_fab2(sch_1):page93_i108@mstr_discrete.res~
(chips)',
 P_PATH='@baseboard_fab2_lib.baseboard_fab2(sch_1):page93_i108@mstr_discrete.res~
(chips)',
 PATH='I108',
 DRAWING='@BASEBOARD_FAB2_LIB.BASEBOARD_FAB2(SCH_1):PAGE93',
 WATTAGE='1/16W',
 TOLERANCE='5%',
 SEC_TYPE='0402',
 MATERIAL='EMPTY',
 PHYS_PAGE='93',
 XY='(-1400,1900)',
 ROT='0',
 VER='2',
 VALUE='0.0',
 PACK_TYPE='0402',
 PART_NUMBER='G21497-005',
 LOCATION='R2T69',
 SEC='1',
 CDS_LIB='mstr_discrete',
 CDS_PART_NAME='RES_0402-0.0,5%,1/16W,EMPTY,G2A',
 PRIM_FILE='./archive_libs/mstr_discrete/res/chips/chips.prt';

PART_NAME
 R2T71 'RES_0402-0.0,5%,1/16W,EMPTY,G2A':;

SECTION_NUMBER 1
 '@BASEBOARD_FAB2_LIB.BASEBOARD_FAB2(SCH_1):PAGE93_I109@MSTR_DISCRETE.RES(CHIPS)':
 C_PATH='@baseboard_fab2_lib.baseboard_fab2(sch_1):page93_i109@mstr_discrete.res~
(chips)',
 P_PATH='@baseboard_fab2_lib.baseboard_fab2(sch_1):page93_i109@mstr_discrete.res~
(chips)',
 PATH='I109',
 DRAWING='@BASEBOARD_FAB2_LIB.BASEBOARD_FAB2(SCH_1):PAGE93',
 WATTAGE='1/16W',
 TOLERANCE='5%',
 SEC_TYPE='0402',
 MATERIAL='EMPTY',
 PHYS_PAGE='93',
 XY='(2025,2225)',
 ROT='0',
 VER='2',
 VALUE='0.0',
 PACK_TYPE='0402',
 PART_NUMBER='G21497-005',
 LOCATION='R2T71',
 SEC='1',
 CDS_LIB='mstr_discrete',
 CDS_PART_NAME='RES_0402-0.0,5%,1/16W,EMPTY,G2A',
 PRIM_FILE='./archive_libs/mstr_discrete/res/chips/chips.prt';

PART_NAME
 R2T72 'RES_0402-150.0,1%,1/16W,CHIP,GA':
 ROOM='PROC_SIDEBAND';

SECTION_NUMBER 1
 '@BASEBOARD_FAB2_LIB.BASEBOARD_FAB2(SCH_1):PAGE93_I143@MSTR_DISCRETE.RES(CHIPS)':
 C_PATH='@baseboard_fab2_lib.baseboard_fab2(sch_1):page93_i143@mstr_discrete.res~
(chips)',
 P_PATH='@baseboard_fab2_lib.baseboard_fab2(sch_1):page93_i143@mstr_discrete.res~
(chips)',
 PATH='I143',
 DRAWING='@BASEBOARD_FAB2_LIB.BASEBOARD_FAB2(SCH_1):PAGE93',
 WATTAGE='1/16W',
 TOLERANCE='1%',
 SEC_TYPE='0402',
 MATERIAL='CHIP',
 BOM_COST='PROC_SIDEBAND',
 PHYS_PAGE='93',
 XY='(-2475,2525)',
 ROT='0',
 VER='2',
 VALUE='150.0',
 PACK_TYPE='0402',
 PART_NUMBER='G21796-009',
 LOCATION='R2T72',
 ROOM='PROC_SIDEBAND',
 SEC='1',
 CDS_LIB='mstr_discrete',
 CDS_PART_NAME='RES_0402-150.0,1%,1/16W,CHIP,GA',
 PRIM_FILE='./archive_libs/mstr_discrete/res/chips/chips.prt';

PART_NAME
 R2T73 'RES_0402-150.0,1%,1/16W,CHIP,GA':
 ROOM='PROC_SIDEBAND';

SECTION_NUMBER 1
 '@BASEBOARD_FAB2_LIB.BASEBOARD_FAB2(SCH_1):PAGE93_I144@MSTR_DISCRETE.RES(CHIPS)':
 C_PATH='@baseboard_fab2_lib.baseboard_fab2(sch_1):page93_i144@mstr_discrete.res~
(chips)',
 P_PATH='@baseboard_fab2_lib.baseboard_fab2(sch_1):page93_i144@mstr_discrete.res~
(chips)',
 PATH='I144',
 DRAWING='@BASEBOARD_FAB2_LIB.BASEBOARD_FAB2(SCH_1):PAGE93',
 WATTAGE='1/16W',
 TOLERANCE='1%',
 SEC_TYPE='0402',
 MATERIAL='CHIP',
 BOM_COST='PROC_SIDEBAND',
 PHYS_PAGE='93',
 XY='(-1900,2500)',
 ROT='0',
 VER='2',
 VALUE='150.0',
 PACK_TYPE='0402',
 PART_NUMBER='G21796-009',
 LOCATION='R2T73',
 ROOM='PROC_SIDEBAND',
 SEC='1',
 CDS_LIB='mstr_discrete',
 CDS_PART_NAME='RES_0402-150.0,1%,1/16W,CHIP,GA',
 PRIM_FILE='./archive_libs/mstr_discrete/res/chips/chips.prt';

PART_NAME
 R2U1 'RES_0402-20.0,1%,1/16W,CHIP,G2A':
 ROOM='SMBUS';

SECTION_NUMBER 1
 '@BASEBOARD_FAB2_LIB.BASEBOARD_FAB2(SCH_1):PAGE159_I218@MSTR_DISCRETE.RES(CHIPS)':
 C_PATH='@baseboard_fab2_lib.baseboard_fab2(sch_1):page159_i218@mstr_discrete.re~
s(chips)',
 P_PATH='@baseboard_fab2_lib.baseboard_fab2(sch_1):page159_i218@mstr_discrete.re~
s(chips)',
 PATH='I218',
 DRAWING='@BASEBOARD_FAB2_LIB.BASEBOARD_FAB2(SCH_1):PAGE159',
 WATTAGE='1/16W',
 TOLERANCE='1%',
 MATERIAL='CHIP',
 BOM_COST='SM_CONTROLLER',
 PHYS_PAGE='159',
 XY='(700,3375)',
 ROT='0',
 VER='1',
 VALUE='20.0',
 PACK_TYPE='0402',
 PART_NUMBER='G21796-173',
 LOCATION='R2U1',
 ROOM='SMBUS',
 CDS_LIB='mstr_discrete',
 CDS_PART_NAME='RES_0402-20.0,1%,1/16W,CHIP,G2A',
 PRIM_FILE='./archive_libs/mstr_discrete/res/chips/chips.prt';

PART_NAME
 R2U2 'RES_0402-4.75K,1%,1/16W,CHIP,GA':
 ROOM='BMC_MISC';

SECTION_NUMBER 1
 '@BASEBOARD_FAB2_LIB.BASEBOARD_FAB2(SCH_1):PAGE156_I265@MSTR_DISCRETE.RES(CHIPS)':
 C_PATH='@baseboard_fab2_lib.baseboard_fab2(sch_1):page156_i265@mstr_discrete.re~
s(chips)',
 P_PATH='@baseboard_fab2_lib.baseboard_fab2(sch_1):page156_i265@mstr_discrete.re~
s(chips)',
 PATH='I265',
 DRAWING='@BASEBOARD_FAB2_LIB.BASEBOARD_FAB2(SCH_1):PAGE156',
 WATTAGE='1/16W',
 TOLERANCE='1%',
 SEC_TYPE='0402',
 MATERIAL='CHIP',
 BOM_COST='SM_CONTROLLER',
 PHYS_PAGE='156',
 XY='(-3825,3250)',
 ROT='0',
 VER='2',
 VALUE='4.75K',
 PACK_TYPE='0402',
 PART_NUMBER='G21796-072',
 LOCATION='R2U2',
 ROOM='BMC_MISC',
 SEC='1',
 CDS_LIB='mstr_discrete',
 CDS_PART_NAME='RES_0402-4.75K,1%,1/16W,CHIP,GA',
 PRIM_FILE='./archive_libs/mstr_discrete/res/chips/chips.prt';

PART_NAME
 R2U3 'RES_0402-665,1.0%,1/16W,CHIP,GA':
 ROOM='SMBUS';

SECTION_NUMBER 1
 '@BASEBOARD_FAB2_LIB.BASEBOARD_FAB2(SCH_1):PAGE138_I98@MSTR_DISCRETE.RES(CHIPS)':
 C_PATH='@baseboard_fab2_lib.baseboard_fab2(sch_1):page138_i98@mstr_discrete.res~
(chips)',
 P_PATH='@baseboard_fab2_lib.baseboard_fab2(sch_1):page138_i98@mstr_discrete.res~
(chips)',
 PATH='I98',
 DRAWING='@BASEBOARD_FAB2_LIB.BASEBOARD_FAB2(SCH_1):PAGE138',
 WATTAGE='1/16W',
 TOLERANCE='1.0%',
 SEC_TYPE='0402',
 MATERIAL='CHIP',
 BOM_COST='SM_CONTROLLER',
 PHYS_PAGE='138',
 XY='(-2750,2025)',
 ROT='0',
 VER='2',
 VALUE='665',
 PACK_TYPE='0402',
 PART_NUMBER='G21796-235',
 LOCATION='R2U3',
 ROOM='SMBUS',
 SEC='1',
 CDS_LIB='mstr_discrete',
 CDS_PART_NAME='RES_0402-665,1.0%,1/16W,CHIP,GA',
 PRIM_FILE='./archive_libs/mstr_discrete/res/chips/chips.prt';

PART_NAME
 R2U4 'RES_0402-4.75K,1%,1/16W,CHIP,GA':
 ROOM='BMC_MISC';

SECTION_NUMBER 1
 '@BASEBOARD_FAB2_LIB.BASEBOARD_FAB2(SCH_1):PAGE157_I367@MSTR_DISCRETE.RES(CHIPS)':
 C_PATH='@baseboard_fab2_lib.baseboard_fab2(sch_1):page157_i367@mstr_discrete.re~
s(chips)',
 P_PATH='@baseboard_fab2_lib.baseboard_fab2(sch_1):page157_i367@mstr_discrete.re~
s(chips)',
 PATH='I367',
 DRAWING='@BASEBOARD_FAB2_LIB.BASEBOARD_FAB2(SCH_1):PAGE157',
 WATTAGE='1/16W',
 TOLERANCE='1%',
 SEC_TYPE='0402',
 MATERIAL='CHIP',
 BOM_COST='SM_CONTROLLER',
 PHYS_PAGE='157',
 XY='(-4925,4025)',
 ROT='0',
 VER='1',
 VALUE='4.75K',
 PACK_TYPE='0402',
 PART_NUMBER='G21796-072',
 LOCATION='R2U4',
 ROOM='BMC_MISC',
 SEC='1',
 CDS_LIB='mstr_discrete',
 CDS_PART_NAME='RES_0402-4.75K,1%,1/16W,CHIP,GA',
 PRIM_FILE='./archive_libs/mstr_discrete/res/chips/chips.prt';

PART_NAME
 R2U5 'RES_0402-2.26K,1.0%,1/16W,CHIPA':
 ROOM='SMBUS';

SECTION_NUMBER 1
 '@BASEBOARD_FAB2_LIB.BASEBOARD_FAB2(SCH_1):PAGE159_I214@MSTR_DISCRETE.RES(CHIPS)':
 C_PATH='@baseboard_fab2_lib.baseboard_fab2(sch_1):page159_i214@mstr_discrete.re~
s(chips)',
 P_PATH='@baseboard_fab2_lib.baseboard_fab2(sch_1):page159_i214@mstr_discrete.re~
s(chips)',
 PATH='I214',
 DRAWING='@BASEBOARD_FAB2_LIB.BASEBOARD_FAB2(SCH_1):PAGE159',
 SKU='B',
 WATTAGE='1/16W',
 TOLERANCE='1.0%',
 SEC_TYPE='0402',
 MATERIAL='CHIP',
 BOM_COST='SM_CONTROLLER',
 PHYS_PAGE='159',
 XY='(550,4825)',
 ROT='0',
 VER='2',
 VALUE='2.26K',
 PACK_TYPE='0402',
 PART_NUMBER='G21796-311',
 LOCATION='R2U5',
 ROOM='SMBUS',
 SEC='1',
 CDS_LIB='mstr_discrete',
 CDS_PART_NAME='RES_0402-2.26K,1.0%,1/16W,CHIPA',
 PRIM_FILE='./archive_libs/mstr_discrete/res/chips/chips.prt';

PART_NAME
 R2U6 'RES_0402-20.0,1%,1/16W,CHIP,G2A':
 ROOM='SMBUS';

SECTION_NUMBER 1
 '@BASEBOARD_FAB2_LIB.BASEBOARD_FAB2(SCH_1):PAGE138_I166@MSTR_DISCRETE.RES(CHIPS)':
 C_PATH='@baseboard_fab2_lib.baseboard_fab2(sch_1):page138_i166@mstr_discrete.re~
s(chips)',
 P_PATH='@baseboard_fab2_lib.baseboard_fab2(sch_1):page138_i166@mstr_discrete.re~
s(chips)',
 PATH='I166',
 DRAWING='@BASEBOARD_FAB2_LIB.BASEBOARD_FAB2(SCH_1):PAGE138',
 WATTAGE='1/16W',
 TOLERANCE='1%',
 SEC_TYPE='0402',
 MATERIAL='CHIP',
 BOM_COST='SM_CONTROLLER',
 PHYS_PAGE='138',
 XY='(-3950,1625)',
 ROT='0',
 VER='1',
 VALUE='20.0',
 PACK_TYPE='0402',
 PART_NUMBER='G21796-173',
 LOCATION='R2U6',
 ROOM='SMBUS',
 SEC='1',
 CDS_LIB='mstr_discrete',
 CDS_PART_NAME='RES_0402-20.0,1%,1/16W,CHIP,G2A',
 PRIM_FILE='./archive_libs/mstr_discrete/res/chips/chips.prt';

PART_NAME
 R2U7 'RES_0402-20.0,1%,1/16W,CHIP,G2A':
 ROOM='SMBUS';

SECTION_NUMBER 1
 '@BASEBOARD_FAB2_LIB.BASEBOARD_FAB2(SCH_1):PAGE159_I220@MSTR_DISCRETE.RES(CHIPS)':
 C_PATH='@baseboard_fab2_lib.baseboard_fab2(sch_1):page159_i220@mstr_discrete.re~
s(chips)',
 P_PATH='@baseboard_fab2_lib.baseboard_fab2(sch_1):page159_i220@mstr_discrete.re~
s(chips)',
 PATH='I220',
 DRAWING='@BASEBOARD_FAB2_LIB.BASEBOARD_FAB2(SCH_1):PAGE159',
 WATTAGE='1/16W',
 TOLERANCE='1%',
 MATERIAL='CHIP',
 BOM_COST='SM_CONTROLLER',
 PHYS_PAGE='159',
 XY='(800,4275)',
 ROT='0',
 VER='1',
 VALUE='20.0',
 PACK_TYPE='0402',
 PART_NUMBER='G21796-173',
 LOCATION='R2U7',
 ROOM='SMBUS',
 CDS_LIB='mstr_discrete',
 CDS_PART_NAME='RES_0402-20.0,1%,1/16W,CHIP,G2A',
 PRIM_FILE='./archive_libs/mstr_discrete/res/chips/chips.prt';

PART_NAME
 R2U8 'RES_0402-20.0,1%,1/16W,EMPTY,GA':
 ROOM='SMBUS';

SECTION_NUMBER 1
 '@BASEBOARD_FAB2_LIB.BASEBOARD_FAB2(SCH_1):PAGE138_I158@MSTR_DISCRETE.RES(CHIPS)':
 C_PATH='@baseboard_fab2_lib.baseboard_fab2(sch_1):page138_i158@mstr_discrete.re~
s(chips)',
 P_PATH='@baseboard_fab2_lib.baseboard_fab2(sch_1):page138_i158@mstr_discrete.re~
s(chips)',
 PATH='I158',
 DRAWING='@BASEBOARD_FAB2_LIB.BASEBOARD_FAB2(SCH_1):PAGE138',
 SKU='A',
 WATTAGE='1/16W',
 TOLERANCE='1%',
 MATERIAL='EMPTY',
 BOM_COST='SM_CONTROLLER',
 PHYS_PAGE='138',
 XY='(-3100,1325)',
 ROT='0',
 VER='1',
 VALUE='20.0',
 PACK_TYPE='0402',
 PART_NUMBER='G21796-173',
 LOCATION='R2U8',
 ROOM='SMBUS',
 CDS_LIB='mstr_discrete',
 CDS_PART_NAME='RES_0402-20.0,1%,1/16W,EMPTY,GA',
 PRIM_FILE='./archive_libs/mstr_discrete/res/chips/chips.prt';

PART_NAME
 R2U9 'RES_0402-20.0,1%,1/16W,CHIP,G2A':
 ROOM='SMBUS';

SECTION_NUMBER 1
 '@BASEBOARD_FAB2_LIB.BASEBOARD_FAB2(SCH_1):PAGE138_I165@MSTR_DISCRETE.RES(CHIPS)':
 C_PATH='@baseboard_fab2_lib.baseboard_fab2(sch_1):page138_i165@mstr_discrete.re~
s(chips)',
 P_PATH='@baseboard_fab2_lib.baseboard_fab2(sch_1):page138_i165@mstr_discrete.re~
s(chips)',
 PATH='I165',
 DRAWING='@BASEBOARD_FAB2_LIB.BASEBOARD_FAB2(SCH_1):PAGE138',
 WATTAGE='1/16W',
 TOLERANCE='1%',
 SEC_TYPE='0402',
 MATERIAL='CHIP',
 BOM_COST='SM_CONTROLLER',
 PHYS_PAGE='138',
 XY='(-3950,1775)',
 ROT='0',
 VER='1',
 VALUE='20.0',
 PACK_TYPE='0402',
 PART_NUMBER='G21796-173',
 LOCATION='R2U9',
 ROOM='SMBUS',
 SEC='1',
 CDS_LIB='mstr_discrete',
 CDS_PART_NAME='RES_0402-20.0,1%,1/16W,CHIP,G2A',
 PRIM_FILE='./archive_libs/mstr_discrete/res/chips/chips.prt';

PART_NAME
 R2U10 'RES_0402-20.0,1%,1/16W,CHIP,G2A':
 ROOM='SMBUS';

SECTION_NUMBER 1
 '@BASEBOARD_FAB2_LIB.BASEBOARD_FAB2(SCH_1):PAGE159_I221@MSTR_DISCRETE.RES(CHIPS)':
 C_PATH='@baseboard_fab2_lib.baseboard_fab2(sch_1):page159_i221@mstr_discrete.re~
s(chips)',
 P_PATH='@baseboard_fab2_lib.baseboard_fab2(sch_1):page159_i221@mstr_discrete.re~
s(chips)',
 PATH='I221',
 DRAWING='@BASEBOARD_FAB2_LIB.BASEBOARD_FAB2(SCH_1):PAGE159',
 WATTAGE='1/16W',
 TOLERANCE='1%',
 MATERIAL='CHIP',
 BOM_COST='SM_CONTROLLER',
 PHYS_PAGE='159',
 XY='(800,4450)',
 ROT='0',
 VER='1',
 VALUE='20.0',
 PACK_TYPE='0402',
 PART_NUMBER='G21796-173',
 LOCATION='R2U10',
 ROOM='SMBUS',
 CDS_LIB='mstr_discrete',
 CDS_PART_NAME='RES_0402-20.0,1%,1/16W,CHIP,G2A',
 PRIM_FILE='./archive_libs/mstr_discrete/res/chips/chips.prt';

PART_NAME
 R2U11 'RES_0402-665,1.0%,1/16W,CHIP,GA':
 ROOM='SMBUS';

SECTION_NUMBER 1
 '@BASEBOARD_FAB2_LIB.BASEBOARD_FAB2(SCH_1):PAGE138_I97@MSTR_DISCRETE.RES(CHIPS)':
 C_PATH='@baseboard_fab2_lib.baseboard_fab2(sch_1):page138_i97@mstr_discrete.res~
(chips)',
 P_PATH='@baseboard_fab2_lib.baseboard_fab2(sch_1):page138_i97@mstr_discrete.res~
(chips)',
 PATH='I97',
 DRAWING='@BASEBOARD_FAB2_LIB.BASEBOARD_FAB2(SCH_1):PAGE138',
 WATTAGE='1/16W',
 TOLERANCE='1.0%',
 SEC_TYPE='0402',
 MATERIAL='CHIP',
 BOM_COST='SM_CONTROLLER',
 PHYS_PAGE='138',
 XY='(-3150,2100)',
 ROT='0',
 VER='2',
 VALUE='665',
 PACK_TYPE='0402',
 PART_NUMBER='G21796-235',
 LOCATION='R2U11',
 ROOM='SMBUS',
 SEC='1',
 CDS_LIB='mstr_discrete',
 CDS_PART_NAME='RES_0402-665,1.0%,1/16W,CHIP,GA',
 PRIM_FILE='./archive_libs/mstr_discrete/res/chips/chips.prt';

PART_NAME
 R2U12 'RES_0402-20.0,1%,1/16W,EMPTY,GA':
 ROOM='SMBUS';

SECTION_NUMBER 1
 '@BASEBOARD_FAB2_LIB.BASEBOARD_FAB2(SCH_1):PAGE138_I159@MSTR_DISCRETE.RES(CHIPS)':
 C_PATH='@baseboard_fab2_lib.baseboard_fab2(sch_1):page138_i159@mstr_discrete.re~
s(chips)',
 P_PATH='@baseboard_fab2_lib.baseboard_fab2(sch_1):page138_i159@mstr_discrete.re~
s(chips)',
 PATH='I159',
 DRAWING='@BASEBOARD_FAB2_LIB.BASEBOARD_FAB2(SCH_1):PAGE138',
 SKU='A',
 WATTAGE='1/16W',
 TOLERANCE='1%',
 MATERIAL='EMPTY',
 BOM_COST='SM_CONTROLLER',
 PHYS_PAGE='138',
 XY='(-3100,1425)',
 ROT='0',
 VER='1',
 VALUE='20.0',
 PACK_TYPE='0402',
 PART_NUMBER='G21796-173',
 LOCATION='R2U12',
 ROOM='SMBUS',
 CDS_LIB='mstr_discrete',
 CDS_PART_NAME='RES_0402-20.0,1%,1/16W,EMPTY,GA',
 PRIM_FILE='./archive_libs/mstr_discrete/res/chips/chips.prt';

PART_NAME
 R2U13 'RES_0402-2.26K,1.0%,1/16W,CHIPA':
 ROOM='SMBUS';

SECTION_NUMBER 1
 '@BASEBOARD_FAB2_LIB.BASEBOARD_FAB2(SCH_1):PAGE159_I216@MSTR_DISCRETE.RES(CHIPS)':
 C_PATH='@baseboard_fab2_lib.baseboard_fab2(sch_1):page159_i216@mstr_discrete.re~
s(chips)',
 P_PATH='@baseboard_fab2_lib.baseboard_fab2(sch_1):page159_i216@mstr_discrete.re~
s(chips)',
 PATH='I216',
 DRAWING='@BASEBOARD_FAB2_LIB.BASEBOARD_FAB2(SCH_1):PAGE159',
 SKU='B',
 WATTAGE='1/16W',
 TOLERANCE='1.0%',
 SEC_TYPE='0402',
 MATERIAL='CHIP',
 BOM_COST='SM_CONTROLLER',
 PHYS_PAGE='159',
 XY='(200,4825)',
 ROT='0',
 VER='2',
 VALUE='2.26K',
 PACK_TYPE='0402',
 PART_NUMBER='G21796-311',
 LOCATION='R2U13',
 ROOM='SMBUS',
 SEC='1',
 CDS_LIB='mstr_discrete',
 CDS_PART_NAME='RES_0402-2.26K,1.0%,1/16W,CHIPA',
 PRIM_FILE='./archive_libs/mstr_discrete/res/chips/chips.prt';

PART_NAME
 R2U14 'RES_0402-0.0,5%,1/16W,CHIP,G21A':
 GROUP='PCIE_RISER';

SECTION_NUMBER 1
 '@BASEBOARD_FAB2_LIB.BASEBOARD_FAB2(SCH_1):PAGE107_I499@MSTR_DISCRETE.RES(CHIPS)':
 C_PATH='@baseboard_fab2_lib.baseboard_fab2(sch_1):page107_i499@mstr_discrete.re~
s(chips)',
 P_PATH='@baseboard_fab2_lib.baseboard_fab2(sch_1):page107_i499@mstr_discrete.re~
s(chips)',
 PATH='I499',
 DRAWING='@BASEBOARD_FAB2_LIB.BASEBOARD_FAB2(SCH_1):PAGE107',
 WATTAGE='1/16W',
 TOLERANCE='5%',
 MATERIAL='CHIP',
 PHYS_PAGE='107',
 XY='(-800,3100)',
 ROT='1',
 VER='1',
 VALUE='0.0',
 PACK_TYPE='0402',
 PART_NUMBER='G21497-005',
 LOCATION='R2U14',
 GROUP='PCIE_RISER',
 CDS_LIB='mstr_discrete',
 CDS_PART_NAME='RES_0402-0.0,5%,1/16W,CHIP,G21A',
 PRIM_FILE='./archive_libs/mstr_discrete/res/chips/chips.prt';

PART_NAME
 R2U15 'RES_0402-0.0,5%,1/16W,CHIP,G21A':
 GROUP='PCIE_RISER';

SECTION_NUMBER 1
 '@BASEBOARD_FAB2_LIB.BASEBOARD_FAB2(SCH_1):PAGE107_I490@MSTR_DISCRETE.RES(CHIPS)':
 C_PATH='@baseboard_fab2_lib.baseboard_fab2(sch_1):page107_i490@mstr_discrete.re~
s(chips)',
 P_PATH='@baseboard_fab2_lib.baseboard_fab2(sch_1):page107_i490@mstr_discrete.re~
s(chips)',
 PATH='I490',
 DRAWING='@BASEBOARD_FAB2_LIB.BASEBOARD_FAB2(SCH_1):PAGE107',
 WATTAGE='1/16W',
 TOLERANCE='5%',
 MATERIAL='CHIP',
 PHYS_PAGE='107',
 XY='(-825,4125)',
 ROT='1',
 VER='1',
 VALUE='0.0',
 PACK_TYPE='0402',
 PART_NUMBER='G21497-005',
 LOCATION='R2U15',
 GROUP='PCIE_RISER',
 CDS_LIB='mstr_discrete',
 CDS_PART_NAME='RES_0402-0.0,5%,1/16W,CHIP,G21A',
 PRIM_FILE='./archive_libs/mstr_discrete/res/chips/chips.prt';

PART_NAME
 R2U16 'RES_0402-0.0,5%,1/16W,CHIP,G21A':
 GROUP='PCIE_RISER';

SECTION_NUMBER 1
 '@BASEBOARD_FAB2_LIB.BASEBOARD_FAB2(SCH_1):PAGE107_I501@MSTR_DISCRETE.RES(CHIPS)':
 C_PATH='@baseboard_fab2_lib.baseboard_fab2(sch_1):page107_i501@mstr_discrete.re~
s(chips)',
 P_PATH='@baseboard_fab2_lib.baseboard_fab2(sch_1):page107_i501@mstr_discrete.re~
s(chips)',
 PATH='I501',
 DRAWING='@BASEBOARD_FAB2_LIB.BASEBOARD_FAB2(SCH_1):PAGE107',
 WATTAGE='1/16W',
 TOLERANCE='5%',
 MATERIAL='CHIP',
 PHYS_PAGE='107',
 XY='(-1000,2800)',
 ROT='1',
 VER='1',
 VALUE='0.0',
 PACK_TYPE='0402',
 PART_NUMBER='G21497-005',
 LOCATION='R2U16',
 GROUP='PCIE_RISER',
 CDS_LIB='mstr_discrete',
 CDS_PART_NAME='RES_0402-0.0,5%,1/16W,CHIP,G21A',
 PRIM_FILE='./archive_libs/mstr_discrete/res/chips/chips.prt';

PART_NAME
 R2U17 'RES_0402-0.0,5%,1/16W,CHIP,G21A':
 GROUP='PCIE_RISER';

SECTION_NUMBER 1
 '@BASEBOARD_FAB2_LIB.BASEBOARD_FAB2(SCH_1):PAGE107_I492@MSTR_DISCRETE.RES(CHIPS)':
 C_PATH='@baseboard_fab2_lib.baseboard_fab2(sch_1):page107_i492@mstr_discrete.re~
s(chips)',
 P_PATH='@baseboard_fab2_lib.baseboard_fab2(sch_1):page107_i492@mstr_discrete.re~
s(chips)',
 PATH='I492',
 DRAWING='@BASEBOARD_FAB2_LIB.BASEBOARD_FAB2(SCH_1):PAGE107',
 WATTAGE='1/16W',
 TOLERANCE='5%',
 MATERIAL='CHIP',
 PHYS_PAGE='107',
 XY='(-1025,3825)',
 ROT='1',
 VER='1',
 VALUE='0.0',
 PACK_TYPE='0402',
 PART_NUMBER='G21497-005',
 LOCATION='R2U17',
 GROUP='PCIE_RISER',
 CDS_LIB='mstr_discrete',
 CDS_PART_NAME='RES_0402-0.0,5%,1/16W,CHIP,G21A',
 PRIM_FILE='./archive_libs/mstr_discrete/res/chips/chips.prt';

PART_NAME
 R2U18 'RES_0402-0.0,5%,1/16W,CHIP,G21A':
 GROUP='PCIE_RISER';

SECTION_NUMBER 1
 '@BASEBOARD_FAB2_LIB.BASEBOARD_FAB2(SCH_1):PAGE107_I502@MSTR_DISCRETE.RES(CHIPS)':
 C_PATH='@baseboard_fab2_lib.baseboard_fab2(sch_1):page107_i502@mstr_discrete.re~
s(chips)',
 P_PATH='@baseboard_fab2_lib.baseboard_fab2(sch_1):page107_i502@mstr_discrete.re~
s(chips)',
 PATH='I502',
 DRAWING='@BASEBOARD_FAB2_LIB.BASEBOARD_FAB2(SCH_1):PAGE107',
 WATTAGE='1/16W',
 TOLERANCE='5%',
 MATERIAL='CHIP',
 PHYS_PAGE='107',
 XY='(-1200,3100)',
 ROT='1',
 VER='1',
 VALUE='0.0',
 PACK_TYPE='0402',
 PART_NUMBER='G21497-005',
 LOCATION='R2U18',
 GROUP='PCIE_RISER',
 CDS_LIB='mstr_discrete',
 CDS_PART_NAME='RES_0402-0.0,5%,1/16W,CHIP,G21A',
 PRIM_FILE='./archive_libs/mstr_discrete/res/chips/chips.prt';

PART_NAME
 R2U19 'RES_0402-0.0,5%,1/16W,CHIP,G21A':
 GROUP='PCIE_RISER';

SECTION_NUMBER 1
 '@BASEBOARD_FAB2_LIB.BASEBOARD_FAB2(SCH_1):PAGE107_I493@MSTR_DISCRETE.RES(CHIPS)':
 C_PATH='@baseboard_fab2_lib.baseboard_fab2(sch_1):page107_i493@mstr_discrete.re~
s(chips)',
 P_PATH='@baseboard_fab2_lib.baseboard_fab2(sch_1):page107_i493@mstr_discrete.re~
s(chips)',
 PATH='I493',
 DRAWING='@BASEBOARD_FAB2_LIB.BASEBOARD_FAB2(SCH_1):PAGE107',
 WATTAGE='1/16W',
 TOLERANCE='5%',
 MATERIAL='CHIP',
 PHYS_PAGE='107',
 XY='(-1225,4125)',
 ROT='1',
 VER='1',
 VALUE='0.0',
 PACK_TYPE='0402',
 PART_NUMBER='G21497-005',
 LOCATION='R2U19',
 GROUP='PCIE_RISER',
 CDS_LIB='mstr_discrete',
 CDS_PART_NAME='RES_0402-0.0,5%,1/16W,CHIP,G21A',
 PRIM_FILE='./archive_libs/mstr_discrete/res/chips/chips.prt';

PART_NAME
 R2U20 'RES_0402-0.0,5%,1/16W,CHIP,G21A':
 GROUP='PCIE_RISER';

SECTION_NUMBER 1
 '@BASEBOARD_FAB2_LIB.BASEBOARD_FAB2(SCH_1):PAGE107_I503@MSTR_DISCRETE.RES(CHIPS)':
 C_PATH='@baseboard_fab2_lib.baseboard_fab2(sch_1):page107_i503@mstr_discrete.re~
s(chips)',
 P_PATH='@baseboard_fab2_lib.baseboard_fab2(sch_1):page107_i503@mstr_discrete.re~
s(chips)',
 PATH='I503',
 DRAWING='@BASEBOARD_FAB2_LIB.BASEBOARD_FAB2(SCH_1):PAGE107',
 WATTAGE='1/16W',
 TOLERANCE='5%',
 MATERIAL='CHIP',
 PHYS_PAGE='107',
 XY='(-1400,2800)',
 ROT='1',
 VER='1',
 VALUE='0.0',
 PACK_TYPE='0402',
 PART_NUMBER='G21497-005',
 LOCATION='R2U20',
 GROUP='PCIE_RISER',
 CDS_LIB='mstr_discrete',
 CDS_PART_NAME='RES_0402-0.0,5%,1/16W,CHIP,G21A',
 PRIM_FILE='./archive_libs/mstr_discrete/res/chips/chips.prt';

PART_NAME
 R2U21 'RES_0402-0.0,5%,1/16W,CHIP,G21A':
 GROUP='PCIE_RISER';

SECTION_NUMBER 1
 '@BASEBOARD_FAB2_LIB.BASEBOARD_FAB2(SCH_1):PAGE107_I491@MSTR_DISCRETE.RES(CHIPS)':
 C_PATH='@baseboard_fab2_lib.baseboard_fab2(sch_1):page107_i491@mstr_discrete.re~
s(chips)',
 P_PATH='@baseboard_fab2_lib.baseboard_fab2(sch_1):page107_i491@mstr_discrete.re~
s(chips)',
 PATH='I491',
 DRAWING='@BASEBOARD_FAB2_LIB.BASEBOARD_FAB2(SCH_1):PAGE107',
 WATTAGE='1/16W',
 TOLERANCE='5%',
 MATERIAL='CHIP',
 PHYS_PAGE='107',
 XY='(-1425,3825)',
 ROT='1',
 VER='1',
 VALUE='0.0',
 PACK_TYPE='0402',
 PART_NUMBER='G21497-005',
 LOCATION='R2U21',
 GROUP='PCIE_RISER',
 CDS_LIB='mstr_discrete',
 CDS_PART_NAME='RES_0402-0.0,5%,1/16W,CHIP,G21A',
 PRIM_FILE='./archive_libs/mstr_discrete/res/chips/chips.prt';

PART_NAME
 R2U22 'RES_0402-0.0,5%,1/16W,CHIP,G21A':
 GROUP='PCIE_RISER';

SECTION_NUMBER 1
 '@BASEBOARD_FAB2_LIB.BASEBOARD_FAB2(SCH_1):PAGE107_I504@MSTR_DISCRETE.RES(CHIPS)':
 C_PATH='@baseboard_fab2_lib.baseboard_fab2(sch_1):page107_i504@mstr_discrete.re~
s(chips)',
 P_PATH='@baseboard_fab2_lib.baseboard_fab2(sch_1):page107_i504@mstr_discrete.re~
s(chips)',
 PATH='I504',
 DRAWING='@BASEBOARD_FAB2_LIB.BASEBOARD_FAB2(SCH_1):PAGE107',
 WATTAGE='1/16W',
 TOLERANCE='5%',
 MATERIAL='CHIP',
 PHYS_PAGE='107',
 XY='(-1600,3100)',
 ROT='1',
 VER='1',
 VALUE='0.0',
 PACK_TYPE='0402',
 PART_NUMBER='G21497-005',
 LOCATION='R2U22',
 GROUP='PCIE_RISER',
 CDS_LIB='mstr_discrete',
 CDS_PART_NAME='RES_0402-0.0,5%,1/16W,CHIP,G21A',
 PRIM_FILE='./archive_libs/mstr_discrete/res/chips/chips.prt';

PART_NAME
 R2U23 'RES_0402-0.0,5%,1/16W,CHIP,G21A':
 GROUP='PCIE_RISER';

SECTION_NUMBER 1
 '@BASEBOARD_FAB2_LIB.BASEBOARD_FAB2(SCH_1):PAGE107_I495@MSTR_DISCRETE.RES(CHIPS)':
 C_PATH='@baseboard_fab2_lib.baseboard_fab2(sch_1):page107_i495@mstr_discrete.re~
s(chips)',
 P_PATH='@baseboard_fab2_lib.baseboard_fab2(sch_1):page107_i495@mstr_discrete.re~
s(chips)',
 PATH='I495',
 DRAWING='@BASEBOARD_FAB2_LIB.BASEBOARD_FAB2(SCH_1):PAGE107',
 WATTAGE='1/16W',
 TOLERANCE='5%',
 MATERIAL='CHIP',
 PHYS_PAGE='107',
 XY='(-1625,4125)',
 ROT='1',
 VER='1',
 VALUE='0.0',
 PACK_TYPE='0402',
 PART_NUMBER='G21497-005',
 LOCATION='R2U23',
 GROUP='PCIE_RISER',
 CDS_LIB='mstr_discrete',
 CDS_PART_NAME='RES_0402-0.0,5%,1/16W,CHIP,G21A',
 PRIM_FILE='./archive_libs/mstr_discrete/res/chips/chips.prt';

PART_NAME
 R2U24 'RES_0402-0.0,5%,1/16W,CHIP,G21A':
 GROUP='PCIE_RISER';

SECTION_NUMBER 1
 '@BASEBOARD_FAB2_LIB.BASEBOARD_FAB2(SCH_1):PAGE107_I505@MSTR_DISCRETE.RES(CHIPS)':
 C_PATH='@baseboard_fab2_lib.baseboard_fab2(sch_1):page107_i505@mstr_discrete.re~
s(chips)',
 P_PATH='@baseboard_fab2_lib.baseboard_fab2(sch_1):page107_i505@mstr_discrete.re~
s(chips)',
 PATH='I505',
 DRAWING='@BASEBOARD_FAB2_LIB.BASEBOARD_FAB2(SCH_1):PAGE107',
 WATTAGE='1/16W',
 TOLERANCE='5%',
 MATERIAL='CHIP',
 PHYS_PAGE='107',
 XY='(-1800,2800)',
 ROT='1',
 VER='1',
 VALUE='0.0',
 PACK_TYPE='0402',
 PART_NUMBER='G21497-005',
 LOCATION='R2U24',
 GROUP='PCIE_RISER',
 CDS_LIB='mstr_discrete',
 CDS_PART_NAME='RES_0402-0.0,5%,1/16W,CHIP,G21A',
 PRIM_FILE='./archive_libs/mstr_discrete/res/chips/chips.prt';

PART_NAME
 R2U25 'RES_0402-0.0,5%,1/16W,CHIP,G21A':
 GROUP='PCIE_RISER';

SECTION_NUMBER 1
 '@BASEBOARD_FAB2_LIB.BASEBOARD_FAB2(SCH_1):PAGE107_I496@MSTR_DISCRETE.RES(CHIPS)':
 C_PATH='@baseboard_fab2_lib.baseboard_fab2(sch_1):page107_i496@mstr_discrete.re~
s(chips)',
 P_PATH='@baseboard_fab2_lib.baseboard_fab2(sch_1):page107_i496@mstr_discrete.re~
s(chips)',
 PATH='I496',
 DRAWING='@BASEBOARD_FAB2_LIB.BASEBOARD_FAB2(SCH_1):PAGE107',
 WATTAGE='1/16W',
 TOLERANCE='5%',
 MATERIAL='CHIP',
 PHYS_PAGE='107',
 XY='(-1825,3825)',
 ROT='1',
 VER='1',
 VALUE='0.0',
 PACK_TYPE='0402',
 PART_NUMBER='G21497-005',
 LOCATION='R2U25',
 GROUP='PCIE_RISER',
 CDS_LIB='mstr_discrete',
 CDS_PART_NAME='RES_0402-0.0,5%,1/16W,CHIP,G21A',
 PRIM_FILE='./archive_libs/mstr_discrete/res/chips/chips.prt';

PART_NAME
 R2U26 'RES_0402-0.0,5%,1/16W,CHIP,G21A':
 GROUP='PCIE_RISER';

SECTION_NUMBER 1
 '@BASEBOARD_FAB2_LIB.BASEBOARD_FAB2(SCH_1):PAGE107_I498@MSTR_DISCRETE.RES(CHIPS)':
 C_PATH='@baseboard_fab2_lib.baseboard_fab2(sch_1):page107_i498@mstr_discrete.re~
s(chips)',
 P_PATH='@baseboard_fab2_lib.baseboard_fab2(sch_1):page107_i498@mstr_discrete.re~
s(chips)',
 PATH='I498',
 DRAWING='@BASEBOARD_FAB2_LIB.BASEBOARD_FAB2(SCH_1):PAGE107',
 WATTAGE='1/16W',
 TOLERANCE='5%',
 MATERIAL='CHIP',
 PHYS_PAGE='107',
 XY='(-2000,3100)',
 ROT='1',
 VER='1',
 VALUE='0.0',
 PACK_TYPE='0402',
 PART_NUMBER='G21497-005',
 LOCATION='R2U26',
 GROUP='PCIE_RISER',
 CDS_LIB='mstr_discrete',
 CDS_PART_NAME='RES_0402-0.0,5%,1/16W,CHIP,G21A',
 PRIM_FILE='./archive_libs/mstr_discrete/res/chips/chips.prt';

PART_NAME
 R2U27 'RES_0402-0.0,5%,1/16W,CHIP,G21A':
 GROUP='PCIE_RISER';

SECTION_NUMBER 1
 '@BASEBOARD_FAB2_LIB.BASEBOARD_FAB2(SCH_1):PAGE107_I497@MSTR_DISCRETE.RES(CHIPS)':
 C_PATH='@baseboard_fab2_lib.baseboard_fab2(sch_1):page107_i497@mstr_discrete.re~
s(chips)',
 P_PATH='@baseboard_fab2_lib.baseboard_fab2(sch_1):page107_i497@mstr_discrete.re~
s(chips)',
 PATH='I497',
 DRAWING='@BASEBOARD_FAB2_LIB.BASEBOARD_FAB2(SCH_1):PAGE107',
 WATTAGE='1/16W',
 TOLERANCE='5%',
 MATERIAL='CHIP',
 PHYS_PAGE='107',
 XY='(-2025,4125)',
 ROT='1',
 VER='1',
 VALUE='0.0',
 PACK_TYPE='0402',
 PART_NUMBER='G21497-005',
 LOCATION='R2U27',
 GROUP='PCIE_RISER',
 CDS_LIB='mstr_discrete',
 CDS_PART_NAME='RES_0402-0.0,5%,1/16W,CHIP,G21A',
 PRIM_FILE='./archive_libs/mstr_discrete/res/chips/chips.prt';

PART_NAME
 R2U28 'RES_0402-0.0,5%,1/16W,CHIP,G21A':
 GROUP='PCIE_RISER';

SECTION_NUMBER 1
 '@BASEBOARD_FAB2_LIB.BASEBOARD_FAB2(SCH_1):PAGE107_I500@MSTR_DISCRETE.RES(CHIPS)':
 C_PATH='@baseboard_fab2_lib.baseboard_fab2(sch_1):page107_i500@mstr_discrete.re~
s(chips)',
 P_PATH='@baseboard_fab2_lib.baseboard_fab2(sch_1):page107_i500@mstr_discrete.re~
s(chips)',
 PATH='I500',
 DRAWING='@BASEBOARD_FAB2_LIB.BASEBOARD_FAB2(SCH_1):PAGE107',
 WATTAGE='1/16W',
 TOLERANCE='5%',
 MATERIAL='CHIP',
 PHYS_PAGE='107',
 XY='(-2200,2800)',
 ROT='1',
 VER='1',
 VALUE='0.0',
 PACK_TYPE='0402',
 PART_NUMBER='G21497-005',
 LOCATION='R2U28',
 GROUP='PCIE_RISER',
 CDS_LIB='mstr_discrete',
 CDS_PART_NAME='RES_0402-0.0,5%,1/16W,CHIP,G21A',
 PRIM_FILE='./archive_libs/mstr_discrete/res/chips/chips.prt';

PART_NAME
 R2U29 'RES_0402-0.0,5%,1/16W,CHIP,G21A':
 GROUP='PCIE_RISER';

SECTION_NUMBER 1
 '@BASEBOARD_FAB2_LIB.BASEBOARD_FAB2(SCH_1):PAGE107_I494@MSTR_DISCRETE.RES(CHIPS)':
 C_PATH='@baseboard_fab2_lib.baseboard_fab2(sch_1):page107_i494@mstr_discrete.re~
s(chips)',
 P_PATH='@baseboard_fab2_lib.baseboard_fab2(sch_1):page107_i494@mstr_discrete.re~
s(chips)',
 PATH='I494',
 DRAWING='@BASEBOARD_FAB2_LIB.BASEBOARD_FAB2(SCH_1):PAGE107',
 WATTAGE='1/16W',
 TOLERANCE='5%',
 MATERIAL='CHIP',
 PHYS_PAGE='107',
 XY='(-2225,3825)',
 ROT='1',
 VER='1',
 VALUE='0.0',
 PACK_TYPE='0402',
 PART_NUMBER='G21497-005',
 LOCATION='R2U29',
 GROUP='PCIE_RISER',
 CDS_LIB='mstr_discrete',
 CDS_PART_NAME='RES_0402-0.0,5%,1/16W,CHIP,G21A',
 PRIM_FILE='./archive_libs/mstr_discrete/res/chips/chips.prt';

PART_NAME
 R2U30 'RES_0402-4.75K,1%,1/16W,EMPTY,A':
 ROOM='DB1200ZL';

SECTION_NUMBER 1
 '@BASEBOARD_FAB2_LIB.BASEBOARD_FAB2(SCH_1):PAGE125_I88@MSTR_DISCRETE.RES(CHIPS)':
 C_PATH='@baseboard_fab2_lib.baseboard_fab2(sch_1):page125_i88@mstr_discrete.res~
(chips)',
 P_PATH='@baseboard_fab2_lib.baseboard_fab2(sch_1):page125_i88@mstr_discrete.res~
(chips)',
 PATH='I88',
 DRAWING='@BASEBOARD_FAB2_LIB.BASEBOARD_FAB2(SCH_1):PAGE125',
 WATTAGE='1/16W',
 TOLERANCE='1%',
 SEC_TYPE='0402',
 MATERIAL='EMPTY',
 BOM_COST='SYS_CLOCK',
 PHYS_PAGE='125',
 XY='(-3350,1375)',
 ROT='2',
 VER='2',
 VALUE='4.75K',
 PACK_TYPE='0402',
 PART_NUMBER='G21796-072',
 LOCATION='R2U30',
 ROOM='DB1200ZL',
 SEC='1',
 CDS_LIB='mstr_discrete',
 CDS_PART_NAME='RES_0402-4.75K,1%,1/16W,EMPTY,A',
 PRIM_FILE='./archive_libs/mstr_discrete/res/chips/chips.prt';

PART_NAME
 R2U31 'RES_0402-20.0,1%,1/16W,CHIP,G2A':
 ROOM='SMBUS';

SECTION_NUMBER 1
 '@BASEBOARD_FAB2_LIB.BASEBOARD_FAB2(SCH_1):PAGE108_I330@MSTR_DISCRETE.RES(CHIPS)':
 C_PATH='@baseboard_fab2_lib.baseboard_fab2(sch_1):page108_i330@mstr_discrete.re~
s(chips)',
 P_PATH='@baseboard_fab2_lib.baseboard_fab2(sch_1):page108_i330@mstr_discrete.re~
s(chips)',
 PATH='I330',
 DRAWING='@BASEBOARD_FAB2_LIB.BASEBOARD_FAB2(SCH_1):PAGE108',
 SKU='B',
 WATTAGE='1/16W',
 TOLERANCE='1%',
 MATERIAL='CHIP',
 BOM_COST='SM_CONTROLLER',
 PHYS_PAGE='108',
 XY='(-2275,4500)',
 ROT='0',
 VER='1',
 VALUE='20.0',
 PACK_TYPE='0402',
 PART_NUMBER='G21796-173',
 LOCATION='R2U31',
 ROOM='SMBUS',
 CDS_LIB='mstr_discrete',
 CDS_PART_NAME='RES_0402-20.0,1%,1/16W,CHIP,G2A',
 PRIM_FILE='./archive_libs/mstr_discrete/res/chips/chips.prt';

PART_NAME
 R2U32 'RES_0402-20.0,1%,1/16W,CHIP,G2A':
 ROOM='SMBUS';

SECTION_NUMBER 1
 '@BASEBOARD_FAB2_LIB.BASEBOARD_FAB2(SCH_1):PAGE108_I339@MSTR_DISCRETE.RES(CHIPS)':
 C_PATH='@baseboard_fab2_lib.baseboard_fab2(sch_1):page108_i339@mstr_discrete.re~
s(chips)',
 P_PATH='@baseboard_fab2_lib.baseboard_fab2(sch_1):page108_i339@mstr_discrete.re~
s(chips)',
 PATH='I339',
 DRAWING='@BASEBOARD_FAB2_LIB.BASEBOARD_FAB2(SCH_1):PAGE108',
 SKU='B',
 WATTAGE='1/16W',
 TOLERANCE='1%',
 MATERIAL='CHIP',
 BOM_COST='SM_CONTROLLER',
 PHYS_PAGE='108',
 XY='(-2275,4250)',
 ROT='0',
 VER='1',
 VALUE='20.0',
 PACK_TYPE='0402',
 PART_NUMBER='G21796-173',
 LOCATION='R2U32',
 ROOM='SMBUS',
 CDS_LIB='mstr_discrete',
 CDS_PART_NAME='RES_0402-20.0,1%,1/16W,CHIP,G2A',
 PRIM_FILE='./archive_libs/mstr_discrete/res/chips/chips.prt';

PART_NAME
 R2U33 'RES_0402-20.0,1%,1/16W,CHIP,G2A':
 ROOM='SMBUS';

SECTION_NUMBER 1
 '@BASEBOARD_FAB2_LIB.BASEBOARD_FAB2(SCH_1):PAGE159_I231@MSTR_DISCRETE.RES(CHIPS)':
 C_PATH='@baseboard_fab2_lib.baseboard_fab2(sch_1):page159_i231@mstr_discrete.re~
s(chips)',
 P_PATH='@baseboard_fab2_lib.baseboard_fab2(sch_1):page159_i231@mstr_discrete.re~
s(chips)',
 PATH='I231',
 DRAWING='@BASEBOARD_FAB2_LIB.BASEBOARD_FAB2(SCH_1):PAGE159',
 WATTAGE='1/16W',
 TOLERANCE='1%',
 MATERIAL='CHIP',
 BOM_COST='SM_CONTROLLER',
 PHYS_PAGE='159',
 XY='(-3175,3775)',
 ROT='0',
 VER='1',
 VALUE='20.0',
 PACK_TYPE='0402',
 PART_NUMBER='G21796-173',
 LOCATION='R2U33',
 ROOM='SMBUS',
 CDS_LIB='mstr_discrete',
 CDS_PART_NAME='RES_0402-20.0,1%,1/16W,CHIP,G2A',
 PRIM_FILE='./archive_libs/mstr_discrete/res/chips/chips.prt';

PART_NAME
 R2U34 'RES_0402-20.0,1%,1/16W,CHIP,G2A':
 ROOM='SMBUS';

SECTION_NUMBER 1
 '@BASEBOARD_FAB2_LIB.BASEBOARD_FAB2(SCH_1):PAGE159_I230@MSTR_DISCRETE.RES(CHIPS)':
 C_PATH='@baseboard_fab2_lib.baseboard_fab2(sch_1):page159_i230@mstr_discrete.re~
s(chips)',
 P_PATH='@baseboard_fab2_lib.baseboard_fab2(sch_1):page159_i230@mstr_discrete.re~
s(chips)',
 PATH='I230',
 DRAWING='@BASEBOARD_FAB2_LIB.BASEBOARD_FAB2(SCH_1):PAGE159',
 WATTAGE='1/16W',
 TOLERANCE='1%',
 MATERIAL='CHIP',
 BOM_COST='SM_CONTROLLER',
 PHYS_PAGE='159',
 XY='(-3175,3600)',
 ROT='0',
 VER='1',
 VALUE='20.0',
 PACK_TYPE='0402',
 PART_NUMBER='G21796-173',
 LOCATION='R2U34',
 ROOM='SMBUS',
 CDS_LIB='mstr_discrete',
 CDS_PART_NAME='RES_0402-20.0,1%,1/16W,CHIP,G2A',
 PRIM_FILE='./archive_libs/mstr_discrete/res/chips/chips.prt';

PART_NAME
 R2U35 'RES_0402-20.0,1%,1/16W,EMPTY,GA':
 ROOM='SMBUS';

SECTION_NUMBER 1
 '@BASEBOARD_FAB2_LIB.BASEBOARD_FAB2(SCH_1):PAGE108_I350@MSTR_DISCRETE.RES(CHIPS)':
 C_PATH='@baseboard_fab2_lib.baseboard_fab2(sch_1):page108_i350@mstr_discrete.re~
s(chips)',
 P_PATH='@baseboard_fab2_lib.baseboard_fab2(sch_1):page108_i350@mstr_discrete.re~
s(chips)',
 PATH='I350',
 DRAWING='@BASEBOARD_FAB2_LIB.BASEBOARD_FAB2(SCH_1):PAGE108',
 SKU='A',
 WATTAGE='1/16W',
 TOLERANCE='1%',
 MATERIAL='EMPTY',
 BOM_COST='SM_CONTROLLER',
 PHYS_PAGE='108',
 XY='(-2275,4625)',
 ROT='0',
 VER='1',
 VALUE='20.0',
 PACK_TYPE='0402',
 PART_NUMBER='G21796-173',
 LOCATION='R2U35',
 ROOM='SMBUS',
 CDS_LIB='mstr_discrete',
 CDS_PART_NAME='RES_0402-20.0,1%,1/16W,EMPTY,GA',
 PRIM_FILE='./archive_libs/mstr_discrete/res/chips/chips.prt';

PART_NAME
 R2U36 'RES_0402-20.0,1%,1/16W,EMPTY,GA':
 ROOM='SMBUS';

SECTION_NUMBER 1
 '@BASEBOARD_FAB2_LIB.BASEBOARD_FAB2(SCH_1):PAGE108_I351@MSTR_DISCRETE.RES(CHIPS)':
 C_PATH='@baseboard_fab2_lib.baseboard_fab2(sch_1):page108_i351@mstr_discrete.re~
s(chips)',
 P_PATH='@baseboard_fab2_lib.baseboard_fab2(sch_1):page108_i351@mstr_discrete.re~
s(chips)',
 PATH='I351',
 DRAWING='@BASEBOARD_FAB2_LIB.BASEBOARD_FAB2(SCH_1):PAGE108',
 SKU='A',
 WATTAGE='1/16W',
 TOLERANCE='1%',
 MATERIAL='EMPTY',
 BOM_COST='SM_CONTROLLER',
 PHYS_PAGE='108',
 XY='(-2275,4375)',
 ROT='0',
 VER='1',
 VALUE='20.0',
 PACK_TYPE='0402',
 PART_NUMBER='G21796-173',
 LOCATION='R2U36',
 ROOM='SMBUS',
 CDS_LIB='mstr_discrete',
 CDS_PART_NAME='RES_0402-20.0,1%,1/16W,EMPTY,GA',
 PRIM_FILE='./archive_libs/mstr_discrete/res/chips/chips.prt';

PART_NAME
 R2U37 'RES_0402-0.0,5%,1/16W,CHIP,G21A':
 ROOM='IO_SLOT';

SECTION_NUMBER 1
 '@BASEBOARD_FAB2_LIB.BASEBOARD_FAB2(SCH_1):PAGE108_I173@MSTR_DISCRETE.RES(CHIPS)':
 C_PATH='@baseboard_fab2_lib.baseboard_fab2(sch_1):page108_i173@mstr_discrete.re~
s(chips)',
 P_PATH='@baseboard_fab2_lib.baseboard_fab2(sch_1):page108_i173@mstr_discrete.re~
s(chips)',
 PATH='I173',
 DRAWING='@BASEBOARD_FAB2_LIB.BASEBOARD_FAB2(SCH_1):PAGE108',
 WATTAGE='1/16W',
 TOLERANCE='5%',
 SEC_TYPE='0402',
 MATERIAL='CHIP',
 PHYS_PAGE='108',
 XY='(-1100,3625)',
 ROT='0',
 VER='1',
 VALUE='0.0',
 PACK_TYPE='0402',
 PART_NUMBER='G21497-005',
 LOCATION='R2U37',
 ROOM='IO_SLOT',
 SEC='1',
 CDS_LIB='mstr_discrete',
 CDS_PART_NAME='RES_0402-0.0,5%,1/16W,CHIP,G21A',
 PRIM_FILE='./archive_libs/mstr_discrete/res/chips/chips.prt';

PART_NAME
 R2U38 'RES_0402-665,1.0%,1/16W,CHIP,GA':
 ROOM='SMBUS';

SECTION_NUMBER 1
 '@BASEBOARD_FAB2_LIB.BASEBOARD_FAB2(SCH_1):PAGE167_I80@MSTR_DISCRETE.RES(CHIPS)':
 C_PATH='@baseboard_fab2_lib.baseboard_fab2(sch_1):page167_i80@mstr_discrete.res~
(chips)',
 P_PATH='@baseboard_fab2_lib.baseboard_fab2(sch_1):page167_i80@mstr_discrete.res~
(chips)',
 PATH='I80',
 DRAWING='@BASEBOARD_FAB2_LIB.BASEBOARD_FAB2(SCH_1):PAGE167',
 WATTAGE='1/16W',
 TOLERANCE='1.0%',
 SEC_TYPE='0402',
 MATERIAL='CHIP',
 BOM_COST='SM_CONTROLLER',
 PHYS_PAGE='167',
 XY='(-6075,1950)',
 ROT='0',
 VER='2',
 VALUE='665',
 PACK_TYPE='0402',
 PART_NUMBER='G21796-235',
 LOCATION='R2U38',
 ROOM='SMBUS',
 SEC='1',
 CDS_LIB='mstr_discrete',
 CDS_PART_NAME='RES_0402-665,1.0%,1/16W,CHIP,GA',
 PRIM_FILE='./archive_libs/mstr_discrete/res/chips/chips.prt';

PART_NAME
 R2U39 'RES_0402-665,1.0%,1/16W,CHIP,GA':
 ROOM='SMBUS';

SECTION_NUMBER 1
 '@BASEBOARD_FAB2_LIB.BASEBOARD_FAB2(SCH_1):PAGE167_I83@MSTR_DISCRETE.RES(CHIPS)':
 C_PATH='@baseboard_fab2_lib.baseboard_fab2(sch_1):page167_i83@mstr_discrete.res~
(chips)',
 P_PATH='@baseboard_fab2_lib.baseboard_fab2(sch_1):page167_i83@mstr_discrete.res~
(chips)',
 PATH='I83',
 DRAWING='@BASEBOARD_FAB2_LIB.BASEBOARD_FAB2(SCH_1):PAGE167',
 WATTAGE='1/16W',
 TOLERANCE='1.0%',
 SEC_TYPE='0402',
 MATERIAL='CHIP',
 BOM_COST='SM_CONTROLLER',
 PHYS_PAGE='167',
 XY='(-6425,1950)',
 ROT='0',
 VER='2',
 VALUE='665',
 PACK_TYPE='0402',
 PART_NUMBER='G21796-235',
 LOCATION='R2U39',
 ROOM='SMBUS',
 SEC='1',
 CDS_LIB='mstr_discrete',
 CDS_PART_NAME='RES_0402-665,1.0%,1/16W,CHIP,GA',
 PRIM_FILE='./archive_libs/mstr_discrete/res/chips/chips.prt';

PART_NAME
 R2U40 'RES_0402-150.0,1%,1/16W,CHIP,GA':
 ROOM='PROC_SIDEBAND';

SECTION_NUMBER 1
 '@BASEBOARD_FAB2_LIB.BASEBOARD_FAB2(SCH_1):PAGE152_I53@MSTR_DISCRETE.RES(CHIPS)':
 C_PATH='@baseboard_fab2_lib.baseboard_fab2(sch_1):page152_i53@mstr_discrete.res~
(chips)',
 P_PATH='@baseboard_fab2_lib.baseboard_fab2(sch_1):page152_i53@mstr_discrete.res~
(chips)',
 PATH='I53',
 DRAWING='@BASEBOARD_FAB2_LIB.BASEBOARD_FAB2(SCH_1):PAGE152',
 WATTAGE='1/16W',
 TOLERANCE='1%',
 SEC_TYPE='0402',
 MATERIAL='CHIP',
 BOM_COST='PROC_SIDEBAND',
 PHYS_PAGE='152',
 XY='(-7875,4650)',
 ROT='0',
 VER='2',
 VALUE='150.0',
 PACK_TYPE='0402',
 PART_NUMBER='G21796-009',
 LOCATION='R2U40',
 ROOM='PROC_SIDEBAND',
 SEC='1',
 CDS_LIB='mstr_discrete',
 CDS_PART_NAME='RES_0402-150.0,1%,1/16W,CHIP,GA',
 PRIM_FILE='./archive_libs/mstr_discrete/res/chips/chips.prt';

PART_NAME
 R2U41 'RES_0402-150.0,1%,1/16W,CHIP,GA':
 ROOM='PROC_SIDEBAND';

SECTION_NUMBER 1
 '@BASEBOARD_FAB2_LIB.BASEBOARD_FAB2(SCH_1):PAGE152_I54@MSTR_DISCRETE.RES(CHIPS)':
 C_PATH='@baseboard_fab2_lib.baseboard_fab2(sch_1):page152_i54@mstr_discrete.res~
(chips)',
 P_PATH='@baseboard_fab2_lib.baseboard_fab2(sch_1):page152_i54@mstr_discrete.res~
(chips)',
 PATH='I54',
 DRAWING='@BASEBOARD_FAB2_LIB.BASEBOARD_FAB2(SCH_1):PAGE152',
 WATTAGE='1/16W',
 TOLERANCE='1%',
 SEC_TYPE='0402',
 MATERIAL='CHIP',
 BOM_COST='PROC_SIDEBAND',
 PHYS_PAGE='152',
 XY='(-7975,4650)',
 ROT='2',
 VER='2',
 VALUE='150.0',
 PACK_TYPE='0402',
 PART_NUMBER='G21796-009',
 LOCATION='R2U41',
 ROOM='PROC_SIDEBAND',
 SEC='1',
 CDS_LIB='mstr_discrete',
 CDS_PART_NAME='RES_0402-150.0,1%,1/16W,CHIP,GA',
 PRIM_FILE='./archive_libs/mstr_discrete/res/chips/chips.prt';

PART_NAME
 R2U42 'RES_0402-221,1.0%,1/16W,CHIP,GA':
 ROOM='CPU_FANS';

SECTION_NUMBER 1
 '@BASEBOARD_FAB2_LIB.BASEBOARD_FAB2(SCH_1):PAGE161_I99@MSTR_DISCRETE.RES(CHIPS)':
 C_PATH='@baseboard_fab2_lib.baseboard_fab2(sch_1):page161_i99@mstr_discrete.res~
(chips)',
 P_PATH='@baseboard_fab2_lib.baseboard_fab2(sch_1):page161_i99@mstr_discrete.res~
(chips)',
 PATH='I99',
 DRAWING='@BASEBOARD_FAB2_LIB.BASEBOARD_FAB2(SCH_1):PAGE161',
 WATTAGE='1/16W',
 TOLERANCE='1.0%',
 SEC_TYPE='0402',
 MATERIAL='CHIP',
 BOM_COST='SM_THERM',
 PHYS_PAGE='161',
 XY='(-5450,3850)',
 ROT='0',
 VER='1',
 VALUE='221',
 PACK_TYPE='0402',
 PART_NUMBER='G21796-271',
 LOCATION='R2U42',
 ROOM='CPU_FANS',
 SEC='1',
 CDS_LIB='mstr_discrete',
 CDS_PART_NAME='RES_0402-221,1.0%,1/16W,CHIP,GA',
 PRIM_FILE='./archive_libs/mstr_discrete/res/chips/chips.prt';

PART_NAME
 R2U43 'RES_0402-1.00K,1%,1/16W,CHIP,GA':
 ROOM='SB_VRD';

SECTION_NUMBER 1
 '@BASEBOARD_FAB2_LIB.BASEBOARD_FAB2(SCH_1):PAGE196_I46@MSTR_DISCRETE.RES(CHIPS)':
 C_PATH='@baseboard_fab2_lib.baseboard_fab2(sch_1):page196_i46@mstr_discrete.res~
(chips)',
 P_PATH='@baseboard_fab2_lib.baseboard_fab2(sch_1):page196_i46@mstr_discrete.res~
(chips)',
 PATH='I46',
 DRAWING='@BASEBOARD_FAB2_LIB.BASEBOARD_FAB2(SCH_1):PAGE196',
 WATTAGE='1/16W',
 TOLERANCE='1%',
 SEC_TYPE='0402',
 MATERIAL='CHIP',
 BOM_COST='SB',
 PHYS_PAGE='196',
 XY='(-3650,4550)',
 ROT='0',
 VER='1',
 VALUE='1.00K',
 PACK_TYPE='0402',
 PART_NUMBER='G21796-026',
 LOCATION='R2U43',
 ROOM='SB_VRD',
 SEC='1',
 CDS_LIB='mstr_discrete',
 CDS_PART_NAME='RES_0402-1.00K,1%,1/16W,CHIP,GA',
 PRIM_FILE='./archive_libs/mstr_discrete/res/chips/chips.prt';

PART_NAME
 R2U44 'RES_0402-221,1.0%,1/16W,CHIP,GA':
 ROOM='CPU_FANS';

SECTION_NUMBER 1
 '@BASEBOARD_FAB2_LIB.BASEBOARD_FAB2(SCH_1):PAGE161_I102@MSTR_DISCRETE.RES(CHIPS)':
 C_PATH='@baseboard_fab2_lib.baseboard_fab2(sch_1):page161_i102@mstr_discrete.re~
s(chips)',
 P_PATH='@baseboard_fab2_lib.baseboard_fab2(sch_1):page161_i102@mstr_discrete.re~
s(chips)',
 PATH='I102',
 DRAWING='@BASEBOARD_FAB2_LIB.BASEBOARD_FAB2(SCH_1):PAGE161',
 WATTAGE='1/16W',
 TOLERANCE='1.0%',
 SEC_TYPE='0402',
 MATERIAL='CHIP',
 BOM_COST='SM_THERM',
 PHYS_PAGE='161',
 XY='(-5600,1100)',
 ROT='0',
 VER='1',
 VALUE='221',
 PACK_TYPE='0402',
 PART_NUMBER='G21796-271',
 LOCATION='R2U44',
 ROOM='CPU_FANS',
 SEC='1',
 CDS_LIB='mstr_discrete',
 CDS_PART_NAME='RES_0402-221,1.0%,1/16W,CHIP,GA',
 PRIM_FILE='./archive_libs/mstr_discrete/res/chips/chips.prt';

PART_NAME
 R2U45 'RES_0402-0.0,5%,1/16W,EMPTY,G2A':;

SECTION_NUMBER 1
 '@BASEBOARD_FAB2_LIB.BASEBOARD_FAB2(SCH_1):PAGE152_I102@MSTR_DISCRETE.RES(CHIPS)':
 C_PATH='@baseboard_fab2_lib.baseboard_fab2(sch_1):page152_i102@mstr_discrete.re~
s(chips)',
 P_PATH='@baseboard_fab2_lib.baseboard_fab2(sch_1):page152_i102@mstr_discrete.re~
s(chips)',
 PATH='I102',
 DRAWING='@BASEBOARD_FAB2_LIB.BASEBOARD_FAB2(SCH_1):PAGE152',
 WATTAGE='1/16W',
 TOLERANCE='5%',
 SEC_TYPE='0402',
 MATERIAL='EMPTY',
 PHYS_PAGE='152',
 XY='(-6700,975)',
 ROT='0',
 VER='1',
 VALUE='0.0',
 PACK_TYPE='0402',
 PART_NUMBER='G21497-005',
 LOCATION='R2U45',
 SEC='1',
 CDS_LIB='mstr_discrete',
 CDS_PART_NAME='RES_0402-0.0,5%,1/16W,EMPTY,G2A',
 PRIM_FILE='./archive_libs/mstr_discrete/res/chips/chips.prt';

PART_NAME
 R2U46 'RES_0402-0.0,5%,1/16W,CHIP,G21A':;

SECTION_NUMBER 1
 '@BASEBOARD_FAB2_LIB.BASEBOARD_FAB2(SCH_1):PAGE152_I94@MSTR_DISCRETE.RES(CHIPS)':
 C_PATH='@baseboard_fab2_lib.baseboard_fab2(sch_1):page152_i94@mstr_discrete.res~
(chips)',
 P_PATH='@baseboard_fab2_lib.baseboard_fab2(sch_1):page152_i94@mstr_discrete.res~
(chips)',
 PATH='I94',
 DRAWING='@BASEBOARD_FAB2_LIB.BASEBOARD_FAB2(SCH_1):PAGE152',
 WATTAGE='1/16W',
 TOLERANCE='5%',
 SEC_TYPE='0402',
 MATERIAL='CHIP',
 PHYS_PAGE='152',
 XY='(-6700,1175)',
 ROT='0',
 VER='1',
 VALUE='0.0',
 PACK_TYPE='0402',
 PART_NUMBER='G21497-005',
 LOCATION='R2U46',
 SEC='1',
 CDS_LIB='mstr_discrete',
 CDS_PART_NAME='RES_0402-0.0,5%,1/16W,CHIP,G21A',
 PRIM_FILE='./archive_libs/mstr_discrete/res/chips/chips.prt';

PART_NAME
 R2U47 'RES_0402-0.0,5%,1/16W,CHIP,G21A':;

SECTION_NUMBER 1
 '@BASEBOARD_FAB2_LIB.BASEBOARD_FAB2(SCH_1):PAGE152_I79@MSTR_DISCRETE.RES(CHIPS)':
 C_PATH='@baseboard_fab2_lib.baseboard_fab2(sch_1):page152_i79@mstr_discrete.res~
(chips)',
 P_PATH='@baseboard_fab2_lib.baseboard_fab2(sch_1):page152_i79@mstr_discrete.res~
(chips)',
 PATH='I79',
 DRAWING='@BASEBOARD_FAB2_LIB.BASEBOARD_FAB2(SCH_1):PAGE152',
 WATTAGE='1/16W',
 TOLERANCE='5%',
 SEC_TYPE='0402',
 MATERIAL='CHIP',
 PHYS_PAGE='152',
 XY='(-6700,2475)',
 ROT='0',
 VER='1',
 VALUE='0.0',
 PACK_TYPE='0402',
 PART_NUMBER='G21497-005',
 LOCATION='R2U47',
 SEC='1',
 CDS_LIB='mstr_discrete',
 CDS_PART_NAME='RES_0402-0.0,5%,1/16W,CHIP,G21A',
 PRIM_FILE='./archive_libs/mstr_discrete/res/chips/chips.prt';

PART_NAME
 R2U48 'RES_0402-4.75K,1%,1/16W,CHIP,GA':;

SECTION_NUMBER 1
 '@BASEBOARD_FAB2_LIB.BASEBOARD_FAB2(SCH_1):PAGE119_I213@MSTR_DISCRETE.RES(CHIPS)':
 C_PATH='@baseboard_fab2_lib.baseboard_fab2(sch_1):page119_i213@mstr_discrete.re~
s(chips)',
 P_PATH='@baseboard_fab2_lib.baseboard_fab2(sch_1):page119_i213@mstr_discrete.re~
s(chips)',
 PATH='I213',
 DRAWING='@BASEBOARD_FAB2_LIB.BASEBOARD_FAB2(SCH_1):PAGE119',
 WATTAGE='1/16W',
 TOLERANCE='1%',
 SEC_TYPE='0402',
 MATERIAL='CHIP',
 PHYS_PAGE='119',
 XY='(-1700,4725)',
 ROT='0',
 VER='2',
 VALUE='4.75K',
 PACK_TYPE='0402',
 PART_NUMBER='G21796-072',
 LOCATION='R2U48',
 SEC='1',
 CDS_LIB='mstr_discrete',
 CDS_PART_NAME='RES_0402-4.75K,1%,1/16W,CHIP,GA',
 PRIM_FILE='./archive_libs/mstr_discrete/res/chips/chips.prt';

PART_NAME
 R2U49 'RES_0402-0.0,5%,1/16W,EMPTY,G2A':;

SECTION_NUMBER 1
 '@BASEBOARD_FAB2_LIB.BASEBOARD_FAB2(SCH_1):PAGE152_I66@MSTR_DISCRETE.RES(CHIPS)':
 C_PATH='@baseboard_fab2_lib.baseboard_fab2(sch_1):page152_i66@mstr_discrete.res~
(chips)',
 P_PATH='@baseboard_fab2_lib.baseboard_fab2(sch_1):page152_i66@mstr_discrete.res~
(chips)',
 PATH='I66',
 DRAWING='@BASEBOARD_FAB2_LIB.BASEBOARD_FAB2(SCH_1):PAGE152',
 WATTAGE='1/16W',
 TOLERANCE='5%',
 SEC_TYPE='0402',
 MATERIAL='EMPTY',
 PHYS_PAGE='152',
 XY='(-2850,4600)',
 ROT='0',
 VER='2',
 VALUE='0.0',
 PACK_TYPE='0402',
 PART_NUMBER='G21497-005',
 LOCATION='R2U49',
 SEC='1',
 CDS_LIB='mstr_discrete',
 CDS_PART_NAME='RES_0402-0.0,5%,1/16W,EMPTY,G2A',
 PRIM_FILE='./archive_libs/mstr_discrete/res/chips/chips.prt';

PART_NAME
 R2U50 'RES_0402-0.0,5%,1/16W,CHIP,G21A':
 ROOM='CPU0';

SECTION_NUMBER 1
 '@BASEBOARD_FAB2_LIB.BASEBOARD_FAB2(SCH_1):PAGE119_I228@MSTR_DISCRETE.RES(CHIPS)':
 C_PATH='@baseboard_fab2_lib.baseboard_fab2(sch_1):page119_i228@mstr_discrete.re~
s(chips)',
 P_PATH='@baseboard_fab2_lib.baseboard_fab2(sch_1):page119_i228@mstr_discrete.re~
s(chips)',
 PATH='I228',
 DRAWING='@BASEBOARD_FAB2_LIB.BASEBOARD_FAB2(SCH_1):PAGE119',
 POP='NOPOP',
 WATTAGE='1/16W',
 TOLERANCE='5%',
 SEC_TYPE='0402',
 MATERIAL='CHIP',
 BOM_COST='PROC_SIDEBAND',
 PHYS_PAGE='119',
 XY='(-1475,4100)',
 ROT='0',
 VER='1',
 VALUE='0.0',
 PACK_TYPE='0402',
 PART_NUMBER='G21497-005',
 LOCATION='R2U50',
 ROOM='CPU0',
 SEC='1',
 CDS_LIB='mstr_discrete',
 CDS_PART_NAME='RES_0402-0.0,5%,1/16W,CHIP,G21A',
 PRIM_FILE='./archive_libs/mstr_discrete/res/chips/chips.prt';

PART_NAME
 R2U51 'RES_0402-0.0,5%,1/16W,EMPTY,G2A':;

SECTION_NUMBER 1
 '@BASEBOARD_FAB2_LIB.BASEBOARD_FAB2(SCH_1):PAGE152_I51@MSTR_DISCRETE.RES(CHIPS)':
 C_PATH='@baseboard_fab2_lib.baseboard_fab2(sch_1):page152_i51@mstr_discrete.res~
(chips)',
 P_PATH='@baseboard_fab2_lib.baseboard_fab2(sch_1):page152_i51@mstr_discrete.res~
(chips)',
 PATH='I51',
 DRAWING='@BASEBOARD_FAB2_LIB.BASEBOARD_FAB2(SCH_1):PAGE152',
 WATTAGE='1/16W',
 TOLERANCE='5%',
 SEC_TYPE='0402',
 MATERIAL='EMPTY',
 PHYS_PAGE='152',
 XY='(-7450,4525)',
 ROT='0',
 VER='2',
 VALUE='0.0',
 PACK_TYPE='0402',
 PART_NUMBER='G21497-005',
 LOCATION='R2U51',
 SEC='1',
 CDS_LIB='mstr_discrete',
 CDS_PART_NAME='RES_0402-0.0,5%,1/16W,EMPTY,G2A',
 PRIM_FILE='./archive_libs/mstr_discrete/res/chips/chips.prt';

PART_NAME
 R2W1 'RES_0402-10.0K,1%,1/16W,CHIP,GA':
 ROOM='CPU0';

SECTION_NUMBER 1
 '@BASEBOARD_FAB2_LIB.BASEBOARD_FAB2(SCH_1):PAGE187_I174@MSTR_DISCRETE.RES(CHIPS)':
 C_PATH='@baseboard_fab2_lib.baseboard_fab2(sch_1):page187_i174@mstr_discrete.re~
s(chips)',
 P_PATH='@baseboard_fab2_lib.baseboard_fab2(sch_1):page187_i174@mstr_discrete.re~
s(chips)',
 PATH='I174',
 DRAWING='@BASEBOARD_FAB2_LIB.BASEBOARD_FAB2(SCH_1):PAGE187',
 WATTAGE='1/16W',
 TOLERANCE='1%',
 SEC_TYPE='0402',
 MATERIAL='CHIP',
 BOM_COST='PROC_SIDEBAND',
 PHYS_PAGE='187',
 XY='(1950,4675)',
 ROT='0',
 VER='2',
 VALUE='10.0K',
 PACK_TYPE='0402',
 PART_NUMBER='G21796-016',
 LOCATION='R2W1',
 ROOM='CPU0',
 SEC='1',
 CDS_LIB='mstr_discrete',
 CDS_PART_NAME='RES_0402-10.0K,1%,1/16W,CHIP,GA',
 PRIM_FILE='./archive_libs/mstr_discrete/res/chips/chips.prt';

PART_NAME
 R2W2 'RES_0402-49.9,1%,1/16W,EMPTY,GA':
 ROOM='SB';

SECTION_NUMBER 1
 '@BASEBOARD_FAB2_LIB.BASEBOARD_FAB2(SCH_1):PAGE93_I147@MSTR_DISCRETE.RES(CHIPS)':
 C_PATH='@baseboard_fab2_lib.baseboard_fab2(sch_1):page93_i147@mstr_discrete.res~
(chips)',
 P_PATH='@baseboard_fab2_lib.baseboard_fab2(sch_1):page93_i147@mstr_discrete.res~
(chips)',
 PATH='I147',
 DRAWING='@BASEBOARD_FAB2_LIB.BASEBOARD_FAB2(SCH_1):PAGE93',
 WATTAGE='1/16W',
 TOLERANCE='1%',
 SEC_TYPE='0402',
 MATERIAL='EMPTY',
 PHYS_PAGE='93',
 XY='(1750,1100)',
 ROT='0',
 VER='2',
 VALUE='49.9',
 PACK_TYPE='0402',
 PART_NUMBER='G21796-047',
 LOCATION='R2W2',
 ROOM='SB',
 SEC='1',
 CDS_LIB='mstr_discrete',
 CDS_PART_NAME='RES_0402-49.9,1%,1/16W,EMPTY,GA',
 PRIM_FILE='./archive_libs/mstr_discrete/res/chips/chips.prt';

PART_NAME
 R2W3 'RES_0402-0.0,5%,1/16W,CHIP,G21A':
 ROOM='CPU0';

SECTION_NUMBER 1
 '@BASEBOARD_FAB2_LIB.BASEBOARD_FAB2(SCH_1):PAGE119_I223@MSTR_DISCRETE.RES(CHIPS)':
 C_PATH='@baseboard_fab2_lib.baseboard_fab2(sch_1):page119_i223@mstr_discrete.re~
s(chips)',
 P_PATH='@baseboard_fab2_lib.baseboard_fab2(sch_1):page119_i223@mstr_discrete.re~
s(chips)',
 PATH='I223',
 DRAWING='@BASEBOARD_FAB2_LIB.BASEBOARD_FAB2(SCH_1):PAGE119',
 WATTAGE='1/16W',
 TOLERANCE='5%',
 SEC_TYPE='0402',
 MATERIAL='CHIP',
 BOM_COST='PROC_SIDEBAND',
 PHYS_PAGE='119',
 XY='(-1200,4150)',
 ROT='0',
 VER='1',
 VALUE='0.0',
 PACK_TYPE='0402',
 PART_NUMBER='G21497-005',
 LOCATION='R2W3',
 ROOM='CPU0',
 SEC='1',
 CDS_LIB='mstr_discrete',
 CDS_PART_NAME='RES_0402-0.0,5%,1/16W,CHIP,G21A',
 PRIM_FILE='./archive_libs/mstr_discrete/res/chips/chips.prt';

PART_NAME
 R2W4 'RES_0402-0.0,5%,1/16W,CHIP,G21A':
 ROOM='CPU0';

SECTION_NUMBER 1
 '@BASEBOARD_FAB2_LIB.BASEBOARD_FAB2(SCH_1):PAGE119_I224@MSTR_DISCRETE.RES(CHIPS)':
 C_PATH='@baseboard_fab2_lib.baseboard_fab2(sch_1):page119_i224@mstr_discrete.re~
s(chips)',
 P_PATH='@baseboard_fab2_lib.baseboard_fab2(sch_1):page119_i224@mstr_discrete.re~
s(chips)',
 PATH='I224',
 DRAWING='@BASEBOARD_FAB2_LIB.BASEBOARD_FAB2(SCH_1):PAGE119',
 POP='NOPOP',
 WATTAGE='1/16W',
 TOLERANCE='5%',
 SEC_TYPE='0402',
 MATERIAL='CHIP',
 BOM_COST='PROC_SIDEBAND',
 PHYS_PAGE='119',
 XY='(-6925,2550)',
 ROT='0',
 VER='1',
 VALUE='0.0',
 PACK_TYPE='0402',
 PART_NUMBER='G21497-005',
 LOCATION='R2W4',
 ROOM='CPU0',
 SEC='1',
 CDS_LIB='mstr_discrete',
 CDS_PART_NAME='RES_0402-0.0,5%,1/16W,CHIP,G21A',
 PRIM_FILE='./archive_libs/mstr_discrete/res/chips/chips.prt';

PART_NAME
 R2W5 'RES_0402-0.0,5%,1/16W,CHIP,G21A':
 ROOM='CPU0';

SECTION_NUMBER 1
 '@BASEBOARD_FAB2_LIB.BASEBOARD_FAB2(SCH_1):PAGE145_I176@MSTR_DISCRETE.RES(CHIPS)':
 C_PATH='@baseboard_fab2_lib.baseboard_fab2(sch_1):page145_i176@mstr_discrete.re~
s(chips)',
 P_PATH='@baseboard_fab2_lib.baseboard_fab2(sch_1):page145_i176@mstr_discrete.re~
s(chips)',
 PATH='I176',
 DRAWING='@BASEBOARD_FAB2_LIB.BASEBOARD_FAB2(SCH_1):PAGE145',
 WATTAGE='1/16W',
 TOLERANCE='5%',
 SEC_TYPE='0402',
 MATERIAL='CHIP',
 BOM_COST='PROC_SIDEBAND',
 PHYS_PAGE='145',
 XY='(-1500,-1850)',
 ROT='0',
 VER='1',
 VALUE='0.0',
 PACK_TYPE='0402',
 PART_NUMBER='G21497-005',
 LOCATION='R2W5',
 ROOM='CPU0',
 SEC='1',
 CDS_LIB='mstr_discrete',
 CDS_PART_NAME='RES_0402-0.0,5%,1/16W,CHIP,G21A',
 PRIM_FILE='./archive_libs/mstr_discrete/res/chips/chips.prt';

PART_NAME
 R3B1 'RES_0402-221,1.0%,1/16W,CHIP,GA':
 ROOM='CPU1';

SECTION_NUMBER 1
 '@BASEBOARD_FAB2_LIB.BASEBOARD_FAB2(SCH_1):PAGE55_I27@MSTR_DISCRETE.RES(CHIPS)':
 C_PATH='@baseboard_fab2_lib.baseboard_fab2(sch_1):page55_i27@mstr_discrete.res(~
chips)',
 P_PATH='@baseboard_fab2_lib.baseboard_fab2(sch_1):page55_i27@mstr_discrete.res(~
chips)',
 PATH='I27',
 DRAWING='@BASEBOARD_FAB2_LIB.BASEBOARD_FAB2(SCH_1):PAGE55',
 WATTAGE='1/16W',
 TOLERANCE='1.0%',
 MATERIAL='CHIP',
 BOM_COST='PROC_SOCKET',
 PHYS_PAGE='55',
 XY='(12250,3400)',
 ROT='0',
 VER='1',
 VALUE='221',
 PACK_TYPE='0402',
 PART_NUMBER='G21796-271',
 LOCATION='R3B1',
 ROOM='CPU1',
 CDS_LIB='mstr_discrete',
 CDS_PART_NAME='RES_0402-221,1.0%,1/16W,CHIP,GA',
 PRIM_FILE='./archive_libs/mstr_discrete/res/chips/chips.prt';

PART_NAME
 R3B2 'RES_0402-49.9,1%,1/16W,CHIP,G2A':
 ROOM='CPU1';

SECTION_NUMBER 1
 '@BASEBOARD_FAB2_LIB.BASEBOARD_FAB2(SCH_1):PAGE55_I19@MSTR_DISCRETE.RES(CHIPS)':
 C_PATH='@baseboard_fab2_lib.baseboard_fab2(sch_1):page55_i19@mstr_discrete.res(~
chips)',
 P_PATH='@baseboard_fab2_lib.baseboard_fab2(sch_1):page55_i19@mstr_discrete.res(~
chips)',
 PATH='I19',
 DRAWING='@BASEBOARD_FAB2_LIB.BASEBOARD_FAB2(SCH_1):PAGE55',
 WATTAGE='1/16W',
 TOLERANCE='1%',
 SEC_TYPE='0402',
 MATERIAL='CHIP',
 BOM_COST='PROC_SOCKET',
 PHYS_PAGE='55',
 XY='(13600,3200)',
 ROT='0',
 VER='2',
 VALUE='49.9',
 PACK_TYPE='0402',
 PART_NUMBER='G21796-047',
 LOCATION='R3B2',
 ROOM='CPU1',
 SEC='1',
 CDS_LIB='mstr_discrete',
 CDS_PART_NAME='RES_0402-49.9,1%,1/16W,CHIP,G2A',
 PRIM_FILE='./archive_libs/mstr_discrete/res/chips/chips.prt';

PART_NAME
 R3B3 'RES_0402-0.0,5%,1/16W,CHIP,G21A':
 ROOM='CPU1';

SECTION_NUMBER 1
 '@BASEBOARD_FAB2_LIB.BASEBOARD_FAB2(SCH_1):PAGE55_I29@MSTR_DISCRETE.RES(CHIPS)':
 C_PATH='@baseboard_fab2_lib.baseboard_fab2(sch_1):page55_i29@mstr_discrete.res(~
chips)',
 P_PATH='@baseboard_fab2_lib.baseboard_fab2(sch_1):page55_i29@mstr_discrete.res(~
chips)',
 PATH='I29',
 DRAWING='@BASEBOARD_FAB2_LIB.BASEBOARD_FAB2(SCH_1):PAGE55',
 WATTAGE='1/16W',
 TOLERANCE='5%',
 MATERIAL='CHIP',
 BOM_COST='PROC_SOCKET',
 PHYS_PAGE='55',
 XY='(12250,3500)',
 ROT='0',
 VER='1',
 VALUE='0.0',
 PACK_TYPE='0402',
 PART_NUMBER='G21497-005',
 LOCATION='R3B3',
 ROOM='CPU1',
 CDS_LIB='mstr_discrete',
 CDS_PART_NAME='RES_0402-0.0,5%,1/16W,CHIP,G21A',
 PRIM_FILE='./archive_libs/mstr_discrete/res/chips/chips.prt';

PART_NAME
 R3B4 'RES_0402-100.0,1%,1/16W,CHIP,GA':
 ROOM='CPU1';

SECTION_NUMBER 1
 '@BASEBOARD_FAB2_LIB.BASEBOARD_FAB2(SCH_1):PAGE55_I21@MSTR_DISCRETE.RES(CHIPS)':
 C_PATH='@baseboard_fab2_lib.baseboard_fab2(sch_1):page55_i21@mstr_discrete.res(~
chips)',
 P_PATH='@baseboard_fab2_lib.baseboard_fab2(sch_1):page55_i21@mstr_discrete.res(~
chips)',
 PATH='I21',
 DRAWING='@BASEBOARD_FAB2_LIB.BASEBOARD_FAB2(SCH_1):PAGE55',
 WATTAGE='1/16W',
 TOLERANCE='1%',
 SEC_TYPE='0402',
 MATERIAL='CHIP',
 BOM_COST='PROC_SOCKET',
 PHYS_PAGE='55',
 XY='(13325,3200)',
 ROT='0',
 VER='2',
 VALUE='100.0',
 PACK_TYPE='0402',
 PART_NUMBER='G21796-017',
 LOCATION='R3B4',
 ROOM='CPU1',
 SEC='1',
 CDS_LIB='mstr_discrete',
 CDS_PART_NAME='RES_0402-100.0,1%,1/16W,CHIP,GA',
 PRIM_FILE='./archive_libs/mstr_discrete/res/chips/chips.prt';

PART_NAME
 R3B5 'RES_0402-0.0,5%,1/16W,CHIP,G21A':
 ROOM='CPU1';

SECTION_NUMBER 1
 '@BASEBOARD_FAB2_LIB.BASEBOARD_FAB2(SCH_1):PAGE55_I28@MSTR_DISCRETE.RES(CHIPS)':
 C_PATH='@baseboard_fab2_lib.baseboard_fab2(sch_1):page55_i28@mstr_discrete.res(~
chips)',
 P_PATH='@baseboard_fab2_lib.baseboard_fab2(sch_1):page55_i28@mstr_discrete.res(~
chips)',
 PATH='I28',
 DRAWING='@BASEBOARD_FAB2_LIB.BASEBOARD_FAB2(SCH_1):PAGE55',
 WATTAGE='1/16W',
 TOLERANCE='5%',
 MATERIAL='CHIP',
 BOM_COST='PROC_SOCKET',
 PHYS_PAGE='55',
 XY='(12250,3450)',
 ROT='0',
 VER='1',
 VALUE='0.0',
 PACK_TYPE='0402',
 PART_NUMBER='G21497-005',
 LOCATION='R3B5',
 ROOM='CPU1',
 CDS_LIB='mstr_discrete',
 CDS_PART_NAME='RES_0402-0.0,5%,1/16W,CHIP,G21A',
 PRIM_FILE='./archive_libs/mstr_discrete/res/chips/chips.prt';

PART_NAME
 R3D1 'RES_0402-90.9,1%,1/16W,CHIP,G2A':
 ROOM='CPU1';

SECTION_NUMBER 1
 '@BASEBOARD_FAB2_LIB.BASEBOARD_FAB2(SCH_1):PAGE55_I116@MSTR_DISCRETE.RES(CHIPS)':
 C_PATH='@baseboard_fab2_lib.baseboard_fab2(sch_1):page55_i116@mstr_discrete.res~
(chips)',
 P_PATH='@baseboard_fab2_lib.baseboard_fab2(sch_1):page55_i116@mstr_discrete.res~
(chips)',
 PATH='I116',
 DRAWING='@BASEBOARD_FAB2_LIB.BASEBOARD_FAB2(SCH_1):PAGE55',
 WATTAGE='1/16W',
 TOLERANCE='1%',
 SEC_TYPE='0402',
 MATERIAL='CHIP',
 BOM_COST='PROC_SOCKET',
 PHYS_PAGE='55',
 XY='(7700,2525)',
 ROT='2',
 VER='2',
 VALUE='90.9',
 PACK_TYPE='0402',
 PART_NUMBER='G21796-365',
 LOCATION='R3D1',
 ROOM='CPU1',
 SEC='1',
 CDS_LIB='mstr_discrete',
 CDS_PART_NAME='RES_0402-90.9,1%,1/16W,CHIP,G2A',
 PRIM_FILE='./archive_libs/mstr_discrete/res/chips/chips.prt';

PART_NAME
 R3D2 'RES_0402-90.9,1%,1/16W,CHIP,G2A':
 ROOM='CPU1';

SECTION_NUMBER 1
 '@BASEBOARD_FAB2_LIB.BASEBOARD_FAB2(SCH_1):PAGE55_I117@MSTR_DISCRETE.RES(CHIPS)':
 C_PATH='@baseboard_fab2_lib.baseboard_fab2(sch_1):page55_i117@mstr_discrete.res~
(chips)',
 P_PATH='@baseboard_fab2_lib.baseboard_fab2(sch_1):page55_i117@mstr_discrete.res~
(chips)',
 PATH='I117',
 DRAWING='@BASEBOARD_FAB2_LIB.BASEBOARD_FAB2(SCH_1):PAGE55',
 WATTAGE='1/16W',
 TOLERANCE='1%',
 SEC_TYPE='0402',
 MATERIAL='CHIP',
 BOM_COST='PROC_SOCKET',
 PHYS_PAGE='55',
 XY='(7475,2525)',
 ROT='2',
 VER='2',
 VALUE='90.9',
 PACK_TYPE='0402',
 PART_NUMBER='G21796-365',
 LOCATION='R3D2',
 ROOM='CPU1',
 SEC='1',
 CDS_LIB='mstr_discrete',
 CDS_PART_NAME='RES_0402-90.9,1%,1/16W,CHIP,G2A',
 PRIM_FILE='./archive_libs/mstr_discrete/res/chips/chips.prt';

PART_NAME
 R3D3 'RES_0402-100.0,1%,1/16W,CHIP,GA':
 ROOM='CPU1';

SECTION_NUMBER 1
 '@BASEBOARD_FAB2_LIB.BASEBOARD_FAB2(SCH_1):PAGE55_I118@MSTR_DISCRETE.RES(CHIPS)':
 C_PATH='@baseboard_fab2_lib.baseboard_fab2(sch_1):page55_i118@mstr_discrete.res~
(chips)',
 P_PATH='@baseboard_fab2_lib.baseboard_fab2(sch_1):page55_i118@mstr_discrete.res~
(chips)',
 PATH='I118',
 DRAWING='@BASEBOARD_FAB2_LIB.BASEBOARD_FAB2(SCH_1):PAGE55',
 WATTAGE='1/16W',
 TOLERANCE='1%',
 SEC_TYPE='0402',
 MATERIAL='CHIP',
 BOM_COST='PROC_SOCKET',
 PHYS_PAGE='55',
 XY='(7250,2525)',
 ROT='2',
 VER='2',
 VALUE='100.0',
 PACK_TYPE='0402',
 PART_NUMBER='G21796-017',
 LOCATION='R3D3',
 ROOM='CPU1',
 SEC='1',
 CDS_LIB='mstr_discrete',
 CDS_PART_NAME='RES_0402-100.0,1%,1/16W,CHIP,GA',
 PRIM_FILE='./archive_libs/mstr_discrete/res/chips/chips.prt';

PART_NAME
 R3D4 'RES_0402-49.9,1%,1/16W,CHIP,G2A':
 ROOM='CPU1';

SECTION_NUMBER 1
 '@BASEBOARD_FAB2_LIB.BASEBOARD_FAB2(SCH_1):PAGE55_I155@MSTR_DISCRETE.RES(CHIPS)':
 C_PATH='@baseboard_fab2_lib.baseboard_fab2(sch_1):page55_i155@mstr_discrete.res~
(chips)',
 P_PATH='@baseboard_fab2_lib.baseboard_fab2(sch_1):page55_i155@mstr_discrete.res~
(chips)',
 PATH='I155',
 DRAWING='@BASEBOARD_FAB2_LIB.BASEBOARD_FAB2(SCH_1):PAGE55',
 WATTAGE='1/16W',
 TOLERANCE='1%',
 SEC_TYPE='0402',
 MATERIAL='CHIP',
 BOM_COST='PROC_SOCKET',
 PHYS_PAGE='55',
 XY='(7500,1425)',
 ROT='2',
 VER='2',
 VALUE='49.9',
 PACK_TYPE='0402',
 PART_NUMBER='G21796-047',
 LOCATION='R3D4',
 ROOM='CPU1',
 SEC='1',
 CDS_LIB='mstr_discrete',
 CDS_PART_NAME='RES_0402-49.9,1%,1/16W,CHIP,G2A',
 PRIM_FILE='./archive_libs/mstr_discrete/res/chips/chips.prt';

PART_NAME
 R3D9 'RES_0402-49.9,1%,1/16W,CHIP,G2A':
 ROOM='CPU1';

SECTION_NUMBER 1
 '@BASEBOARD_FAB2_LIB.BASEBOARD_FAB2(SCH_1):PAGE90_I88@MSTR_DISCRETE.RES(CHIPS)':
 C_PATH='@baseboard_fab2_lib.baseboard_fab2(sch_1):page90_i88@mstr_discrete.res(~
chips)',
 P_PATH='@baseboard_fab2_lib.baseboard_fab2(sch_1):page90_i88@mstr_discrete.res(~
chips)',
 PATH='I88',
 DRAWING='@BASEBOARD_FAB2_LIB.BASEBOARD_FAB2(SCH_1):PAGE90',
 WATTAGE='1/16W',
 TOLERANCE='1%',
 SEC_TYPE='0402',
 MATERIAL='CHIP',
 PHYS_PAGE='90',
 XY='(325,2200)',
 ROT='0',
 VER='1',
 VALUE='49.9',
 PACK_TYPE='0402',
 PART_NUMBER='G21796-047',
 LOCATION='R3D9',
 ROOM='CPU1',
 SEC='1',
 CDS_LIB='mstr_discrete',
 CDS_PART_NAME='RES_0402-49.9,1%,1/16W,CHIP,G2A',
 PRIM_FILE='./archive_libs/mstr_discrete/res/chips/chips.prt';

PART_NAME
 R3D12 'RES_0402-240,1.0%,1/16W,EMPTY,A':
 ROOM='PROC_SIDEBAND';

SECTION_NUMBER 1
 '@BASEBOARD_FAB2_LIB.BASEBOARD_FAB2(SCH_1):PAGE90_I102@MSTR_DISCRETE.RES(CHIPS)':
 C_PATH='@baseboard_fab2_lib.baseboard_fab2(sch_1):page90_i102@mstr_discrete.res~
(chips)',
 P_PATH='@baseboard_fab2_lib.baseboard_fab2(sch_1):page90_i102@mstr_discrete.res~
(chips)',
 PATH='I102',
 DRAWING='@BASEBOARD_FAB2_LIB.BASEBOARD_FAB2(SCH_1):PAGE90',
 WATTAGE='1/16W',
 TOLERANCE='1.0%',
 SEC_TYPE='0402',
 MATERIAL='EMPTY',
 BOM_COST='PROC',
 PHYS_PAGE='90',
 XY='(-425,1275)',
 ROT='0',
 VER='1',
 VALUE='240',
 PACK_TYPE='0402',
 PART_NUMBER='G21796-294',
 LOCATION='R3D12',
 ROOM='PROC_SIDEBAND',
 SEC='1',
 CDS_LIB='mstr_discrete',
 CDS_PART_NAME='RES_0402-240,1.0%,1/16W,EMPTY,A',
 PRIM_FILE='./archive_libs/mstr_discrete/res/chips/chips.prt';

PART_NAME
 R3D13 'RES_0402-240,1.0%,1/16W,EMPTY,A':
 ROOM='PROC_SIDEBAND';

SECTION_NUMBER 1
 '@BASEBOARD_FAB2_LIB.BASEBOARD_FAB2(SCH_1):PAGE90_I99@MSTR_DISCRETE.RES(CHIPS)':
 C_PATH='@baseboard_fab2_lib.baseboard_fab2(sch_1):page90_i99@mstr_discrete.res(~
chips)',
 P_PATH='@baseboard_fab2_lib.baseboard_fab2(sch_1):page90_i99@mstr_discrete.res(~
chips)',
 PATH='I99',
 DRAWING='@BASEBOARD_FAB2_LIB.BASEBOARD_FAB2(SCH_1):PAGE90',
 WATTAGE='1/16W',
 TOLERANCE='1.0%',
 SEC_TYPE='0402',
 MATERIAL='EMPTY',
 BOM_COST='PROC',
 PHYS_PAGE='90',
 XY='(-425,1050)',
 ROT='0',
 VER='1',
 VALUE='240',
 PACK_TYPE='0402',
 PART_NUMBER='G21796-294',
 LOCATION='R3D13',
 ROOM='PROC_SIDEBAND',
 SEC='1',
 CDS_LIB='mstr_discrete',
 CDS_PART_NAME='RES_0402-240,1.0%,1/16W,EMPTY,A',
 PRIM_FILE='./archive_libs/mstr_discrete/res/chips/chips.prt';

PART_NAME
 R3D14 'RES_0603-2.2,1.0%,1/10W,CHIP,GA':
 ROOM='DB1200ZL';

SECTION_NUMBER 1
 '@BASEBOARD_FAB2_LIB.BASEBOARD_FAB2(SCH_1):PAGE102_I21@MSTR_DISCRETE.RES(CHIPS)':
 C_PATH='@baseboard_fab2_lib.baseboard_fab2(sch_1):page102_i21@mstr_discrete.res~
(chips)',
 P_PATH='@baseboard_fab2_lib.baseboard_fab2(sch_1):page102_i21@mstr_discrete.res~
(chips)',
 PATH='I21',
 DRAWING='@BASEBOARD_FAB2_LIB.BASEBOARD_FAB2(SCH_1):PAGE102',
 WATTAGE='1/10W',
 TOLERANCE='1.0%',
 SEC_TYPE='0603',
 MATERIAL='CHIP',
 BOM_COST='SYS_CLOCK',
 PHYS_PAGE='102',
 XY='(-2425,4125)',
 ROT='0',
 VER='1',
 VALUE='2.2',
 PACK_TYPE='0603',
 PART_NUMBER='G22026-127',
 LOCATION='R3D14',
 ROOM='DB1200ZL',
 SEC='1',
 CDS_LIB='mstr_discrete',
 CDS_PART_NAME='RES_0603-2.2,1.0%,1/10W,CHIP,GA',
 PRIM_FILE='./archive_libs/mstr_discrete/res/chips/chips.prt';

PART_NAME
 R3D15 'RES_0402-49.9,1%,1/16W,CHIP,G2A':
 ROOM='PROC_RSTS_PGOODS';

SECTION_NUMBER 1
 '@BASEBOARD_FAB2_LIB.BASEBOARD_FAB2(SCH_1):PAGE96_I26@MSTR_DISCRETE.RES(CHIPS)':
 C_PATH='@baseboard_fab2_lib.baseboard_fab2(sch_1):page96_i26@mstr_discrete.res(~
chips)',
 P_PATH='@baseboard_fab2_lib.baseboard_fab2(sch_1):page96_i26@mstr_discrete.res(~
chips)',
 PATH='I26',
 DRAWING='@BASEBOARD_FAB2_LIB.BASEBOARD_FAB2(SCH_1):PAGE96',
 WATTAGE='1/16W',
 TOLERANCE='1%',
 SEC_TYPE='0402',
 MATERIAL='CHIP',
 BOM_COST='PROC_SIDEBAND',
 PHYS_PAGE='96',
 XY='(1700,2150)',
 ROT='2',
 VER='2',
 VALUE='49.9',
 PACK_TYPE='0402',
 PART_NUMBER='G21796-047',
 LOCATION='R3D15',
 ROOM='PROC_RSTS_PGOODS',
 SEC='1',
 CDS_LIB='mstr_discrete',
 CDS_PART_NAME='RES_0402-49.9,1%,1/16W,CHIP,G2A',
 PRIM_FILE='./archive_libs/mstr_discrete/res/chips/chips.prt';

PART_NAME
 R3D16 'RES_0402-240,1.0%,1/16W,EMPTY,A':
 ROOM='PROC_SIDEBAND';

SECTION_NUMBER 1
 '@BASEBOARD_FAB2_LIB.BASEBOARD_FAB2(SCH_1):PAGE90_I24@MSTR_DISCRETE.RES(CHIPS)':
 C_PATH='@baseboard_fab2_lib.baseboard_fab2(sch_1):page90_i24@mstr_discrete.res(~
chips)',
 P_PATH='@baseboard_fab2_lib.baseboard_fab2(sch_1):page90_i24@mstr_discrete.res(~
chips)',
 PATH='I24',
 DRAWING='@BASEBOARD_FAB2_LIB.BASEBOARD_FAB2(SCH_1):PAGE90',
 WATTAGE='1/16W',
 TOLERANCE='1.0%',
 SEC_TYPE='0402',
 MATERIAL='EMPTY',
 BOM_COST='PROC',
 PHYS_PAGE='90',
 XY='(-2450,1675)',
 ROT='0',
 VER='1',
 VALUE='240',
 PACK_TYPE='0402',
 PART_NUMBER='G21796-294',
 LOCATION='R3D16',
 ROOM='PROC_SIDEBAND',
 SEC='1',
 CDS_LIB='mstr_discrete',
 CDS_PART_NAME='RES_0402-240,1.0%,1/16W,EMPTY,A',
 PRIM_FILE='./archive_libs/mstr_discrete/res/chips/chips.prt';

PART_NAME
 R3D17 'RES_0402-240,1.0%,1/16W,EMPTY,A':
 ROOM='PROC_SIDEBAND';

SECTION_NUMBER 1
 '@BASEBOARD_FAB2_LIB.BASEBOARD_FAB2(SCH_1):PAGE90_I60@MSTR_DISCRETE.RES(CHIPS)':
 C_PATH='@baseboard_fab2_lib.baseboard_fab2(sch_1):page90_i60@mstr_discrete.res(~
chips)',
 P_PATH='@baseboard_fab2_lib.baseboard_fab2(sch_1):page90_i60@mstr_discrete.res(~
chips)',
 PATH='I60',
 DRAWING='@BASEBOARD_FAB2_LIB.BASEBOARD_FAB2(SCH_1):PAGE90',
 WATTAGE='1/16W',
 TOLERANCE='1.0%',
 SEC_TYPE='0402',
 MATERIAL='EMPTY',
 BOM_COST='PROC',
 PHYS_PAGE='90',
 XY='(-425,1475)',
 ROT='0',
 VER='1',
 VALUE='240',
 PACK_TYPE='0402',
 PART_NUMBER='G21796-294',
 LOCATION='R3D17',
 ROOM='PROC_SIDEBAND',
 SEC='1',
 CDS_LIB='mstr_discrete',
 CDS_PART_NAME='RES_0402-240,1.0%,1/16W,EMPTY,A',
 PRIM_FILE='./archive_libs/mstr_discrete/res/chips/chips.prt';

PART_NAME
 R3D18 'RES_0402-0.0,5%,1/16W,CHIP,G21A':
 ROOM='PROC_SIDEBAND';

SECTION_NUMBER 1
 '@BASEBOARD_FAB2_LIB.BASEBOARD_FAB2(SCH_1):PAGE97_I33@MSTR_DISCRETE.RES(CHIPS)':
 C_PATH='@baseboard_fab2_lib.baseboard_fab2(sch_1):page97_i33@mstr_discrete.res(~
chips)',
 P_PATH='@baseboard_fab2_lib.baseboard_fab2(sch_1):page97_i33@mstr_discrete.res(~
chips)',
 PATH='I33',
 DRAWING='@BASEBOARD_FAB2_LIB.BASEBOARD_FAB2(SCH_1):PAGE97',
 WATTAGE='1/16W',
 TOLERANCE='5%',
 MATERIAL='CHIP',
 BOM_COST='PROC_SIDEBAND',
 PHYS_PAGE='97',
 XY='(-2000,4225)',
 ROT='0',
 VER='1',
 VALUE='0.0',
 PACK_TYPE='0402',
 PART_NUMBER='G21497-005',
 LOCATION='R3D18',
 ROOM='PROC_SIDEBAND',
 CDS_LIB='mstr_discrete',
 CDS_PART_NAME='RES_0402-0.0,5%,1/16W,CHIP,G21A',
 PRIM_FILE='./archive_libs/mstr_discrete/res/chips/chips.prt';

PART_NAME
 R3D19 'RES_0402-49.9,1%,1/16W,CHIP,G2A':
 ROOM='CPU1';

SECTION_NUMBER 1
 '@BASEBOARD_FAB2_LIB.BASEBOARD_FAB2(SCH_1):PAGE55_I125@MSTR_DISCRETE.RES(CHIPS)':
 C_PATH='@baseboard_fab2_lib.baseboard_fab2(sch_1):page55_i125@mstr_discrete.res~
(chips)',
 P_PATH='@baseboard_fab2_lib.baseboard_fab2(sch_1):page55_i125@mstr_discrete.res~
(chips)',
 PATH='I125',
 DRAWING='@BASEBOARD_FAB2_LIB.BASEBOARD_FAB2(SCH_1):PAGE55',
 WATTAGE='1/16W',
 TOLERANCE='1%',
 SEC_TYPE='0402',
 MATERIAL='CHIP',
 BOM_COST='PROC_SOCKET',
 PHYS_PAGE='55',
 XY='(7050,1425)',
 ROT='2',
 VER='2',
 VALUE='49.9',
 PACK_TYPE='0402',
 PART_NUMBER='G21796-047',
 LOCATION='R3D19',
 ROOM='CPU1',
 SEC='1',
 CDS_LIB='mstr_discrete',
 CDS_PART_NAME='RES_0402-49.9,1%,1/16W,CHIP,G2A',
 PRIM_FILE='./archive_libs/mstr_discrete/res/chips/chips.prt';

PART_NAME
 R3D20 'RES_0402-49.9,1%,1/16W,CHIP,G2A':
 ROOM='PROC_RSTS_PGOODS';

SECTION_NUMBER 1
 '@BASEBOARD_FAB2_LIB.BASEBOARD_FAB2(SCH_1):PAGE96_I25@MSTR_DISCRETE.RES(CHIPS)':
 C_PATH='@baseboard_fab2_lib.baseboard_fab2(sch_1):page96_i25@mstr_discrete.res(~
chips)',
 P_PATH='@baseboard_fab2_lib.baseboard_fab2(sch_1):page96_i25@mstr_discrete.res(~
chips)',
 PATH='I25',
 DRAWING='@BASEBOARD_FAB2_LIB.BASEBOARD_FAB2(SCH_1):PAGE96',
 WATTAGE='1/16W',
 TOLERANCE='1%',
 SEC_TYPE='0402',
 MATERIAL='CHIP',
 BOM_COST='PROC_SIDEBAND',
 PHYS_PAGE='96',
 XY='(1900,2150)',
 ROT='0',
 VER='2',
 VALUE='49.9',
 PACK_TYPE='0402',
 PART_NUMBER='G21796-047',
 LOCATION='R3D20',
 ROOM='PROC_RSTS_PGOODS',
 SEC='1',
 CDS_LIB='mstr_discrete',
 CDS_PART_NAME='RES_0402-49.9,1%,1/16W,CHIP,G2A',
 PRIM_FILE='./archive_libs/mstr_discrete/res/chips/chips.prt';

PART_NAME
 R3D21 'RES_0402-64.9,1.0%,1/16W,CHIP,A':
 ROOM='PROC_RSTS_PGOODS';

SECTION_NUMBER 1
 '@BASEBOARD_FAB2_LIB.BASEBOARD_FAB2(SCH_1):PAGE96_I30@MSTR_DISCRETE.RES(CHIPS)':
 C_PATH='@baseboard_fab2_lib.baseboard_fab2(sch_1):page96_i30@mstr_discrete.res(~
chips)',
 P_PATH='@baseboard_fab2_lib.baseboard_fab2(sch_1):page96_i30@mstr_discrete.res(~
chips)',
 PATH='I30',
 DRAWING='@BASEBOARD_FAB2_LIB.BASEBOARD_FAB2(SCH_1):PAGE96',
 WATTAGE='1/16W',
 TOLERANCE='1.0%',
 MATERIAL='CHIP',
 BOM_COST='PROC_SIDEBAND',
 PHYS_PAGE='96',
 XY='(575,2150)',
 ROT='0',
 VER='2',
 VALUE='64.9',
 PACK_TYPE='0402',
 PART_NUMBER='G21796-298',
 LOCATION='R3D21',
 ROOM='PROC_RSTS_PGOODS',
 CDS_LIB='mstr_discrete',
 CDS_PART_NAME='RES_0402-64.9,1.0%,1/16W,CHIP,A',
 PRIM_FILE='./archive_libs/mstr_discrete/res/chips/chips.prt';

PART_NAME
 R3D22 'RES_0402-240,1.0%,1/16W,EMPTY,A':
 ROOM='PROC_SIDEBAND';

SECTION_NUMBER 1
 '@BASEBOARD_FAB2_LIB.BASEBOARD_FAB2(SCH_1):PAGE90_I17@MSTR_DISCRETE.RES(CHIPS)':
 C_PATH='@baseboard_fab2_lib.baseboard_fab2(sch_1):page90_i17@mstr_discrete.res(~
chips)',
 P_PATH='@baseboard_fab2_lib.baseboard_fab2(sch_1):page90_i17@mstr_discrete.res(~
chips)',
 PATH='I17',
 DRAWING='@BASEBOARD_FAB2_LIB.BASEBOARD_FAB2(SCH_1):PAGE90',
 WATTAGE='1/16W',
 TOLERANCE='1.0%',
 SEC_TYPE='0402',
 MATERIAL='EMPTY',
 BOM_COST='PROC',
 PHYS_PAGE='90',
 XY='(-2450,1875)',
 ROT='0',
 VER='1',
 VALUE='240',
 PACK_TYPE='0402',
 PART_NUMBER='G21796-294',
 LOCATION='R3D22',
 ROOM='PROC_SIDEBAND',
 SEC='1',
 CDS_LIB='mstr_discrete',
 CDS_PART_NAME='RES_0402-240,1.0%,1/16W,EMPTY,A',
 PRIM_FILE='./archive_libs/mstr_discrete/res/chips/chips.prt';

PART_NAME
 R3D23 'RES_0402-240,1.0%,1/16W,EMPTY,A':
 ROOM='PROC_SIDEBAND';

SECTION_NUMBER 1
 '@BASEBOARD_FAB2_LIB.BASEBOARD_FAB2(SCH_1):PAGE90_I25@MSTR_DISCRETE.RES(CHIPS)':
 C_PATH='@baseboard_fab2_lib.baseboard_fab2(sch_1):page90_i25@mstr_discrete.res(~
chips)',
 P_PATH='@baseboard_fab2_lib.baseboard_fab2(sch_1):page90_i25@mstr_discrete.res(~
chips)',
 PATH='I25',
 DRAWING='@BASEBOARD_FAB2_LIB.BASEBOARD_FAB2(SCH_1):PAGE90',
 WATTAGE='1/16W',
 TOLERANCE='1.0%',
 MATERIAL='EMPTY',
 BOM_COST='PROC',
 PHYS_PAGE='90',
 XY='(-2450,1475)',
 ROT='0',
 VER='1',
 VALUE='240',
 PACK_TYPE='0402',
 PART_NUMBER='G21796-294',
 LOCATION='R3D23',
 ROOM='PROC_SIDEBAND',
 CDS_LIB='mstr_discrete',
 CDS_PART_NAME='RES_0402-240,1.0%,1/16W,EMPTY,A',
 PRIM_FILE='./archive_libs/mstr_discrete/res/chips/chips.prt';

PART_NAME
 R3D24 'RES_0402-240,1.0%,1/16W,CHIP,GA':
 ROOM='PROC_SIDEBAND';

SECTION_NUMBER 1
 '@BASEBOARD_FAB2_LIB.BASEBOARD_FAB2(SCH_1):PAGE90_I59@MSTR_DISCRETE.RES(CHIPS)':
 C_PATH='@baseboard_fab2_lib.baseboard_fab2(sch_1):page90_i59@mstr_discrete.res(~
chips)',
 P_PATH='@baseboard_fab2_lib.baseboard_fab2(sch_1):page90_i59@mstr_discrete.res(~
chips)',
 PATH='I59',
 DRAWING='@BASEBOARD_FAB2_LIB.BASEBOARD_FAB2(SCH_1):PAGE90',
 WATTAGE='1/16W',
 TOLERANCE='1.0%',
 SEC_TYPE='0402',
 MATERIAL='CHIP',
 BOM_COST='PROC',
 PHYS_PAGE='90',
 XY='(-425,1675)',
 ROT='0',
 VER='1',
 VALUE='240',
 PACK_TYPE='0402',
 PART_NUMBER='G21796-294',
 LOCATION='R3D24',
 ROOM='PROC_SIDEBAND',
 SEC='1',
 CDS_LIB='mstr_discrete',
 CDS_PART_NAME='RES_0402-240,1.0%,1/16W,CHIP,GA',
 PRIM_FILE='./archive_libs/mstr_discrete/res/chips/chips.prt';

PART_NAME
 R3D25 'RES_0402-240,1.0%,1/16W,EMPTY,A':
 ROOM='PROC_SIDEBAND';

SECTION_NUMBER 1
 '@BASEBOARD_FAB2_LIB.BASEBOARD_FAB2(SCH_1):PAGE90_I66@MSTR_DISCRETE.RES(CHIPS)':
 C_PATH='@baseboard_fab2_lib.baseboard_fab2(sch_1):page90_i66@mstr_discrete.res(~
chips)',
 P_PATH='@baseboard_fab2_lib.baseboard_fab2(sch_1):page90_i66@mstr_discrete.res(~
chips)',
 PATH='I66',
 DRAWING='@BASEBOARD_FAB2_LIB.BASEBOARD_FAB2(SCH_1):PAGE90',
 WATTAGE='1/16W',
 TOLERANCE='1.0%',
 SEC_TYPE='0402',
 MATERIAL='EMPTY',
 BOM_COST='PROC',
 PHYS_PAGE='90',
 XY='(-2450,1025)',
 ROT='0',
 VER='1',
 VALUE='240',
 PACK_TYPE='0402',
 PART_NUMBER='G21796-294',
 LOCATION='R3D25',
 ROOM='PROC_SIDEBAND',
 SEC='1',
 CDS_LIB='mstr_discrete',
 CDS_PART_NAME='RES_0402-240,1.0%,1/16W,EMPTY,A',
 PRIM_FILE='./archive_libs/mstr_discrete/res/chips/chips.prt';

PART_NAME
 R3D26 'RES_0402-240,1.0%,1/16W,EMPTY,A':
 ROOM='PROC_SIDEBAND';

SECTION_NUMBER 1
 '@BASEBOARD_FAB2_LIB.BASEBOARD_FAB2(SCH_1):PAGE90_I28@MSTR_DISCRETE.RES(CHIPS)':
 C_PATH='@baseboard_fab2_lib.baseboard_fab2(sch_1):page90_i28@mstr_discrete.res(~
chips)',
 P_PATH='@baseboard_fab2_lib.baseboard_fab2(sch_1):page90_i28@mstr_discrete.res(~
chips)',
 PATH='I28',
 DRAWING='@BASEBOARD_FAB2_LIB.BASEBOARD_FAB2(SCH_1):PAGE90',
 WATTAGE='1/16W',
 TOLERANCE='1.0%',
 SEC_TYPE='0402',
 MATERIAL='EMPTY',
 BOM_COST='PROC',
 PHYS_PAGE='90',
 XY='(-2450,1275)',
 ROT='0',
 VER='1',
 VALUE='240',
 PACK_TYPE='0402',
 PART_NUMBER='G21796-294',
 LOCATION='R3D26',
 ROOM='PROC_SIDEBAND',
 SEC='1',
 CDS_LIB='mstr_discrete',
 CDS_PART_NAME='RES_0402-240,1.0%,1/16W,EMPTY,A',
 PRIM_FILE='./archive_libs/mstr_discrete/res/chips/chips.prt';

PART_NAME
 R3D27 'RES_0402-249,0.1%,1/16W,CHIP,GA':
 ROOM='CPU1';

SECTION_NUMBER 1
 '@BASEBOARD_FAB2_LIB.BASEBOARD_FAB2(SCH_1):PAGE71_I43@MSTR_DISCRETE.RES(CHIPS)':
 C_PATH='@baseboard_fab2_lib.baseboard_fab2(sch_1):page71_i43@mstr_discrete.res(~
chips)',
 P_PATH='@baseboard_fab2_lib.baseboard_fab2(sch_1):page71_i43@mstr_discrete.res(~
chips)',
 PATH='I43',
 DRAWING='@BASEBOARD_FAB2_LIB.BASEBOARD_FAB2(SCH_1):PAGE71',
 WATTAGE='1/16W',
 TOLERANCE='0.1%',
 SEC_TYPE='0402',
 MATERIAL='CHIP',
 BOM_COST='PROC_SOCKET',
 PHYS_PAGE='71',
 XY='(-500,750)',
 ROT='0',
 VER='2',
 VALUE='249',
 PACK_TYPE='0402',
 PART_NUMBER='G85996-031',
 LOCATION='R3D27',
 ROOM='CPU1',
 SEC='1',
 CDS_LIB='mstr_discrete',
 CDS_PART_NAME='RES_0402-249,0.1%,1/16W,CHIP,GA',
 PRIM_FILE='./archive_libs/mstr_discrete/res/chips/chips.prt';

PART_NAME
 R3D28 'RES_0402-100.0,1%,1/16W,CHIP,GA':
 ROOM='PVCCIO_CPU1';

SECTION_NUMBER 1
 '@BASEBOARD_FAB2_LIB.BASEBOARD_FAB2(SCH_1):PAGE214_I101@MSTR_DISCRETE.RES(CHIPS)':
 C_PATH='@baseboard_fab2_lib.baseboard_fab2(sch_1):page214_i101@mstr_discrete.re~
s(chips)',
 P_PATH='@baseboard_fab2_lib.baseboard_fab2(sch_1):page214_i101@mstr_discrete.re~
s(chips)',
 PATH='I101',
 DRAWING='@BASEBOARD_FAB2_LIB.BASEBOARD_FAB2(SCH_1):PAGE214',
 WATTAGE='1/16W',
 TOLERANCE='1%',
 SEC_TYPE='0402',
 MATERIAL='CHIP',
 BOM_COST='PROC_VRD_VCCIO_CPU1',
 PHYS_PAGE='214',
 XY='(-750,1050)',
 ROT='0',
 VER='1',
 VALUE='100.0',
 PACK_TYPE='0402',
 PART_NUMBER='G21796-017',
 LOCATION='R3D28',
 ROOM='PVCCIO_CPU1',
 SEC='1',
 CDS_LIB='mstr_discrete',
 CDS_PART_NAME='RES_0402-100.0,1%,1/16W,CHIP,GA',
 PRIM_FILE='./archive_libs/mstr_discrete/res/chips/chips.prt';

PART_NAME
 R3D31 'RES_0402-0.0,5%,1/16W,EMPTY,G2A':
 ROOM='BMC_MISC';

SECTION_NUMBER 1
 '@BASEBOARD_FAB2_LIB.BASEBOARD_FAB2(SCH_1):PAGE156_I300@MSTR_DISCRETE.RES(CHIPS)':
 C_PATH='@baseboard_fab2_lib.baseboard_fab2(sch_1):page156_i300@mstr_discrete.re~
s(chips)',
 P_PATH='@baseboard_fab2_lib.baseboard_fab2(sch_1):page156_i300@mstr_discrete.re~
s(chips)',
 PATH='I300',
 DRAWING='@BASEBOARD_FAB2_LIB.BASEBOARD_FAB2(SCH_1):PAGE156',
 WATTAGE='1/16W',
 TOLERANCE='5%',
 SEC_TYPE='0402',
 MATERIAL='EMPTY',
 BOM_COST='SM_CONTROLLER',
 PHYS_PAGE='156',
 XY='(-2900,1550)',
 ROT='0',
 VER='1',
 VALUE='0.0',
 PACK_TYPE='0402',
 PART_NUMBER='G21497-005',
 LOCATION='R3D31',
 ROOM='BMC_MISC',
 SEC='1',
 CDS_LIB='mstr_discrete',
 CDS_PART_NAME='RES_0402-0.0,5%,1/16W,EMPTY,G2A',
 PRIM_FILE='./archive_libs/mstr_discrete/res/chips/chips.prt';

PART_NAME
 R3D32 'RES_0402-10.0,1%,1/16W,EMPTY,GA':
 ROOM='CPU1';

SECTION_NUMBER 1
 '@BASEBOARD_FAB2_LIB.BASEBOARD_FAB2(SCH_1):PAGE71_I53@MSTR_DISCRETE.RES(CHIPS)':
 C_PATH='@baseboard_fab2_lib.baseboard_fab2(sch_1):page71_i53@mstr_discrete.res(~
chips)',
 P_PATH='@baseboard_fab2_lib.baseboard_fab2(sch_1):page71_i53@mstr_discrete.res(~
chips)',
 PATH='I53',
 DRAWING='@BASEBOARD_FAB2_LIB.BASEBOARD_FAB2(SCH_1):PAGE71',
 WATTAGE='1/16W',
 TOLERANCE='1%',
 SEC_TYPE='0402',
 MATERIAL='EMPTY',
 PHYS_PAGE='71',
 XY='(-500,1200)',
 ROT='0',
 VER='2',
 VALUE='10.0',
 PACK_TYPE='0402',
 PART_NUMBER='G21796-066',
 LOCATION='R3D32',
 ROOM='CPU1',
 SEC='1',
 CDS_LIB='mstr_discrete',
 CDS_PART_NAME='RES_0402-10.0,1%,1/16W,EMPTY,GA',
 PRIM_FILE='./archive_libs/mstr_discrete/res/chips/chips.prt';

PART_NAME
 R3E1 'RES_0402-100.0,1%,1/16W,CHIP,GA':
 ROOM='PVCCIO_CPU1';

SECTION_NUMBER 1
 '@BASEBOARD_FAB2_LIB.BASEBOARD_FAB2(SCH_1):PAGE214_I105@MSTR_DISCRETE.RES(CHIPS)':
 C_PATH='@baseboard_fab2_lib.baseboard_fab2(sch_1):page214_i105@mstr_discrete.re~
s(chips)',
 P_PATH='@baseboard_fab2_lib.baseboard_fab2(sch_1):page214_i105@mstr_discrete.re~
s(chips)',
 PATH='I105',
 DRAWING='@BASEBOARD_FAB2_LIB.BASEBOARD_FAB2(SCH_1):PAGE214',
 WATTAGE='1/16W',
 TOLERANCE='1%',
 SEC_TYPE='0402',
 MATERIAL='CHIP',
 BOM_COST='PROC_VRD_VCCIO_CPU1',
 PHYS_PAGE='214',
 XY='(-750,2250)',
 ROT='0',
 VER='1',
 VALUE='100.0',
 PACK_TYPE='0402',
 PART_NUMBER='G21796-017',
 LOCATION='R3E1',
 ROOM='PVCCIO_CPU1',
 SEC='1',
 CDS_LIB='mstr_discrete',
 CDS_PART_NAME='RES_0402-100.0,1%,1/16W,CHIP,GA',
 PRIM_FILE='./archive_libs/mstr_discrete/res/chips/chips.prt';

PART_NAME
 R3F1 'RES_0402-0.0,5%,1/16W,EMPTY,G2A':
 ROOM='CLOCK_CPU1_OSC',
 NO_XNET_CONNECTION='1';

SECTION_NUMBER 1
 '@BASEBOARD_FAB2_LIB.BASEBOARD_FAB2(SCH_1):PAGE104_I51@MSTR_DISCRETE.RES(CHIPS)':
 C_PATH='@baseboard_fab2_lib.baseboard_fab2(sch_1):page104_i51@mstr_discrete.res~
(chips)',
 P_PATH='@baseboard_fab2_lib.baseboard_fab2(sch_1):page104_i51@mstr_discrete.res~
(chips)',
 PATH='I51',
 DRAWING='@BASEBOARD_FAB2_LIB.BASEBOARD_FAB2(SCH_1):PAGE104',
 WATTAGE='1/16W',
 TOLERANCE='5%',
 SEC_TYPE='0402',
 MATERIAL='EMPTY',
 NO_XNET_CONNECTION='1',
 PHYS_PAGE='104',
 XY='(525,3625)',
 ROT='0',
 VER='1',
 VALUE='0.0',
 PACK_TYPE='0402',
 PART_NUMBER='G21497-005',
 LOCATION='R3F1',
 ROOM='CLOCK_CPU1_OSC',
 SEC='1',
 CDS_LIB='mstr_discrete',
 CDS_PART_NAME='RES_0402-0.0,5%,1/16W,EMPTY,G2A',
 PRIM_FILE='./archive_libs/mstr_discrete/res/chips/chips.prt';

PART_NAME
 R3F2 'RES_0402-0.0,5%,1/16W,CHIP,G21A':
 ROOM='CLOCK_CPU1_OSC',
 NO_XNET_CONNECTION='1';

SECTION_NUMBER 1
 '@BASEBOARD_FAB2_LIB.BASEBOARD_FAB2(SCH_1):PAGE104_I69@MSTR_DISCRETE.RES(CHIPS)':
 C_PATH='@baseboard_fab2_lib.baseboard_fab2(sch_1):page104_i69@mstr_discrete.res~
(chips)',
 P_PATH='@baseboard_fab2_lib.baseboard_fab2(sch_1):page104_i69@mstr_discrete.res~
(chips)',
 PATH='I69',
 DRAWING='@BASEBOARD_FAB2_LIB.BASEBOARD_FAB2(SCH_1):PAGE104',
 WATTAGE='1/16W',
 TOLERANCE='5%',
 SEC_TYPE='0402',
 MATERIAL='CHIP',
 NO_XNET_CONNECTION='1',
 PHYS_PAGE='104',
 XY='(525,3775)',
 ROT='0',
 VER='1',
 VALUE='0.0',
 PACK_TYPE='0402',
 PART_NUMBER='G21497-005',
 LOCATION='R3F2',
 ROOM='CLOCK_CPU1_OSC',
 SEC='1',
 CDS_LIB='mstr_discrete',
 CDS_PART_NAME='RES_0402-0.0,5%,1/16W,CHIP,G21A',
 PRIM_FILE='./archive_libs/mstr_discrete/res/chips/chips.prt';

PART_NAME
 R3F3 'RES_0402-0.0,5%,1/16W,EMPTY,G2A':
 ROOM='CLOCK_CPU1_OSC',
 NO_XNET_CONNECTION='1';

SECTION_NUMBER 1
 '@BASEBOARD_FAB2_LIB.BASEBOARD_FAB2(SCH_1):PAGE104_I53@MSTR_DISCRETE.RES(CHIPS)':
 C_PATH='@baseboard_fab2_lib.baseboard_fab2(sch_1):page104_i53@mstr_discrete.res~
(chips)',
 P_PATH='@baseboard_fab2_lib.baseboard_fab2(sch_1):page104_i53@mstr_discrete.res~
(chips)',
 PATH='I53',
 DRAWING='@BASEBOARD_FAB2_LIB.BASEBOARD_FAB2(SCH_1):PAGE104',
 WATTAGE='1/16W',
 TOLERANCE='5%',
 SEC_TYPE='0402',
 MATERIAL='EMPTY',
 NO_XNET_CONNECTION='1',
 PHYS_PAGE='104',
 XY='(525,2925)',
 ROT='0',
 VER='1',
 VALUE='0.0',
 PACK_TYPE='0402',
 PART_NUMBER='G21497-005',
 LOCATION='R3F3',
 ROOM='CLOCK_CPU1_OSC',
 SEC='1',
 CDS_LIB='mstr_discrete',
 CDS_PART_NAME='RES_0402-0.0,5%,1/16W,EMPTY,G2A',
 PRIM_FILE='./archive_libs/mstr_discrete/res/chips/chips.prt';

PART_NAME
 R3F4 'RES_0402-0.0,5%,1/16W,CHIP,G21A':
 ROOM='CLOCK_CPU1_OSC',
 NO_XNET_CONNECTION='1';

SECTION_NUMBER 1
 '@BASEBOARD_FAB2_LIB.BASEBOARD_FAB2(SCH_1):PAGE104_I70@MSTR_DISCRETE.RES(CHIPS)':
 C_PATH='@baseboard_fab2_lib.baseboard_fab2(sch_1):page104_i70@mstr_discrete.res~
(chips)',
 P_PATH='@baseboard_fab2_lib.baseboard_fab2(sch_1):page104_i70@mstr_discrete.res~
(chips)',
 PATH='I70',
 DRAWING='@BASEBOARD_FAB2_LIB.BASEBOARD_FAB2(SCH_1):PAGE104',
 WATTAGE='1/16W',
 TOLERANCE='5%',
 SEC_TYPE='0402',
 MATERIAL='CHIP',
 NO_XNET_CONNECTION='1',
 PHYS_PAGE='104',
 XY='(525,3075)',
 ROT='0',
 VER='1',
 VALUE='0.0',
 PACK_TYPE='0402',
 PART_NUMBER='G21497-005',
 LOCATION='R3F4',
 ROOM='CLOCK_CPU1_OSC',
 SEC='1',
 CDS_LIB='mstr_discrete',
 CDS_PART_NAME='RES_0402-0.0,5%,1/16W,CHIP,G21A',
 PRIM_FILE='./archive_libs/mstr_discrete/res/chips/chips.prt';

PART_NAME
 R3F5 'RES_0402-0.0,5%,1/16W,EMPTY,G2A':;

SECTION_NUMBER 1
 '@BASEBOARD_FAB2_LIB.BASEBOARD_FAB2(SCH_1):PAGE104_I84@MSTR_DISCRETE.RES(CHIPS)':
 C_PATH='@baseboard_fab2_lib.baseboard_fab2(sch_1):page104_i84@mstr_discrete.res~
(chips)',
 P_PATH='@baseboard_fab2_lib.baseboard_fab2(sch_1):page104_i84@mstr_discrete.res~
(chips)',
 PATH='I84',
 DRAWING='@BASEBOARD_FAB2_LIB.BASEBOARD_FAB2(SCH_1):PAGE104',
 WATTAGE='1/16W',
 TOLERANCE='5%',
 SEC_TYPE='0402',
 MATERIAL='EMPTY',
 PHYS_PAGE='104',
 XY='(525,3425)',
 ROT='0',
 VER='1',
 VALUE='0.0',
 PACK_TYPE='0402',
 PART_NUMBER='G21497-005',
 LOCATION='R3F5',
 SEC='1',
 CDS_LIB='mstr_discrete',
 CDS_PART_NAME='RES_0402-0.0,5%,1/16W,EMPTY,G2A',
 PRIM_FILE='./archive_libs/mstr_discrete/res/chips/chips.prt';

PART_NAME
 R3F6 'RES_0402-0.0,5%,1/16W,EMPTY,G2A':;

SECTION_NUMBER 1
 '@BASEBOARD_FAB2_LIB.BASEBOARD_FAB2(SCH_1):PAGE104_I88@MSTR_DISCRETE.RES(CHIPS)':
 C_PATH='@baseboard_fab2_lib.baseboard_fab2(sch_1):page104_i88@mstr_discrete.res~
(chips)',
 P_PATH='@baseboard_fab2_lib.baseboard_fab2(sch_1):page104_i88@mstr_discrete.res~
(chips)',
 PATH='I88',
 DRAWING='@BASEBOARD_FAB2_LIB.BASEBOARD_FAB2(SCH_1):PAGE104',
 WATTAGE='1/16W',
 TOLERANCE='5%',
 SEC_TYPE='0402',
 MATERIAL='EMPTY',
 PHYS_PAGE='104',
 XY='(525,2725)',
 ROT='0',
 VER='1',
 VALUE='0.0',
 PACK_TYPE='0402',
 PART_NUMBER='G21497-005',
 LOCATION='R3F6',
 SEC='1',
 CDS_LIB='mstr_discrete',
 CDS_PART_NAME='RES_0402-0.0,5%,1/16W,EMPTY,G2A',
 PRIM_FILE='./archive_libs/mstr_discrete/res/chips/chips.prt';

PART_NAME
 R3L1 'RES_0402-0.0,5%,1/16W,CHIP,G21A':
 ROOM='CPU0';

SECTION_NUMBER 1
 '@BASEBOARD_FAB2_LIB.BASEBOARD_FAB2(SCH_1):PAGE236_I175@MSTR_DISCRETE.RES(CHIPS)':
 C_PATH='@baseboard_fab2_lib.baseboard_fab2(sch_1):page236_i175@mstr_discrete.re~
s(chips)',
 P_PATH='@baseboard_fab2_lib.baseboard_fab2(sch_1):page236_i175@mstr_discrete.re~
s(chips)',
 PATH='I175',
 DRAWING='@BASEBOARD_FAB2_LIB.BASEBOARD_FAB2(SCH_1):PAGE236',
 WATTAGE='1/16W',
 TOLERANCE='5%',
 SEC_TYPE='0402',
 MATERIAL='CHIP',
 BOM_COST='PROC_SIDEBAND',
 PHYS_PAGE='236',
 XY='(7425,5050)',
 ROT='0',
 VER='1',
 VALUE='0.0',
 PACK_TYPE='0402',
 PART_NUMBER='G21497-005',
 LOCATION='R3L1',
 ROOM='CPU0',
 SEC='1',
 CDS_LIB='mstr_discrete',
 CDS_PART_NAME='RES_0402-0.0,5%,1/16W,CHIP,G21A',
 PRIM_FILE='./archive_libs/mstr_discrete/res/chips/chips.prt';

PART_NAME
 R3L4 'RES_0402-0.0,5%,1/16W,CHIP,G21A':
 ROOM='CPU0';

SECTION_NUMBER 1
 '@BASEBOARD_FAB2_LIB.BASEBOARD_FAB2(SCH_1):PAGE236_I177@MSTR_DISCRETE.RES(CHIPS)':
 C_PATH='@baseboard_fab2_lib.baseboard_fab2(sch_1):page236_i177@mstr_discrete.re~
s(chips)',
 P_PATH='@baseboard_fab2_lib.baseboard_fab2(sch_1):page236_i177@mstr_discrete.re~
s(chips)',
 PATH='I177',
 DRAWING='@BASEBOARD_FAB2_LIB.BASEBOARD_FAB2(SCH_1):PAGE236',
 WATTAGE='1/16W',
 TOLERANCE='5%',
 SEC_TYPE='0402',
 MATERIAL='CHIP',
 BOM_COST='PROC_SIDEBAND',
 PHYS_PAGE='236',
 XY='(7325,3300)',
 ROT='0',
 VER='1',
 VALUE='0.0',
 PACK_TYPE='0402',
 PART_NUMBER='G21497-005',
 LOCATION='R3L4',
 ROOM='CPU0',
 SEC='1',
 CDS_LIB='mstr_discrete',
 CDS_PART_NAME='RES_0402-0.0,5%,1/16W,CHIP,G21A',
 PRIM_FILE='./archive_libs/mstr_discrete/res/chips/chips.prt';

PART_NAME
 R3L6 'RES_0402-0.0,5%,1/16W,CHIP,G21A':
 ROOM='CPU0';

SECTION_NUMBER 1
 '@BASEBOARD_FAB2_LIB.BASEBOARD_FAB2(SCH_1):PAGE219_I147@MSTR_DISCRETE.RES(CHIPS)':
 C_PATH='@baseboard_fab2_lib.baseboard_fab2(sch_1):page219_i147@mstr_discrete.re~
s(chips)',
 P_PATH='@baseboard_fab2_lib.baseboard_fab2(sch_1):page219_i147@mstr_discrete.re~
s(chips)',
 PATH='I147',
 DRAWING='@BASEBOARD_FAB2_LIB.BASEBOARD_FAB2(SCH_1):PAGE219',
 WATTAGE='1/16W',
 TOLERANCE='5%',
 SEC_TYPE='0402',
 MATERIAL='CHIP',
 BOM_COST='PROC_SIDEBAND',
 PHYS_PAGE='219',
 XY='(-725,3000)',
 ROT='0',
 VER='1',
 VALUE='0.0',
 PACK_TYPE='0402',
 PART_NUMBER='G21497-005',
 LOCATION='R3L6',
 ROOM='CPU0',
 SEC='1',
 CDS_LIB='mstr_discrete',
 CDS_PART_NAME='RES_0402-0.0,5%,1/16W,CHIP,G21A',
 PRIM_FILE='./archive_libs/mstr_discrete/res/chips/chips.prt';

PART_NAME
 R3L8 'RES_0402-0.0,5%,1/16W,CHIP,G21A':
 ROOM='CPU0';

SECTION_NUMBER 1
 '@BASEBOARD_FAB2_LIB.BASEBOARD_FAB2(SCH_1):PAGE219_I148@MSTR_DISCRETE.RES(CHIPS)':
 C_PATH='@baseboard_fab2_lib.baseboard_fab2(sch_1):page219_i148@mstr_discrete.re~
s(chips)',
 P_PATH='@baseboard_fab2_lib.baseboard_fab2(sch_1):page219_i148@mstr_discrete.re~
s(chips)',
 PATH='I148',
 DRAWING='@BASEBOARD_FAB2_LIB.BASEBOARD_FAB2(SCH_1):PAGE219',
 BOM_SS='NOPOP',
 WATTAGE='1/16W',
 TOLERANCE='5%',
 SEC_TYPE='0402',
 MATERIAL='CHIP',
 BOM_COST='PROC_SIDEBAND',
 PHYS_PAGE='219',
 XY='(-775,700)',
 ROT='0',
 VER='1',
 VALUE='0.0',
 PACK_TYPE='0402',
 PART_NUMBER='G21497-005',
 LOCATION='R3L8',
 ROOM='CPU0',
 SEC='1',
 CDS_LIB='mstr_discrete',
 CDS_PART_NAME='RES_0402-0.0,5%,1/16W,CHIP,G21A',
 PRIM_FILE='./archive_libs/mstr_discrete/res/chips/chips.prt';

PART_NAME
 R3L11 'RES_0402-100.0,1%,1/16W,EMPTY,A':
 ROOM='VDDQ_DEF_PWR_VR';

SECTION_NUMBER 1
 '@BASEBOARD_FAB2_LIB.BASEBOARD_FAB2(SCH_1):PAGE218_I67@MSTR_DISCRETE.RES(CHIPS)':
 C_PATH='@baseboard_fab2_lib.baseboard_fab2(sch_1):page218_i67@mstr_discrete.res~
(chips)',
 P_PATH='@baseboard_fab2_lib.baseboard_fab2(sch_1):page218_i67@mstr_discrete.res~
(chips)',
 PATH='I67',
 DRAWING='@BASEBOARD_FAB2_LIB.BASEBOARD_FAB2(SCH_1):PAGE218',
 WATTAGE='1/16W',
 TOLERANCE='1%',
 SEC_TYPE='0402',
 MATERIAL='EMPTY',
 PHYS_PAGE='218',
 XY='(2700,2625)',
 ROT='0',
 VER='2',
 VALUE='100.0',
 PACK_TYPE='0402',
 PART_NUMBER='G21796-017',
 LOCATION='R3L11',
 ROOM='VDDQ_DEF_PWR_VR',
 SEC='1',
 CDS_LIB='mstr_discrete',
 CDS_PART_NAME='RES_0402-100.0,1%,1/16W,EMPTY,A',
 PRIM_FILE='./archive_libs/mstr_discrete/res/chips/chips.prt';

PART_NAME
 R3L13 'RES_0402-49.9,1%,1/16W,EMPTY,GA':
 ROOM='VDDQ_ABC_PWR_VR';

SECTION_NUMBER 1
 '@BASEBOARD_FAB2_LIB.BASEBOARD_FAB2(SCH_1):PAGE218_I70@MSTR_DISCRETE.RES(CHIPS)':
 C_PATH='@baseboard_fab2_lib.baseboard_fab2(sch_1):page218_i70@mstr_discrete.res~
(chips)',
 P_PATH='@baseboard_fab2_lib.baseboard_fab2(sch_1):page218_i70@mstr_discrete.res~
(chips)',
 PATH='I70',
 DRAWING='@BASEBOARD_FAB2_LIB.BASEBOARD_FAB2(SCH_1):PAGE218',
 WATTAGE='1/16W',
 TOLERANCE='1%',
 SEC_TYPE='0402',
 MATERIAL='EMPTY',
 PHYS_PAGE='218',
 XY='(-1900,3250)',
 ROT='0',
 VER='2',
 VALUE='49.9',
 PACK_TYPE='0402',
 PART_NUMBER='G21796-047',
 LOCATION='R3L13',
 ROOM='VDDQ_ABC_PWR_VR',
 SEC='1',
 CDS_LIB='mstr_discrete',
 CDS_PART_NAME='RES_0402-49.9,1%,1/16W,EMPTY,GA',
 PRIM_FILE='./archive_libs/mstr_discrete/res/chips/chips.prt';

PART_NAME
 R3L14 'RES_0402-68.1K,1%,1/16W,EMPTY,A':;

SECTION_NUMBER 1
 '@BASEBOARD_FAB2_LIB.BASEBOARD_FAB2(SCH_1):PAGE236_I120@MSTR_DISCRETE.RES(CHIPS)':
 C_PATH='@baseboard_fab2_lib.baseboard_fab2(sch_1):page236_i120@mstr_discrete.re~
s(chips)',
 P_PATH='@baseboard_fab2_lib.baseboard_fab2(sch_1):page236_i120@mstr_discrete.re~
s(chips)',
 PATH='I120',
 DRAWING='@BASEBOARD_FAB2_LIB.BASEBOARD_FAB2(SCH_1):PAGE236',
 WATTAGE='1/16W',
 TOLERANCE='1%',
 SEC_TYPE='0402',
 MATERIAL='EMPTY',
 PHYS_PAGE='236',
 XY='(12150,2700)',
 ROT='0',
 VER='2',
 VALUE='68.1K',
 PACK_TYPE='0402',
 PART_NUMBER='G21796-187',
 LOCATION='R3L14',
 SEC='1',
 CDS_LIB='mstr_discrete',
 CDS_PART_NAME='RES_0402-68.1K,1%,1/16W,EMPTY,A',
 PRIM_FILE='./archive_libs/mstr_discrete/res/chips/chips.prt';

PART_NAME
 R3L15 'RES_0402-68.1K,1%,1/16W,EMPTY,A':;

SECTION_NUMBER 1
 '@BASEBOARD_FAB2_LIB.BASEBOARD_FAB2(SCH_1):PAGE236_I118@MSTR_DISCRETE.RES(CHIPS)':
 C_PATH='@baseboard_fab2_lib.baseboard_fab2(sch_1):page236_i118@mstr_discrete.re~
s(chips)',
 P_PATH='@baseboard_fab2_lib.baseboard_fab2(sch_1):page236_i118@mstr_discrete.re~
s(chips)',
 PATH='I118',
 DRAWING='@BASEBOARD_FAB2_LIB.BASEBOARD_FAB2(SCH_1):PAGE236',
 WATTAGE='1/16W',
 TOLERANCE='1%',
 SEC_TYPE='0402',
 MATERIAL='EMPTY',
 PHYS_PAGE='236',
 XY='(12125,4450)',
 ROT='0',
 VER='2',
 VALUE='68.1K',
 PACK_TYPE='0402',
 PART_NUMBER='G21796-187',
 LOCATION='R3L15',
 SEC='1',
 CDS_LIB='mstr_discrete',
 CDS_PART_NAME='RES_0402-68.1K,1%,1/16W,EMPTY,A',
 PRIM_FILE='./archive_libs/mstr_discrete/res/chips/chips.prt';

PART_NAME
 R3M1 'RES_0402-0.0,5%,1/16W,CHIP,G21A':
 ROOM='VDDQ_DEF_PWR_VR';

SECTION_NUMBER 1
 '@BASEBOARD_FAB2_LIB.BASEBOARD_FAB2(SCH_1):PAGE218_I35@MSTR_DISCRETE.RES(CHIPS)':
 C_PATH='@baseboard_fab2_lib.baseboard_fab2(sch_1):page218_i35@mstr_discrete.res~
(chips)',
 P_PATH='@baseboard_fab2_lib.baseboard_fab2(sch_1):page218_i35@mstr_discrete.res~
(chips)',
 PATH='I35',
 DRAWING='@BASEBOARD_FAB2_LIB.BASEBOARD_FAB2(SCH_1):PAGE218',
 WATTAGE='1/16W',
 TOLERANCE='5%',
 SEC_TYPE='0402',
 MATERIAL='CHIP',
 PHYS_PAGE='218',
 XY='(-450,3150)',
 ROT='0',
 VER='2',
 VALUE='0.0',
 PACK_TYPE='0402',
 PART_NUMBER='G21497-005',
 LOCATION='R3M1',
 ROOM='VDDQ_DEF_PWR_VR',
 SEC='1',
 CDS_LIB='mstr_discrete',
 CDS_PART_NAME='RES_0402-0.0,5%,1/16W,CHIP,G21A',
 PRIM_FILE='./archive_libs/mstr_discrete/res/chips/chips.prt';

PART_NAME
 R3M3 'RES_0402-22.1,1.0%,1/16W,CHIP,A':
 ROOM='VDDQ_DEF_PWR_VR';

SECTION_NUMBER 1
 '@BASEBOARD_FAB2_LIB.BASEBOARD_FAB2(SCH_1):PAGE218_I60@MSTR_DISCRETE.RES(CHIPS)':
 C_PATH='@baseboard_fab2_lib.baseboard_fab2(sch_1):page218_i60@mstr_discrete.res~
(chips)',
 P_PATH='@baseboard_fab2_lib.baseboard_fab2(sch_1):page218_i60@mstr_discrete.res~
(chips)',
 PATH='I60',
 DRAWING='@BASEBOARD_FAB2_LIB.BASEBOARD_FAB2(SCH_1):PAGE218',
 POP='NOPOP',
 WATTAGE='1/16W',
 TOLERANCE='1.0%',
 SEC_TYPE='0402',
 MATERIAL='CHIP',
 PHYS_PAGE='218',
 XY='(1925,2250)',
 ROT='0',
 VER='1',
 VALUE='22.1',
 PACK_TYPE='0402',
 PART_NUMBER='G21796-250',
 LOCATION='R3M3',
 ROOM='VDDQ_DEF_PWR_VR',
 SEC='1',
 CDS_LIB='mstr_discrete',
 CDS_PART_NAME='RES_0402-22.1,1.0%,1/16W,CHIP,A',
 PRIM_FILE='./archive_libs/mstr_discrete/res/chips/chips.prt';

PART_NAME
 R3M5 'RES_0402-100.0K,1%,1/16W,EMPTYA':
 ROOM='VDDQ_DEF_PWR_VR';

SECTION_NUMBER 1
 '@BASEBOARD_FAB2_LIB.BASEBOARD_FAB2(SCH_1):PAGE218_I34@MSTR_DISCRETE.RES(CHIPS)':
 C_PATH='@baseboard_fab2_lib.baseboard_fab2(sch_1):page218_i34@mstr_discrete.res~
(chips)',
 P_PATH='@baseboard_fab2_lib.baseboard_fab2(sch_1):page218_i34@mstr_discrete.res~
(chips)',
 PATH='I34',
 DRAWING='@BASEBOARD_FAB2_LIB.BASEBOARD_FAB2(SCH_1):PAGE218',
 WATTAGE='1/16W',
 TOLERANCE='1%',
 SEC_TYPE='0402',
 MATERIAL='EMPTY',
 BOM_COST='SM_CONTROLLER',
 PHYS_PAGE='218',
 XY='(-1150,3225)',
 ROT='0',
 VER='2',
 VALUE='100.0K',
 PACK_TYPE='0402',
 PART_NUMBER='G21796-010',
 LOCATION='R3M5',
 ROOM='VDDQ_DEF_PWR_VR',
 SEC='1',
 CDS_LIB='mstr_discrete',
 CDS_PART_NAME='RES_0402-100.0K,1%,1/16W,EMPTYA',
 PRIM_FILE='./archive_libs/mstr_discrete/res/chips/chips.prt';

PART_NAME
 R3M6 'RES_0402-0.0,5%,1/16W,CHIP,G21A':
 ROOM='VDDQ_DEF_PWR_VR';

SECTION_NUMBER 1
 '@BASEBOARD_FAB2_LIB.BASEBOARD_FAB2(SCH_1):PAGE218_I15@MSTR_DISCRETE.RES(CHIPS)':
 C_PATH='@baseboard_fab2_lib.baseboard_fab2(sch_1):page218_i15@mstr_discrete.res~
(chips)',
 P_PATH='@baseboard_fab2_lib.baseboard_fab2(sch_1):page218_i15@mstr_discrete.res~
(chips)',
 PATH='I15',
 DRAWING='@BASEBOARD_FAB2_LIB.BASEBOARD_FAB2(SCH_1):PAGE218',
 WATTAGE='1/16W',
 TOLERANCE='5%',
 SEC_TYPE='0402',
 MATERIAL='CHIP',
 PHYS_PAGE='218',
 XY='(-2900,1200)',
 ROT='0',
 VER='1',
 VALUE='0.0',
 PACK_TYPE='0402',
 PART_NUMBER='G21497-005',
 LOCATION='R3M6',
 ROOM='VDDQ_DEF_PWR_VR',
 SEC='1',
 CDS_LIB='mstr_discrete',
 CDS_PART_NAME='RES_0402-0.0,5%,1/16W,CHIP,G21A',
 PRIM_FILE='./archive_libs/mstr_discrete/res/chips/chips.prt';

PART_NAME
 R3M8 'RES_0402-100.0K,1%,1/16W,CHIP,A':
 ROOM='SB';

SECTION_NUMBER 1
 '@BASEBOARD_FAB2_LIB.BASEBOARD_FAB2(SCH_1):PAGE116_I235@MSTR_DISCRETE.RES(CHIPS)':
 C_PATH='@baseboard_fab2_lib.baseboard_fab2(sch_1):page116_i235@mstr_discrete.re~
s(chips)',
 P_PATH='@baseboard_fab2_lib.baseboard_fab2(sch_1):page116_i235@mstr_discrete.re~
s(chips)',
 PATH='I235',
 DRAWING='@BASEBOARD_FAB2_LIB.BASEBOARD_FAB2(SCH_1):PAGE116',
 POP='NOPOP',
 WATTAGE='1/16W',
 TOLERANCE='1%',
 MATERIAL='CHIP',
 PHYS_PAGE='116',
 XY='(-5900,750)',
 ROT='0',
 VER='2',
 VALUE='100.0K',
 PACK_TYPE='0402',
 PART_NUMBER='G21796-010',
 LOCATION='R3M8',
 ROOM='SB',
 CDS_LIB='mstr_discrete',
 CDS_PART_NAME='RES_0402-100.0K,1%,1/16W,CHIP,A',
 PRIM_FILE='./archive_libs/mstr_discrete/res/chips/chips.prt';

PART_NAME
 R3M9 'RES_0402-100.0K,1%,1/16W,CHIP,A':
 ROOM='SB';

SECTION_NUMBER 1
 '@BASEBOARD_FAB2_LIB.BASEBOARD_FAB2(SCH_1):PAGE116_I234@MSTR_DISCRETE.RES(CHIPS)':
 C_PATH='@baseboard_fab2_lib.baseboard_fab2(sch_1):page116_i234@mstr_discrete.re~
s(chips)',
 P_PATH='@baseboard_fab2_lib.baseboard_fab2(sch_1):page116_i234@mstr_discrete.re~
s(chips)',
 PATH='I234',
 DRAWING='@BASEBOARD_FAB2_LIB.BASEBOARD_FAB2(SCH_1):PAGE116',
 POP='NOPOP',
 WATTAGE='1/16W',
 TOLERANCE='1%',
 MATERIAL='CHIP',
 PHYS_PAGE='116',
 XY='(-6250,750)',
 ROT='0',
 VER='2',
 VALUE='100.0K',
 PACK_TYPE='0402',
 PART_NUMBER='G21796-010',
 LOCATION='R3M9',
 ROOM='SB',
 CDS_LIB='mstr_discrete',
 CDS_PART_NAME='RES_0402-100.0K,1%,1/16W,CHIP,A',
 PRIM_FILE='./archive_libs/mstr_discrete/res/chips/chips.prt';

PART_NAME
 R3M10 'RES_0402-1.00K,1%,1/16W,CHIP,GA':
 ROOM='DEBUG';

SECTION_NUMBER 1
 '@BASEBOARD_FAB2_LIB.BASEBOARD_FAB2(SCH_1):PAGE112_I85@MSTR_DISCRETE.RES(CHIPS)':
 C_PATH='@baseboard_fab2_lib.baseboard_fab2(sch_1):page112_i85@mstr_discrete.res~
(chips)',
 P_PATH='@baseboard_fab2_lib.baseboard_fab2(sch_1):page112_i85@mstr_discrete.res~
(chips)',
 PATH='I85',
 DRAWING='@BASEBOARD_FAB2_LIB.BASEBOARD_FAB2(SCH_1):PAGE112',
 WATTAGE='1/16W',
 TOLERANCE='1%',
 SEC_TYPE='0402',
 MATERIAL='CHIP',
 BOM_COST='DEBUG',
 PHYS_PAGE='112',
 XY='(-1950,3600)',
 ROT='0',
 VER='2',
 VALUE='1.00K',
 PACK_TYPE='0402',
 PART_NUMBER='G21796-026',
 LOCATION='R3M10',
 ROOM='DEBUG',
 SEC='1',
 CDS_LIB='mstr_discrete',
 CDS_PART_NAME='RES_0402-1.00K,1%,1/16W,CHIP,GA',
 PRIM_FILE='./archive_libs/mstr_discrete/res/chips/chips.prt';

PART_NAME
 R3M11 'RES_0402-100.0,1%,1/16W,CHIP,GA':
 ROOM='SB',
 NO_XNET_CONNECTION='1';

SECTION_NUMBER 1
 '@BASEBOARD_FAB2_LIB.BASEBOARD_FAB2(SCH_1):PAGE116_I108@MSTR_DISCRETE.RES(CHIPS)':
 C_PATH='@baseboard_fab2_lib.baseboard_fab2(sch_1):page116_i108@mstr_discrete.re~
s(chips)',
 P_PATH='@baseboard_fab2_lib.baseboard_fab2(sch_1):page116_i108@mstr_discrete.re~
s(chips)',
 PATH='I108',
 DRAWING='@BASEBOARD_FAB2_LIB.BASEBOARD_FAB2(SCH_1):PAGE116',
 WATTAGE='1/16W',
 TOLERANCE='1%',
 SEC_TYPE='0402',
 MATERIAL='CHIP',
 NO_XNET_CONNECTION='1',
 PHYS_PAGE='116',
 XY='(-7550,2150)',
 ROT='2',
 VER='2',
 VALUE='100.0',
 PACK_TYPE='0402',
 PART_NUMBER='G21796-017',
 LOCATION='R3M11',
 ROOM='SB',
 SEC='1',
 CDS_LIB='mstr_discrete',
 CDS_PART_NAME='RES_0402-100.0,1%,1/16W,CHIP,GA',
 PRIM_FILE='./archive_libs/mstr_discrete/res/chips/chips.prt';

PART_NAME
 R3M12 'RES_0402-100.0,1%,1/16W,CHIP,GA':
 ROOM='SB',
 NO_XNET_CONNECTION='1';

SECTION_NUMBER 1
 '@BASEBOARD_FAB2_LIB.BASEBOARD_FAB2(SCH_1):PAGE116_I181@MSTR_DISCRETE.RES(CHIPS)':
 C_PATH='@baseboard_fab2_lib.baseboard_fab2(sch_1):page116_i181@mstr_discrete.re~
s(chips)',
 P_PATH='@baseboard_fab2_lib.baseboard_fab2(sch_1):page116_i181@mstr_discrete.re~
s(chips)',
 PATH='I181',
 DRAWING='@BASEBOARD_FAB2_LIB.BASEBOARD_FAB2(SCH_1):PAGE116',
 WATTAGE='1/16W',
 TOLERANCE='1%',
 SEC_TYPE='0402',
 MATERIAL='CHIP',
 NO_XNET_CONNECTION='1',
 PHYS_PAGE='116',
 XY='(-7125,2150)',
 ROT='2',
 VER='2',
 VALUE='100.0',
 PACK_TYPE='0402',
 PART_NUMBER='G21796-017',
 LOCATION='R3M12',
 ROOM='SB',
 SEC='1',
 CDS_LIB='mstr_discrete',
 CDS_PART_NAME='RES_0402-100.0,1%,1/16W,CHIP,GA',
 PRIM_FILE='./archive_libs/mstr_discrete/res/chips/chips.prt';

PART_NAME
 R3N1 'RES_0402-169,1.0%,1/16W,CHIP,GA':
 ROOM='SB';

SECTION_NUMBER 1
 '@BASEBOARD_FAB2_LIB.BASEBOARD_FAB2(SCH_1):PAGE114_I149@MSTR_DISCRETE.RES(CHIPS)':
 C_PATH='@baseboard_fab2_lib.baseboard_fab2(sch_1):page114_i149@mstr_discrete.re~
s(chips)',
 P_PATH='@baseboard_fab2_lib.baseboard_fab2(sch_1):page114_i149@mstr_discrete.re~
s(chips)',
 PATH='I149',
 DRAWING='@BASEBOARD_FAB2_LIB.BASEBOARD_FAB2(SCH_1):PAGE114',
 WATTAGE='1/16W',
 TOLERANCE='1.0%',
 SEC_TYPE='0402',
 MATERIAL='CHIP',
 PHYS_PAGE='114',
 XY='(-3150,2750)',
 ROT='0',
 VER='2',
 VALUE='169',
 PACK_TYPE='0402',
 PART_NUMBER='G21796-276',
 LOCATION='R3N1',
 ROOM='SB',
 SEC='1',
 CDS_LIB='mstr_discrete',
 CDS_PART_NAME='RES_0402-169,1.0%,1/16W,CHIP,GA',
 PRIM_FILE='./archive_libs/mstr_discrete/res/chips/chips.prt';

PART_NAME
 R3N2 'RES_0402-4.75K,1%,1/16W,EMPTY,A':
 ROOM='BMC_MISC';

SECTION_NUMBER 1
 '@BASEBOARD_FAB2_LIB.BASEBOARD_FAB2(SCH_1):PAGE125_I72@MSTR_DISCRETE.RES(CHIPS)':
 C_PATH='@baseboard_fab2_lib.baseboard_fab2(sch_1):page125_i72@mstr_discrete.res~
(chips)',
 P_PATH='@baseboard_fab2_lib.baseboard_fab2(sch_1):page125_i72@mstr_discrete.res~
(chips)',
 PATH='I72',
 DRAWING='@BASEBOARD_FAB2_LIB.BASEBOARD_FAB2(SCH_1):PAGE125',
 WATTAGE='1/16W',
 TOLERANCE='1%',
 SEC_TYPE='0402',
 MATERIAL='EMPTY',
 BOM_COST='SB',
 PHYS_PAGE='125',
 XY='(400,4600)',
 ROT='0',
 VER='2',
 VALUE='4.75K',
 PACK_TYPE='0402',
 PART_NUMBER='G21796-072',
 LOCATION='R3N2',
 ROOM='BMC_MISC',
 SEC='1',
 CDS_LIB='mstr_discrete',
 CDS_PART_NAME='RES_0402-4.75K,1%,1/16W,EMPTY,A',
 PRIM_FILE='./archive_libs/mstr_discrete/res/chips/chips.prt';

PART_NAME
 R3N3 'RES_0402-2.0K,1%,1/16W,CHIP,G2A':
 ROOM='SB';

SECTION_NUMBER 1
 '@BASEBOARD_FAB2_LIB.BASEBOARD_FAB2(SCH_1):PAGE133_I120@MSTR_DISCRETE.RES(CHIPS)':
 C_PATH='@baseboard_fab2_lib.baseboard_fab2(sch_1):page133_i120@mstr_discrete.re~
s(chips)',
 P_PATH='@baseboard_fab2_lib.baseboard_fab2(sch_1):page133_i120@mstr_discrete.re~
s(chips)',
 PATH='I120',
 DRAWING='@BASEBOARD_FAB2_LIB.BASEBOARD_FAB2(SCH_1):PAGE133',
 WATTAGE='1/16W',
 TOLERANCE='1%',
 MATERIAL='CHIP',
 BOM_COST='SB',
 PHYS_PAGE='133',
 XY='(-2500,3850)',
 ROT='0',
 VER='1',
 VALUE='2.0K',
 PACK_TYPE='0402',
 PART_NUMBER='G21796-001',
 LOCATION='R3N3',
 ROOM='SB',
 CDS_LIB='mstr_discrete',
 CDS_PART_NAME='RES_0402-2.0K,1%,1/16W,CHIP,G2A',
 PRIM_FILE='./archive_libs/mstr_discrete/res/chips/chips.prt';

PART_NAME
 R3N4 'RES_0402-20.0K,1%,1/16W,CHIP,GA':
 ROOM='SB',
 NO_XNET_CONNECTION='1';

SECTION_NUMBER 1
 '@BASEBOARD_FAB2_LIB.BASEBOARD_FAB2(SCH_1):PAGE137_I19@MSTR_DISCRETE.RES(CHIPS)':
 C_PATH='@baseboard_fab2_lib.baseboard_fab2(sch_1):page137_i19@mstr_discrete.res~
(chips)',
 P_PATH='@baseboard_fab2_lib.baseboard_fab2(sch_1):page137_i19@mstr_discrete.res~
(chips)',
 PATH='I19',
 DRAWING='@BASEBOARD_FAB2_LIB.BASEBOARD_FAB2(SCH_1):PAGE137',
 WATTAGE='1/16W',
 TOLERANCE='1%',
 MATERIAL='CHIP',
 BOM_COST='SB',
 NO_XNET_CONNECTION='1',
 PHYS_PAGE='137',
 XY='(-300,1900)',
 ROT='0',
 VER='2',
 VALUE='20.0K',
 PACK_TYPE='0402',
 PART_NUMBER='G21796-040',
 LOCATION='R3N4',
 ROOM='SB',
 CDS_LIB='mstr_discrete',
 CDS_PART_NAME='RES_0402-20.0K,1%,1/16W,CHIP,GA',
 PRIM_FILE='./archive_libs/mstr_discrete/res/chips/chips.prt';

PART_NAME
 R3N7 'RES_0402-0.0,5%,1/16W,CHIP,G21A':
 ROOM='CPU0';

SECTION_NUMBER 1
 '@BASEBOARD_FAB2_LIB.BASEBOARD_FAB2(SCH_1):PAGE212_I140@MSTR_DISCRETE.RES(CHIPS)':
 C_PATH='@baseboard_fab2_lib.baseboard_fab2(sch_1):page212_i140@mstr_discrete.re~
s(chips)',
 P_PATH='@baseboard_fab2_lib.baseboard_fab2(sch_1):page212_i140@mstr_discrete.re~
s(chips)',
 PATH='I140',
 DRAWING='@BASEBOARD_FAB2_LIB.BASEBOARD_FAB2(SCH_1):PAGE212',
 WATTAGE='1/16W',
 TOLERANCE='5%',
 SEC_TYPE='0402',
 MATERIAL='CHIP',
 BOM_COST='PROC_SIDEBAND',
 PHYS_PAGE='212',
 XY='(-1200,4750)',
 ROT='0',
 VER='1',
 VALUE='0.0',
 PACK_TYPE='0402',
 PART_NUMBER='G21497-005',
 LOCATION='R3N7',
 ROOM='CPU0',
 SEC='1',
 CDS_LIB='mstr_discrete',
 CDS_PART_NAME='RES_0402-0.0,5%,1/16W,CHIP,G21A',
 PRIM_FILE='./archive_libs/mstr_discrete/res/chips/chips.prt';

PART_NAME
 R3N9 'RES_0402-10.0,1%,1/16W,CHIP,G2A':
 ROOM='SB';

SECTION_NUMBER 1
 '@BASEBOARD_FAB2_LIB.BASEBOARD_FAB2(SCH_1):PAGE118_I66@MSTR_DISCRETE.RES(CHIPS)':
 C_PATH='@baseboard_fab2_lib.baseboard_fab2(sch_1):page118_i66@mstr_discrete.res~
(chips)',
 P_PATH='@baseboard_fab2_lib.baseboard_fab2(sch_1):page118_i66@mstr_discrete.res~
(chips)',
 PATH='I66',
 DRAWING='@BASEBOARD_FAB2_LIB.BASEBOARD_FAB2(SCH_1):PAGE118',
 WATTAGE='1/16W',
 TOLERANCE='1%',
 SEC_TYPE='0402',
 MATERIAL='CHIP',
 BOM_COST='SB',
 PHYS_PAGE='118',
 XY='(-1575,2675)',
 ROT='0',
 VER='1',
 VALUE='10.0',
 PACK_TYPE='0402',
 PART_NUMBER='G21796-066',
 LOCATION='R3N9',
 ROOM='SB',
 SEC='1',
 CDS_LIB='mstr_discrete',
 CDS_PART_NAME='RES_0402-10.0,1%,1/16W,CHIP,G2A',
 PRIM_FILE='./archive_libs/mstr_discrete/res/chips/chips.prt';

PART_NAME
 R3N10 'RES_0402-10.0K,1%,1/16W,CHIP,GA':
 ROOM='SB';

SECTION_NUMBER 1
 '@BASEBOARD_FAB2_LIB.BASEBOARD_FAB2(SCH_1):PAGE121_I37@MSTR_DISCRETE.RES(CHIPS)':
 C_PATH='@baseboard_fab2_lib.baseboard_fab2(sch_1):page121_i37@mstr_discrete.res~
(chips)',
 P_PATH='@baseboard_fab2_lib.baseboard_fab2(sch_1):page121_i37@mstr_discrete.res~
(chips)',
 PATH='I37',
 DRAWING='@BASEBOARD_FAB2_LIB.BASEBOARD_FAB2(SCH_1):PAGE121',
 WATTAGE='1/16W',
 TOLERANCE='1%',
 SEC_TYPE='0402',
 MATERIAL='CHIP',
 PHYS_PAGE='121',
 XY='(-8075,2525)',
 ROT='0',
 VER='2',
 VALUE='10.0K',
 PACK_TYPE='0402',
 PART_NUMBER='G21796-016',
 LOCATION='R3N10',
 ROOM='SB',
 SEC='1',
 CDS_LIB='mstr_discrete',
 CDS_PART_NAME='RES_0402-10.0K,1%,1/16W,CHIP,GA',
 PRIM_FILE='./archive_libs/mstr_discrete/res/chips/chips.prt';

PART_NAME
 R3N11 'RES_0402-4.75K,1%,1/16W,CHIP,GA':
 ROOM='BMC_MISC';

SECTION_NUMBER 1
 '@BASEBOARD_FAB2_LIB.BASEBOARD_FAB2(SCH_1):PAGE157_I344@MSTR_DISCRETE.RES(CHIPS)':
 C_PATH='@baseboard_fab2_lib.baseboard_fab2(sch_1):page157_i344@mstr_discrete.re~
s(chips)',
 P_PATH='@baseboard_fab2_lib.baseboard_fab2(sch_1):page157_i344@mstr_discrete.re~
s(chips)',
 PATH='I344',
 DRAWING='@BASEBOARD_FAB2_LIB.BASEBOARD_FAB2(SCH_1):PAGE157',
 WATTAGE='1/16W',
 TOLERANCE='1%',
 SEC_TYPE='0402',
 MATERIAL='CHIP',
 BOM_COST='SM_CONTROLLER',
 PHYS_PAGE='157',
 XY='(-7175,2875)',
 ROT='0',
 VER='1',
 VALUE='4.75K',
 PACK_TYPE='0402',
 PART_NUMBER='G21796-072',
 LOCATION='R3N11',
 ROOM='BMC_MISC',
 SEC='1',
 CDS_LIB='mstr_discrete',
 CDS_PART_NAME='RES_0402-4.75K,1%,1/16W,CHIP,GA',
 PRIM_FILE='./archive_libs/mstr_discrete/res/chips/chips.prt';

PART_NAME
 R3N12 'RES_0402-4.75K,1%,1/16W,CHIP,GA':
 ROOM='BMC_MISC';

SECTION_NUMBER 1
 '@BASEBOARD_FAB2_LIB.BASEBOARD_FAB2(SCH_1):PAGE157_I342@MSTR_DISCRETE.RES(CHIPS)':
 C_PATH='@baseboard_fab2_lib.baseboard_fab2(sch_1):page157_i342@mstr_discrete.re~
s(chips)',
 P_PATH='@baseboard_fab2_lib.baseboard_fab2(sch_1):page157_i342@mstr_discrete.re~
s(chips)',
 PATH='I342',
 DRAWING='@BASEBOARD_FAB2_LIB.BASEBOARD_FAB2(SCH_1):PAGE157',
 WATTAGE='1/16W',
 TOLERANCE='1%',
 SEC_TYPE='0402',
 MATERIAL='CHIP',
 BOM_COST='SM_CONTROLLER',
 PHYS_PAGE='157',
 XY='(-7175,3100)',
 ROT='0',
 VER='1',
 VALUE='4.75K',
 PACK_TYPE='0402',
 PART_NUMBER='G21796-072',
 LOCATION='R3N12',
 ROOM='BMC_MISC',
 SEC='1',
 CDS_LIB='mstr_discrete',
 CDS_PART_NAME='RES_0402-4.75K,1%,1/16W,CHIP,GA',
 PRIM_FILE='./archive_libs/mstr_discrete/res/chips/chips.prt';

PART_NAME
 R3N13 'RES_0402-4.75K,1%,1/16W,CHIP,GA':
 ROOM='SB';

SECTION_NUMBER 1
 '@BASEBOARD_FAB2_LIB.BASEBOARD_FAB2(SCH_1):PAGE118_I71@MSTR_DISCRETE.RES(CHIPS)':
 C_PATH='@baseboard_fab2_lib.baseboard_fab2(sch_1):page118_i71@mstr_discrete.res~
(chips)',
 P_PATH='@baseboard_fab2_lib.baseboard_fab2(sch_1):page118_i71@mstr_discrete.res~
(chips)',
 PATH='I71',
 DRAWING='@BASEBOARD_FAB2_LIB.BASEBOARD_FAB2(SCH_1):PAGE118',
 WATTAGE='1/16W',
 TOLERANCE='1%',
 SEC_TYPE='0402',
 MATERIAL='CHIP',
 BOM_COST='SB',
 PHYS_PAGE='118',
 XY='(-2300,4650)',
 ROT='0',
 VER='2',
 VALUE='4.75K',
 PACK_TYPE='0402',
 PART_NUMBER='G21796-072',
 LOCATION='R3N13',
 ROOM='SB',
 SEC='1',
 CDS_LIB='mstr_discrete',
 CDS_PART_NAME='RES_0402-4.75K,1%,1/16W,CHIP,GA',
 PRIM_FILE='./archive_libs/mstr_discrete/res/chips/chips.prt';

PART_NAME
 R3N14 'RES_0402-49.9,1%,1/16W,EMPTY,GA':
 ROOM='SB';

SECTION_NUMBER 1
 '@BASEBOARD_FAB2_LIB.BASEBOARD_FAB2(SCH_1):PAGE118_I67@MSTR_DISCRETE.RES(CHIPS)':
 C_PATH='@baseboard_fab2_lib.baseboard_fab2(sch_1):page118_i67@mstr_discrete.res~
(chips)',
 P_PATH='@baseboard_fab2_lib.baseboard_fab2(sch_1):page118_i67@mstr_discrete.res~
(chips)',
 PATH='I67',
 DRAWING='@BASEBOARD_FAB2_LIB.BASEBOARD_FAB2(SCH_1):PAGE118',
 WATTAGE='1/16W',
 TOLERANCE='1%',
 SEC_TYPE='0402',
 MATERIAL='EMPTY',
 BOM_COST='SB',
 PHYS_PAGE='118',
 XY='(-1075,2475)',
 ROT='0',
 VER='2',
 VALUE='49.9',
 PACK_TYPE='0402',
 PART_NUMBER='G21796-047',
 LOCATION='R3N14',
 ROOM='SB',
 SEC='1',
 CDS_LIB='mstr_discrete',
 CDS_PART_NAME='RES_0402-49.9,1%,1/16W,EMPTY,GA',
 PRIM_FILE='./archive_libs/mstr_discrete/res/chips/chips.prt';

PART_NAME
 R3N15 'RES_0402-1.00K,1%,1/16W,EMPTY,A':
 ROOM='DEBUG';

SECTION_NUMBER 1
 '@BASEBOARD_FAB2_LIB.BASEBOARD_FAB2(SCH_1):PAGE133_I368@MSTR_DISCRETE.RES(CHIPS)':
 C_PATH='@baseboard_fab2_lib.baseboard_fab2(sch_1):page133_i368@mstr_discrete.re~
s(chips)',
 P_PATH='@baseboard_fab2_lib.baseboard_fab2(sch_1):page133_i368@mstr_discrete.re~
s(chips)',
 PATH='I368',
 DRAWING='@BASEBOARD_FAB2_LIB.BASEBOARD_FAB2(SCH_1):PAGE133',
 WATTAGE='1/16W',
 TOLERANCE='1%',
 SEC_TYPE='0402',
 MATERIAL='EMPTY',
 PHYS_PAGE='133',
 XY='(-375,4400)',
 ROT='3',
 VER='2',
 VALUE='1.00K',
 PACK_TYPE='0402',
 PART_NUMBER='G21796-026',
 LOCATION='R3N15',
 ROOM='DEBUG',
 SEC='1',
 CDS_LIB='mstr_discrete',
 CDS_PART_NAME='RES_0402-1.00K,1%,1/16W,EMPTY,A',
 PRIM_FILE='./archive_libs/mstr_discrete/res/chips/chips.prt';

PART_NAME
 R3N16 'RES_0402-1.00K,1%,1/16W,EMPTY,A':
 ROOM='DEBUG';

SECTION_NUMBER 1
 '@BASEBOARD_FAB2_LIB.BASEBOARD_FAB2(SCH_1):PAGE133_I369@MSTR_DISCRETE.RES(CHIPS)':
 C_PATH='@baseboard_fab2_lib.baseboard_fab2(sch_1):page133_i369@mstr_discrete.re~
s(chips)',
 P_PATH='@baseboard_fab2_lib.baseboard_fab2(sch_1):page133_i369@mstr_discrete.re~
s(chips)',
 PATH='I369',
 DRAWING='@BASEBOARD_FAB2_LIB.BASEBOARD_FAB2(SCH_1):PAGE133',
 WATTAGE='1/16W',
 TOLERANCE='1%',
 SEC_TYPE='0402',
 MATERIAL='EMPTY',
 PHYS_PAGE='133',
 XY='(-375,4175)',
 ROT='3',
 VER='2',
 VALUE='1.00K',
 PACK_TYPE='0402',
 PART_NUMBER='G21796-026',
 LOCATION='R3N16',
 ROOM='DEBUG',
 SEC='1',
 CDS_LIB='mstr_discrete',
 CDS_PART_NAME='RES_0402-1.00K,1%,1/16W,EMPTY,A',
 PRIM_FILE='./archive_libs/mstr_discrete/res/chips/chips.prt';

PART_NAME
 R3N17 'RES_0402-1.00K,1%,1/16W,EMPTY,A':
 ROOM='SB';

SECTION_NUMBER 1
 '@BASEBOARD_FAB2_LIB.BASEBOARD_FAB2(SCH_1):PAGE125_I78@MSTR_DISCRETE.RES(CHIPS)':
 C_PATH='@baseboard_fab2_lib.baseboard_fab2(sch_1):page125_i78@mstr_discrete.res~
(chips)',
 P_PATH='@baseboard_fab2_lib.baseboard_fab2(sch_1):page125_i78@mstr_discrete.res~
(chips)',
 PATH='I78',
 DRAWING='@BASEBOARD_FAB2_LIB.BASEBOARD_FAB2(SCH_1):PAGE125',
 WATTAGE='1/16W',
 TOLERANCE='1%',
 SEC_TYPE='0402',
 MATERIAL='EMPTY',
 BOM_COST='SB',
 PHYS_PAGE='125',
 XY='(1850,1875)',
 ROT='0',
 VER='2',
 VALUE='1.00K',
 PACK_TYPE='0402',
 PART_NUMBER='G21796-026',
 LOCATION='R3N17',
 ROOM='SB',
 SEC='1',
 CDS_LIB='mstr_discrete',
 CDS_PART_NAME='RES_0402-1.00K,1%,1/16W,EMPTY,A',
 PRIM_FILE='./archive_libs/mstr_discrete/res/chips/chips.prt';

PART_NAME
 R3N19 'RES_0402-10.0,1%,1/16W,CHIP,G2A':
 ROOM='PVCCIO_CPU0';

SECTION_NUMBER 1
 '@BASEBOARD_FAB2_LIB.BASEBOARD_FAB2(SCH_1):PAGE211_I81@MSTR_DISCRETE.RES(CHIPS)':
 C_PATH='@baseboard_fab2_lib.baseboard_fab2(sch_1):page211_i81@mstr_discrete.res~
(chips)',
 P_PATH='@baseboard_fab2_lib.baseboard_fab2(sch_1):page211_i81@mstr_discrete.res~
(chips)',
 PATH='I81',
 DRAWING='@BASEBOARD_FAB2_LIB.BASEBOARD_FAB2(SCH_1):PAGE211',
 WATTAGE='1/16W',
 TOLERANCE='1%',
 SEC_TYPE='0402',
 MATERIAL='CHIP',
 PHYS_PAGE='211',
 XY='(-2600,2050)',
 ROT='0',
 VER='1',
 VALUE='10.0',
 PACK_TYPE='0402',
 PART_NUMBER='G21796-066',
 LOCATION='R3N19',
 ROOM='PVCCIO_CPU0',
 SEC='1',
 CDS_LIB='mstr_discrete',
 CDS_PART_NAME='RES_0402-10.0,1%,1/16W,CHIP,G2A',
 PRIM_FILE='./archive_libs/mstr_discrete/res/chips/chips.prt';

PART_NAME
 R3N20 'RES_0402-100.0,1%,1/16W,CHIP,GA':
 ROOM='PVCCIO_CPU0';

SECTION_NUMBER 1
 '@BASEBOARD_FAB2_LIB.BASEBOARD_FAB2(SCH_1):PAGE212_I68@MSTR_DISCRETE.RES(CHIPS)':
 C_PATH='@baseboard_fab2_lib.baseboard_fab2(sch_1):page212_i68@mstr_discrete.res~
(chips)',
 P_PATH='@baseboard_fab2_lib.baseboard_fab2(sch_1):page212_i68@mstr_discrete.res~
(chips)',
 PATH='I68',
 DRAWING='@BASEBOARD_FAB2_LIB.BASEBOARD_FAB2(SCH_1):PAGE212',
 WATTAGE='1/16W',
 TOLERANCE='1%',
 SEC_TYPE='0402',
 MATERIAL='CHIP',
 BOM_COST='PROC_VRD_PVCCIO_CPU0',
 PHYS_PAGE='212',
 XY='(-725,1150)',
 ROT='0',
 VER='1',
 VALUE='100.0',
 PACK_TYPE='0402',
 PART_NUMBER='G21796-017',
 LOCATION='R3N20',
 ROOM='PVCCIO_CPU0',
 SEC='1',
 CDS_LIB='mstr_discrete',
 CDS_PART_NAME='RES_0402-100.0,1%,1/16W,CHIP,GA',
 PRIM_FILE='./archive_libs/mstr_discrete/res/chips/chips.prt';

PART_NAME
 R3N21 'RES_0402-100.0,1%,1/16W,CHIP,GA':
 ROOM='PVCCIO_CPU0';

SECTION_NUMBER 1
 '@BASEBOARD_FAB2_LIB.BASEBOARD_FAB2(SCH_1):PAGE212_I74@MSTR_DISCRETE.RES(CHIPS)':
 C_PATH='@baseboard_fab2_lib.baseboard_fab2(sch_1):page212_i74@mstr_discrete.res~
(chips)',
 P_PATH='@baseboard_fab2_lib.baseboard_fab2(sch_1):page212_i74@mstr_discrete.res~
(chips)',
 PATH='I74',
 DRAWING='@BASEBOARD_FAB2_LIB.BASEBOARD_FAB2(SCH_1):PAGE212',
 WATTAGE='1/16W',
 TOLERANCE='1%',
 SEC_TYPE='0402',
 MATERIAL='CHIP',
 BOM_COST='PROC_VRD_PVCCIO_CPU0',
 PHYS_PAGE='212',
 XY='(-725,2325)',
 ROT='0',
 VER='1',
 VALUE='100.0',
 PACK_TYPE='0402',
 PART_NUMBER='G21796-017',
 LOCATION='R3N21',
 ROOM='PVCCIO_CPU0',
 SEC='1',
 CDS_LIB='mstr_discrete',
 CDS_PART_NAME='RES_0402-100.0,1%,1/16W,CHIP,GA',
 PRIM_FILE='./archive_libs/mstr_discrete/res/chips/chips.prt';

PART_NAME
 R3N22 'RES_0402-4.02K,1%,1/16W,CHIP,GA':
 ROOM='PVCCIN_CPU0_VR';

SECTION_NUMBER 1
 '@BASEBOARD_FAB2_LIB.BASEBOARD_FAB2(SCH_1):PAGE211_I102@MSTR_DISCRETE.RES(CHIPS)':
 C_PATH='@baseboard_fab2_lib.baseboard_fab2(sch_1):page211_i102@mstr_discrete.re~
s(chips)',
 P_PATH='@baseboard_fab2_lib.baseboard_fab2(sch_1):page211_i102@mstr_discrete.re~
s(chips)',
 PATH='I102',
 DRAWING='@BASEBOARD_FAB2_LIB.BASEBOARD_FAB2(SCH_1):PAGE211',
 WATTAGE='1/16W',
 TOLERANCE='1%',
 SEC_TYPE='0402',
 MATERIAL='CHIP',
 PHYS_PAGE='211',
 XY='(-575,1200)',
 ROT='0',
 VER='2',
 VALUE='4.02K',
 PACK_TYPE='0402',
 PART_NUMBER='G21796-082',
 LOCATION='R3N22',
 ROOM='PVCCIN_CPU0_VR',
 SEC='1',
 CDS_LIB='mstr_discrete',
 CDS_PART_NAME='RES_0402-4.02K,1%,1/16W,CHIP,GA',
 PRIM_FILE='./archive_libs/mstr_discrete/res/chips/chips.prt';

PART_NAME
 R3N23 'RES_0402-2.26K,1.0%,1/16W,EMPTA':
 ROOM='PVCCIO_CPU0';

SECTION_NUMBER 1
 '@BASEBOARD_FAB2_LIB.BASEBOARD_FAB2(SCH_1):PAGE211_I60@MSTR_DISCRETE.RES(CHIPS)':
 C_PATH='@baseboard_fab2_lib.baseboard_fab2(sch_1):page211_i60@mstr_discrete.res~
(chips)',
 P_PATH='@baseboard_fab2_lib.baseboard_fab2(sch_1):page211_i60@mstr_discrete.res~
(chips)',
 PATH='I60',
 DRAWING='@BASEBOARD_FAB2_LIB.BASEBOARD_FAB2(SCH_1):PAGE211',
 WATTAGE='1/16W',
 TOLERANCE='1.0%',
 SEC_TYPE='0402',
 MATERIAL='EMPTY',
 PHYS_PAGE='211',
 XY='(1525,4100)',
 ROT='0',
 VER='2',
 VALUE='2.26K',
 PACK_TYPE='0402',
 PART_NUMBER='G21796-311',
 LOCATION='R3N23',
 ROOM='PVCCIO_CPU0',
 SEC='1',
 CDS_LIB='mstr_discrete',
 CDS_PART_NAME='RES_0402-2.26K,1.0%,1/16W,EMPTA',
 PRIM_FILE='./archive_libs/mstr_discrete/res/chips/chips.prt';

PART_NAME
 R3N24 'RES_0402-33.2,1%,1/16W,CHIP,G2A':
 ROOM='BMC';

SECTION_NUMBER 1
 '@BASEBOARD_FAB2_LIB.BASEBOARD_FAB2(SCH_1):PAGE146_I74@MSTR_DISCRETE.RES(CHIPS)':
 C_PATH='@baseboard_fab2_lib.baseboard_fab2(sch_1):page146_i74@mstr_discrete.res~
(chips)',
 P_PATH='@baseboard_fab2_lib.baseboard_fab2(sch_1):page146_i74@mstr_discrete.res~
(chips)',
 PATH='I74',
 DRAWING='@BASEBOARD_FAB2_LIB.BASEBOARD_FAB2(SCH_1):PAGE146',
 WATTAGE='1/16W',
 TOLERANCE='1%',
 SEC_TYPE='0402',
 MATERIAL='CHIP',
 BOM_COST='SB',
 PHYS_PAGE='146',
 XY='(-6850,1350)',
 ROT='0',
 VER='1',
 VALUE='33.2',
 PACK_TYPE='0402',
 PART_NUMBER='G21796-074',
 LOCATION='R3N24',
 ROOM='BMC',
 SEC='1',
 CDS_LIB='mstr_discrete',
 CDS_PART_NAME='RES_0402-33.2,1%,1/16W,CHIP,G2A',
 PRIM_FILE='./archive_libs/mstr_discrete/res/chips/chips.prt';

PART_NAME
 R3N26 'RES_0402-33.2,1%,1/16W,CHIP,G2A':
 ROOM='BMC';

SECTION_NUMBER 1
 '@BASEBOARD_FAB2_LIB.BASEBOARD_FAB2(SCH_1):PAGE146_I75@MSTR_DISCRETE.RES(CHIPS)':
 C_PATH='@baseboard_fab2_lib.baseboard_fab2(sch_1):page146_i75@mstr_discrete.res~
(chips)',
 P_PATH='@baseboard_fab2_lib.baseboard_fab2(sch_1):page146_i75@mstr_discrete.res~
(chips)',
 PATH='I75',
 DRAWING='@BASEBOARD_FAB2_LIB.BASEBOARD_FAB2(SCH_1):PAGE146',
 WATTAGE='1/16W',
 TOLERANCE='1%',
 SEC_TYPE='0402',
 MATERIAL='CHIP',
 BOM_COST='SB',
 PHYS_PAGE='146',
 XY='(-6850,1250)',
 ROT='0',
 VER='1',
 VALUE='33.2',
 PACK_TYPE='0402',
 PART_NUMBER='G21796-074',
 LOCATION='R3N26',
 ROOM='BMC',
 SEC='1',
 CDS_LIB='mstr_discrete',
 CDS_PART_NAME='RES_0402-33.2,1%,1/16W,CHIP,G2A',
 PRIM_FILE='./archive_libs/mstr_discrete/res/chips/chips.prt';

PART_NAME
 R3N29 'RES_0402-16K,1.0%,1/16W,CHIP,GA':
 GROUP='MCP',
 ROOM='VDDQ_ABC_PWR_VR';

SECTION_NUMBER 1
 '@BASEBOARD_FAB2_LIB.BASEBOARD_FAB2(SCH_1):PAGE194_I156@MSTR_DISCRETE.RES(CHIPS)':
 C_PATH='@baseboard_fab2_lib.baseboard_fab2(sch_1):page194_i156@mstr_discrete.re~
s(chips)',
 P_PATH='@baseboard_fab2_lib.baseboard_fab2(sch_1):page194_i156@mstr_discrete.re~
s(chips)',
 PATH='I156',
 DRAWING='@BASEBOARD_FAB2_LIB.BASEBOARD_FAB2(SCH_1):PAGE194',
 WATTAGE='1/16W',
 TOLERANCE='1.0%',
 SEC_TYPE='0402',
 MATERIAL='CHIP',
 PHYS_PAGE='194',
 XY='(-8175,125)',
 ROT='0',
 VER='2',
 VALUE='16K',
 PACK_TYPE='0402',
 PART_NUMBER='G21796-317',
 LOCATION='R3N29',
 ROOM='VDDQ_ABC_PWR_VR',
 GROUP='MCP',
 SEC='1',
 CDS_LIB='mstr_discrete',
 CDS_PART_NAME='RES_0402-16K,1.0%,1/16W,CHIP,GA',
 PRIM_FILE='./archive_libs/mstr_discrete/res/chips/chips.prt';

PART_NAME
 R3N30 'RES_0402-0.0,5%,1/16W,EMPTY,G2A':;

SECTION_NUMBER 1
 '@BASEBOARD_FAB2_LIB.BASEBOARD_FAB2(SCH_1):PAGE152_I95@MSTR_DISCRETE.RES(CHIPS)':
 C_PATH='@baseboard_fab2_lib.baseboard_fab2(sch_1):page152_i95@mstr_discrete.res~
(chips)',
 P_PATH='@baseboard_fab2_lib.baseboard_fab2(sch_1):page152_i95@mstr_discrete.res~
(chips)',
 PATH='I95',
 DRAWING='@BASEBOARD_FAB2_LIB.BASEBOARD_FAB2(SCH_1):PAGE152',
 WATTAGE='1/16W',
 TOLERANCE='5%',
 SEC_TYPE='0402',
 MATERIAL='EMPTY',
 PHYS_PAGE='152',
 XY='(-6700,2275)',
 ROT='0',
 VER='1',
 VALUE='0.0',
 PACK_TYPE='0402',
 PART_NUMBER='G21497-005',
 LOCATION='R3N30',
 SEC='1',
 CDS_LIB='mstr_discrete',
 CDS_PART_NAME='RES_0402-0.0,5%,1/16W,EMPTY,G2A',
 PRIM_FILE='./archive_libs/mstr_discrete/res/chips/chips.prt';

PART_NAME
 R3N31 'RES_0402-3.16K,1%,1/16W,CHIP,GA':
 ROOM='PVCCIO_CPU0';

SECTION_NUMBER 1
 '@BASEBOARD_FAB2_LIB.BASEBOARD_FAB2(SCH_1):PAGE211_I52@MSTR_DISCRETE.RES(CHIPS)':
 C_PATH='@baseboard_fab2_lib.baseboard_fab2(sch_1):page211_i52@mstr_discrete.res~
(chips)',
 P_PATH='@baseboard_fab2_lib.baseboard_fab2(sch_1):page211_i52@mstr_discrete.res~
(chips)',
 PATH='I52',
 DRAWING='@BASEBOARD_FAB2_LIB.BASEBOARD_FAB2(SCH_1):PAGE211',
 WATTAGE='1/16W',
 TOLERANCE='1%',
 SEC_TYPE='0402',
 MATERIAL='CHIP',
 PHYS_PAGE='211',
 XY='(-925,1200)',
 ROT='0',
 VER='2',
 VALUE='3.16K',
 PACK_TYPE='0402',
 PART_NUMBER='G21796-043',
 LOCATION='R3N31',
 ROOM='PVCCIO_CPU0',
 SEC='1',
 CDS_LIB='mstr_discrete',
 CDS_PART_NAME='RES_0402-3.16K,1%,1/16W,CHIP,GA',
 PRIM_FILE='./archive_libs/mstr_discrete/res/chips/chips.prt';

PART_NAME
 R3P1 'RES_0402-0.0,5%,1/16W,CHIP,G21A':
 ROOM='PVCCIO_CPU0';

SECTION_NUMBER 1
 '@BASEBOARD_FAB2_LIB.BASEBOARD_FAB2(SCH_1):PAGE211_I61@MSTR_DISCRETE.RES(CHIPS)':
 C_PATH='@baseboard_fab2_lib.baseboard_fab2(sch_1):page211_i61@mstr_discrete.res~
(chips)',
 P_PATH='@baseboard_fab2_lib.baseboard_fab2(sch_1):page211_i61@mstr_discrete.res~
(chips)',
 PATH='I61',
 DRAWING='@BASEBOARD_FAB2_LIB.BASEBOARD_FAB2(SCH_1):PAGE211',
 WATTAGE='1/16W',
 TOLERANCE='5%',
 SEC_TYPE='0402',
 MATERIAL='CHIP',
 PHYS_PAGE='211',
 XY='(1375,3150)',
 ROT='0',
 VER='1',
 VALUE='0.0',
 PACK_TYPE='0402',
 PART_NUMBER='G21497-005',
 LOCATION='R3P1',
 ROOM='PVCCIO_CPU0',
 SEC='1',
 CDS_LIB='mstr_discrete',
 CDS_PART_NAME='RES_0402-0.0,5%,1/16W,CHIP,G21A',
 PRIM_FILE='./archive_libs/mstr_discrete/res/chips/chips.prt';

PART_NAME
 R3P2 'RES_0402-0.0,5%,1/16W,CHIP,G21A':;

SECTION_NUMBER 1
 '@BASEBOARD_FAB2_LIB.BASEBOARD_FAB2(SCH_1):PAGE121_I90@MSTR_DISCRETE.RES(CHIPS)':
 C_PATH='@baseboard_fab2_lib.baseboard_fab2(sch_1):page121_i90@mstr_discrete.res~
(chips)',
 P_PATH='@baseboard_fab2_lib.baseboard_fab2(sch_1):page121_i90@mstr_discrete.res~
(chips)',
 PATH='I90',
 DRAWING='@BASEBOARD_FAB2_LIB.BASEBOARD_FAB2(SCH_1):PAGE121',
 WATTAGE='1/16W',
 TOLERANCE='5%',
 SEC_TYPE='0402',
 MATERIAL='CHIP',
 PHYS_PAGE='121',
 XY='(-5100,850)',
 ROT='0',
 VER='1',
 VALUE='0.0',
 PACK_TYPE='0402',
 PART_NUMBER='G21497-005',
 LOCATION='R3P2',
 SEC='1',
 CDS_LIB='mstr_discrete',
 CDS_PART_NAME='RES_0402-0.0,5%,1/16W,CHIP,G21A',
 PRIM_FILE='./archive_libs/mstr_discrete/res/chips/chips.prt';

PART_NAME
 R3P3 'RES_0402-0.0,5%,1/16W,CHIP,G21A':;

SECTION_NUMBER 1
 '@BASEBOARD_FAB2_LIB.BASEBOARD_FAB2(SCH_1):PAGE121_I89@MSTR_DISCRETE.RES(CHIPS)':
 C_PATH='@baseboard_fab2_lib.baseboard_fab2(sch_1):page121_i89@mstr_discrete.res~
(chips)',
 P_PATH='@baseboard_fab2_lib.baseboard_fab2(sch_1):page121_i89@mstr_discrete.res~
(chips)',
 PATH='I89',
 DRAWING='@BASEBOARD_FAB2_LIB.BASEBOARD_FAB2(SCH_1):PAGE121',
 WATTAGE='1/16W',
 TOLERANCE='5%',
 SEC_TYPE='0402',
 MATERIAL='CHIP',
 PHYS_PAGE='121',
 XY='(-5100,550)',
 ROT='0',
 VER='1',
 VALUE='0.0',
 PACK_TYPE='0402',
 PART_NUMBER='G21497-005',
 LOCATION='R3P3',
 SEC='1',
 CDS_LIB='mstr_discrete',
 CDS_PART_NAME='RES_0402-0.0,5%,1/16W,CHIP,G21A',
 PRIM_FILE='./archive_libs/mstr_discrete/res/chips/chips.prt';

PART_NAME
 R3P5 'RES_0402-1.00K,1%,1/16W,EMPTY,A':
 ROOM='DEBUG';

SECTION_NUMBER 1
 '@BASEBOARD_FAB2_LIB.BASEBOARD_FAB2(SCH_1):PAGE133_I366@MSTR_DISCRETE.RES(CHIPS)':
 C_PATH='@baseboard_fab2_lib.baseboard_fab2(sch_1):page133_i366@mstr_discrete.re~
s(chips)',
 P_PATH='@baseboard_fab2_lib.baseboard_fab2(sch_1):page133_i366@mstr_discrete.re~
s(chips)',
 PATH='I366',
 DRAWING='@BASEBOARD_FAB2_LIB.BASEBOARD_FAB2(SCH_1):PAGE133',
 WATTAGE='1/16W',
 TOLERANCE='1%',
 SEC_TYPE='0402',
 MATERIAL='EMPTY',
 PHYS_PAGE='133',
 XY='(-400,4875)',
 ROT='3',
 VER='2',
 VALUE='1.00K',
 PACK_TYPE='0402',
 PART_NUMBER='G21796-026',
 LOCATION='R3P5',
 ROOM='DEBUG',
 SEC='1',
 CDS_LIB='mstr_discrete',
 CDS_PART_NAME='RES_0402-1.00K,1%,1/16W,EMPTY,A',
 PRIM_FILE='./archive_libs/mstr_discrete/res/chips/chips.prt';

PART_NAME
 R3P6 'RES_0402-1.00K,1%,1/16W,EMPTY,A':
 ROOM='DEBUG';

SECTION_NUMBER 1
 '@BASEBOARD_FAB2_LIB.BASEBOARD_FAB2(SCH_1):PAGE133_I367@MSTR_DISCRETE.RES(CHIPS)':
 C_PATH='@baseboard_fab2_lib.baseboard_fab2(sch_1):page133_i367@mstr_discrete.re~
s(chips)',
 P_PATH='@baseboard_fab2_lib.baseboard_fab2(sch_1):page133_i367@mstr_discrete.re~
s(chips)',
 PATH='I367',
 DRAWING='@BASEBOARD_FAB2_LIB.BASEBOARD_FAB2(SCH_1):PAGE133',
 WATTAGE='1/16W',
 TOLERANCE='1%',
 SEC_TYPE='0402',
 MATERIAL='EMPTY',
 PHYS_PAGE='133',
 XY='(-375,4650)',
 ROT='3',
 VER='2',
 VALUE='1.00K',
 PACK_TYPE='0402',
 PART_NUMBER='G21796-026',
 LOCATION='R3P6',
 ROOM='DEBUG',
 SEC='1',
 CDS_LIB='mstr_discrete',
 CDS_PART_NAME='RES_0402-1.00K,1%,1/16W,EMPTY,A',
 PRIM_FILE='./archive_libs/mstr_discrete/res/chips/chips.prt';

PART_NAME
 R3P7 'RES_0402-1.00K,1%,1/16W,EMPTY,A':
 ROOM='DEBUG';

SECTION_NUMBER 1
 '@BASEBOARD_FAB2_LIB.BASEBOARD_FAB2(SCH_1):PAGE133_I370@MSTR_DISCRETE.RES(CHIPS)':
 C_PATH='@baseboard_fab2_lib.baseboard_fab2(sch_1):page133_i370@mstr_discrete.re~
s(chips)',
 P_PATH='@baseboard_fab2_lib.baseboard_fab2(sch_1):page133_i370@mstr_discrete.re~
s(chips)',
 PATH='I370',
 DRAWING='@BASEBOARD_FAB2_LIB.BASEBOARD_FAB2(SCH_1):PAGE133',
 WATTAGE='1/16W',
 TOLERANCE='1%',
 SEC_TYPE='0402',
 MATERIAL='EMPTY',
 PHYS_PAGE='133',
 XY='(-400,5100)',
 ROT='3',
 VER='2',
 VALUE='1.00K',
 PACK_TYPE='0402',
 PART_NUMBER='G21796-026',
 LOCATION='R3P7',
 ROOM='DEBUG',
 SEC='1',
 CDS_LIB='mstr_discrete',
 CDS_PART_NAME='RES_0402-1.00K,1%,1/16W,EMPTY,A',
 PRIM_FILE='./archive_libs/mstr_discrete/res/chips/chips.prt';

PART_NAME
 R3P8 'RES_0402-1.00K,1%,1/16W,CHIP,GA':
 ROOM='SB';

SECTION_NUMBER 1
 '@BASEBOARD_FAB2_LIB.BASEBOARD_FAB2(SCH_1):PAGE133_I322@MSTR_DISCRETE.RES(CHIPS)':
 C_PATH='@baseboard_fab2_lib.baseboard_fab2(sch_1):page133_i322@mstr_discrete.re~
s(chips)',
 P_PATH='@baseboard_fab2_lib.baseboard_fab2(sch_1):page133_i322@mstr_discrete.re~
s(chips)',
 PATH='I322',
 DRAWING='@BASEBOARD_FAB2_LIB.BASEBOARD_FAB2(SCH_1):PAGE133',
 WATTAGE='1/16W',
 TOLERANCE='1%',
 SEC_TYPE='0402',
 MATERIAL='CHIP',
 BOM_COST='SB',
 PHYS_PAGE='133',
 XY='(-375,3925)',
 ROT='0',
 VER='1',
 VALUE='1.00K',
 PACK_TYPE='0402',
 PART_NUMBER='G21796-026',
 LOCATION='R3P8',
 ROOM='SB',
 SEC='1',
 CDS_LIB='mstr_discrete',
 CDS_PART_NAME='RES_0402-1.00K,1%,1/16W,CHIP,GA',
 PRIM_FILE='./archive_libs/mstr_discrete/res/chips/chips.prt';

PART_NAME
 R3P11 'RES_0402-0.0,5%,1/16W,CHIP,G21A':
 ROOM='PVCCIO_CPU0';

SECTION_NUMBER 1
 '@BASEBOARD_FAB2_LIB.BASEBOARD_FAB2(SCH_1):PAGE211_I16@MSTR_DISCRETE.RES(CHIPS)':
 C_PATH='@baseboard_fab2_lib.baseboard_fab2(sch_1):page211_i16@mstr_discrete.res~
(chips)',
 P_PATH='@baseboard_fab2_lib.baseboard_fab2(sch_1):page211_i16@mstr_discrete.res~
(chips)',
 PATH='I16',
 DRAWING='@BASEBOARD_FAB2_LIB.BASEBOARD_FAB2(SCH_1):PAGE211',
 WATTAGE='1/16W',
 TOLERANCE='5%',
 SEC_TYPE='0402',
 MATERIAL='CHIP',
 PHYS_PAGE='211',
 XY='(-1250,2950)',
 ROT='0',
 VER='1',
 VALUE='0.0',
 PACK_TYPE='0402',
 PART_NUMBER='G21497-005',
 LOCATION='R3P11',
 ROOM='PVCCIO_CPU0',
 SEC='1',
 CDS_LIB='mstr_discrete',
 CDS_PART_NAME='RES_0402-0.0,5%,1/16W,CHIP,G21A',
 PRIM_FILE='./archive_libs/mstr_discrete/res/chips/chips.prt';

PART_NAME
 R3P12 'RES_0402-100.0K,1%,1/16W,CHIP,B':
 ROOM='PVCCIO_CPU0',
 NO_XNET_CONNECTION='1';

SECTION_NUMBER 1
 '@BASEBOARD_FAB2_LIB.BASEBOARD_FAB2(SCH_1):PAGE211_I31@MSTR_DISCRETE.RES(CHIPS)':
 C_PATH='@baseboard_fab2_lib.baseboard_fab2(sch_1):page211_i31@mstr_discrete.res~
(chips)',
 P_PATH='@baseboard_fab2_lib.baseboard_fab2(sch_1):page211_i31@mstr_discrete.res~
(chips)',
 PATH='I31',
 DRAWING='@BASEBOARD_FAB2_LIB.BASEBOARD_FAB2(SCH_1):PAGE211',
 WATTAGE='1/16W',
 TOLERANCE='1%',
 SEC_TYPE='0402',
 MATERIAL='CHIP',
 NO_XNET_CONNECTION='1',
 PHYS_PAGE='211',
 XY='(-2500,4650)',
 ROT='0',
 VER='2',
 VALUE='100.0K',
 PACK_TYPE='0402',
 PART_NUMBER='G21796-160',
 LOCATION='R3P12',
 ROOM='PVCCIO_CPU0',
 SEC='1',
 CDS_LIB='mstr_discrete',
 CDS_PART_NAME='RES_0402-100.0K,1%,1/16W,CHIP,B',
 PRIM_FILE='./archive_libs/mstr_discrete/res/chips/chips.prt';

PART_NAME
 R3P13 'RES_0402-100.0,1%,1/16W,CHIP,GA':
 ROOM='PVCCIN_CPU0_VR';

SECTION_NUMBER 1
 '@BASEBOARD_FAB2_LIB.BASEBOARD_FAB2(SCH_1):PAGE211_I100@MSTR_DISCRETE.RES(CHIPS)':
 C_PATH='@baseboard_fab2_lib.baseboard_fab2(sch_1):page211_i100@mstr_discrete.re~
s(chips)',
 P_PATH='@baseboard_fab2_lib.baseboard_fab2(sch_1):page211_i100@mstr_discrete.re~
s(chips)',
 PATH='I100',
 DRAWING='@BASEBOARD_FAB2_LIB.BASEBOARD_FAB2(SCH_1):PAGE211',
 WATTAGE='1/16W',
 TOLERANCE='1%',
 SEC_TYPE='0402',
 MATERIAL='CHIP',
 PHYS_PAGE='211',
 XY='(-1600,4500)',
 ROT='0',
 VER='2',
 VALUE='100.0',
 PACK_TYPE='0402',
 PART_NUMBER='G21796-017',
 LOCATION='R3P13',
 ROOM='PVCCIN_CPU0_VR',
 SEC='1',
 CDS_LIB='mstr_discrete',
 CDS_PART_NAME='RES_0402-100.0,1%,1/16W,CHIP,GA',
 PRIM_FILE='./archive_libs/mstr_discrete/res/chips/chips.prt';

PART_NAME
 R3P15 'RES_0402-150.0,1%,1/16W,CHIP,GA':
 ROOM='PVCCIO_CPU0';

SECTION_NUMBER 1
 '@BASEBOARD_FAB2_LIB.BASEBOARD_FAB2(SCH_1):PAGE211_I29@MSTR_DISCRETE.RES(CHIPS)':
 C_PATH='@baseboard_fab2_lib.baseboard_fab2(sch_1):page211_i29@mstr_discrete.res~
(chips)',
 P_PATH='@baseboard_fab2_lib.baseboard_fab2(sch_1):page211_i29@mstr_discrete.res~
(chips)',
 PATH='I29',
 DRAWING='@BASEBOARD_FAB2_LIB.BASEBOARD_FAB2(SCH_1):PAGE211',
 WATTAGE='1/16W',
 TOLERANCE='1%',
 SEC_TYPE='0402',
 MATERIAL='CHIP',
 PHYS_PAGE='211',
 XY='(-1975,3975)',
 ROT='0',
 VER='1',
 VALUE='150.0',
 PACK_TYPE='0402',
 PART_NUMBER='G21796-009',
 LOCATION='R3P15',
 ROOM='PVCCIO_CPU0',
 SEC='1',
 CDS_LIB='mstr_discrete',
 CDS_PART_NAME='RES_0402-150.0,1%,1/16W,CHIP,GA',
 PRIM_FILE='./archive_libs/mstr_discrete/res/chips/chips.prt';

PART_NAME
 R3P16 'RES_0402-1.5K,1%,1/16W,CHIP,G2A':
 ROOM='PVCCIO_CPU0';

SECTION_NUMBER 1
 '@BASEBOARD_FAB2_LIB.BASEBOARD_FAB2(SCH_1):PAGE211_I32@MSTR_DISCRETE.RES(CHIPS)':
 C_PATH='@baseboard_fab2_lib.baseboard_fab2(sch_1):page211_i32@mstr_discrete.res~
(chips)',
 P_PATH='@baseboard_fab2_lib.baseboard_fab2(sch_1):page211_i32@mstr_discrete.res~
(chips)',
 PATH='I32',
 DRAWING='@BASEBOARD_FAB2_LIB.BASEBOARD_FAB2(SCH_1):PAGE211',
 WATTAGE='1/16W',
 TOLERANCE='1%',
 SEC_TYPE='0402',
 MATERIAL='CHIP',
 PHYS_PAGE='211',
 XY='(-2500,4300)',
 ROT='0',
 VER='2',
 VALUE='1.5K',
 PACK_TYPE='0402',
 PART_NUMBER='G21796-003',
 LOCATION='R3P16',
 ROOM='PVCCIO_CPU0',
 SEC='1',
 CDS_LIB='mstr_discrete',
 CDS_PART_NAME='RES_0402-1.5K,1%,1/16W,CHIP,G2A',
 PRIM_FILE='./archive_libs/mstr_discrete/res/chips/chips.prt';

PART_NAME
 R3P17 'RES_0402-49.9,1%,1/16W,CHIP,G2A':
 ROOM='PVCCIN_CPU0_VR';

SECTION_NUMBER 1
 '@BASEBOARD_FAB2_LIB.BASEBOARD_FAB2(SCH_1):PAGE211_I99@MSTR_DISCRETE.RES(CHIPS)':
 C_PATH='@baseboard_fab2_lib.baseboard_fab2(sch_1):page211_i99@mstr_discrete.res~
(chips)',
 P_PATH='@baseboard_fab2_lib.baseboard_fab2(sch_1):page211_i99@mstr_discrete.res~
(chips)',
 PATH='I99',
 DRAWING='@BASEBOARD_FAB2_LIB.BASEBOARD_FAB2(SCH_1):PAGE211',
 WATTAGE='1/16W',
 TOLERANCE='1%',
 SEC_TYPE='0402',
 MATERIAL='CHIP',
 PHYS_PAGE='211',
 XY='(-2125,4525)',
 ROT='0',
 VER='2',
 VALUE='49.9',
 PACK_TYPE='0402',
 PART_NUMBER='G21796-047',
 LOCATION='R3P17',
 ROOM='PVCCIN_CPU0_VR',
 SEC='1',
 CDS_LIB='mstr_discrete',
 CDS_PART_NAME='RES_0402-49.9,1%,1/16W,CHIP,G2A',
 PRIM_FILE='./archive_libs/mstr_discrete/res/chips/chips.prt';

PART_NAME
 R3P18 'RES_0402-1.00K,1%,1/16W,CHIP,GA':;

SECTION_NUMBER 1
 '@BASEBOARD_FAB2_LIB.BASEBOARD_FAB2(SCH_1):PAGE211_I64@MSTR_DISCRETE.RES(CHIPS)':
 C_PATH='@baseboard_fab2_lib.baseboard_fab2(sch_1):page211_i64@mstr_discrete.res~
(chips)',
 P_PATH='@baseboard_fab2_lib.baseboard_fab2(sch_1):page211_i64@mstr_discrete.res~
(chips)',
 PATH='I64',
 DRAWING='@BASEBOARD_FAB2_LIB.BASEBOARD_FAB2(SCH_1):PAGE211',
 WATTAGE='1/16W',
 TOLERANCE='1%',
 SEC_TYPE='0402',
 MATERIAL='CHIP',
 PHYS_PAGE='211',
 XY='(2075,4050)',
 ROT='0',
 VER='2',
 VALUE='1.00K',
 PACK_TYPE='0402',
 PART_NUMBER='G21796-026',
 LOCATION='R3P18',
 SEC='1',
 CDS_LIB='mstr_discrete',
 CDS_PART_NAME='RES_0402-1.00K,1%,1/16W,CHIP,GA',
 PRIM_FILE='./archive_libs/mstr_discrete/res/chips/chips.prt';

PART_NAME
 R3P20 'RES_0402-22.1,1.0%,1/16W,CHIP,A':
 ROOM='PVCCIO_CPU0';

SECTION_NUMBER 1
 '@BASEBOARD_FAB2_LIB.BASEBOARD_FAB2(SCH_1):PAGE211_I58@MSTR_DISCRETE.RES(CHIPS)':
 C_PATH='@baseboard_fab2_lib.baseboard_fab2(sch_1):page211_i58@mstr_discrete.res~
(chips)',
 P_PATH='@baseboard_fab2_lib.baseboard_fab2(sch_1):page211_i58@mstr_discrete.res~
(chips)',
 PATH='I58',
 DRAWING='@BASEBOARD_FAB2_LIB.BASEBOARD_FAB2(SCH_1):PAGE211',
 WATTAGE='1/16W',
 TOLERANCE='1.0%',
 SEC_TYPE='0402',
 MATERIAL='CHIP',
 PHYS_PAGE='211',
 XY='(1875,3600)',
 ROT='0',
 VER='1',
 VALUE='22.1',
 PACK_TYPE='0402',
 PART_NUMBER='G21796-250',
 LOCATION='R3P20',
 ROOM='PVCCIO_CPU0',
 SEC='1',
 CDS_LIB='mstr_discrete',
 CDS_PART_NAME='RES_0402-22.1,1.0%,1/16W,CHIP,A',
 PRIM_FILE='./archive_libs/mstr_discrete/res/chips/chips.prt';

PART_NAME
 R3P21 'RES_0402-100.0K,1%,1/16W,EMPTYA':
 ROOM='BMC';

SECTION_NUMBER 1
 '@BASEBOARD_FAB2_LIB.BASEBOARD_FAB2(SCH_1):PAGE211_I88@MSTR_DISCRETE.RES(CHIPS)':
 C_PATH='@baseboard_fab2_lib.baseboard_fab2(sch_1):page211_i88@mstr_discrete.res~
(chips)',
 P_PATH='@baseboard_fab2_lib.baseboard_fab2(sch_1):page211_i88@mstr_discrete.res~
(chips)',
 PATH='I88',
 DRAWING='@BASEBOARD_FAB2_LIB.BASEBOARD_FAB2(SCH_1):PAGE211',
 WATTAGE='1/16W',
 TOLERANCE='1%',
 MATERIAL='EMPTY',
 BOM_COST='SM_CONTROLLER',
 PHYS_PAGE='211',
 XY='(-1125,4300)',
 ROT='0',
 VER='2',
 VALUE='100.0K',
 PACK_TYPE='0402',
 PART_NUMBER='G21796-010',
 LOCATION='R3P21',
 ROOM='BMC',
 CDS_LIB='mstr_discrete',
 CDS_PART_NAME='RES_0402-100.0K,1%,1/16W,EMPTYA',
 PRIM_FILE='./archive_libs/mstr_discrete/res/chips/chips.prt';

PART_NAME
 R3P22 'RES_0402-0.0,5%,1/16W,CHIP,G21A':
 ROOM='PVCCIO_CPU0';

SECTION_NUMBER 1
 '@BASEBOARD_FAB2_LIB.BASEBOARD_FAB2(SCH_1):PAGE211_I24@MSTR_DISCRETE.RES(CHIPS)':
 C_PATH='@baseboard_fab2_lib.baseboard_fab2(sch_1):page211_i24@mstr_discrete.res~
(chips)',
 P_PATH='@baseboard_fab2_lib.baseboard_fab2(sch_1):page211_i24@mstr_discrete.res~
(chips)',
 PATH='I24',
 DRAWING='@BASEBOARD_FAB2_LIB.BASEBOARD_FAB2(SCH_1):PAGE211',
 WATTAGE='1/16W',
 TOLERANCE='5%',
 SEC_TYPE='0402',
 MATERIAL='CHIP',
 PHYS_PAGE='211',
 XY='(-625,4525)',
 ROT='0',
 VER='2',
 VALUE='0.0',
 PACK_TYPE='0402',
 PART_NUMBER='G21497-005',
 LOCATION='R3P22',
 ROOM='PVCCIO_CPU0',
 SEC='1',
 CDS_LIB='mstr_discrete',
 CDS_PART_NAME='RES_0402-0.0,5%,1/16W,CHIP,G21A',
 PRIM_FILE='./archive_libs/mstr_discrete/res/chips/chips.prt';

PART_NAME
 R3P25 'RES_0402-1.00K,1%,1/16W,CHIP,GA':
 ROOM='PVCCIO_CPU0';

SECTION_NUMBER 1
 '@BASEBOARD_FAB2_LIB.BASEBOARD_FAB2(SCH_1):PAGE211_I56@MSTR_DISCRETE.RES(CHIPS)':
 C_PATH='@baseboard_fab2_lib.baseboard_fab2(sch_1):page211_i56@mstr_discrete.res~
(chips)',
 P_PATH='@baseboard_fab2_lib.baseboard_fab2(sch_1):page211_i56@mstr_discrete.res~
(chips)',
 PATH='I56',
 DRAWING='@BASEBOARD_FAB2_LIB.BASEBOARD_FAB2(SCH_1):PAGE211',
 WATTAGE='1/16W',
 TOLERANCE='1%',
 SEC_TYPE='0402',
 MATERIAL='CHIP',
 PHYS_PAGE='211',
 XY='(775,4100)',
 ROT='0',
 VER='2',
 VALUE='1.00K',
 PACK_TYPE='0402',
 PART_NUMBER='G21796-026',
 LOCATION='R3P25',
 ROOM='PVCCIO_CPU0',
 SEC='1',
 CDS_LIB='mstr_discrete',
 CDS_PART_NAME='RES_0402-1.00K,1%,1/16W,CHIP,GA',
 PRIM_FILE='./archive_libs/mstr_discrete/res/chips/chips.prt';

PART_NAME
 R3P26 'RES_0402-0.0,5%,1/16W,CHIP,G21A':
 ROOM='PVCCIN_CPU0_VR';

SECTION_NUMBER 1
 '@BASEBOARD_FAB2_LIB.BASEBOARD_FAB2(SCH_1):PAGE211_I87@MSTR_DISCRETE.RES(CHIPS)':
 C_PATH='@baseboard_fab2_lib.baseboard_fab2(sch_1):page211_i87@mstr_discrete.res~
(chips)',
 P_PATH='@baseboard_fab2_lib.baseboard_fab2(sch_1):page211_i87@mstr_discrete.res~
(chips)',
 PATH='I87',
 DRAWING='@BASEBOARD_FAB2_LIB.BASEBOARD_FAB2(SCH_1):PAGE211',
 WATTAGE='1/16W',
 TOLERANCE='5%',
 SEC_TYPE='0402',
 MATERIAL='CHIP',
 PHYS_PAGE='211',
 XY='(-1950,3250)',
 ROT='0',
 VER='1',
 VALUE='0.0',
 PACK_TYPE='0402',
 PART_NUMBER='G21497-005',
 LOCATION='R3P26',
 ROOM='PVCCIN_CPU0_VR',
 SEC='1',
 CDS_LIB='mstr_discrete',
 CDS_PART_NAME='RES_0402-0.0,5%,1/16W,CHIP,G21A',
 PRIM_FILE='./archive_libs/mstr_discrete/res/chips/chips.prt';

PART_NAME
 R3P29 'RES_0402-64.9,1.0%,1/16W,CHIP,A':
 ROOM='PROC_RSTS_PGOODS';

SECTION_NUMBER 1
 '@BASEBOARD_FAB2_LIB.BASEBOARD_FAB2(SCH_1):PAGE96_I5@MSTR_DISCRETE.RES(CHIPS)':
 C_PATH='@baseboard_fab2_lib.baseboard_fab2(sch_1):page96_i5@mstr_discrete.res(c~
hips)',
 P_PATH='@baseboard_fab2_lib.baseboard_fab2(sch_1):page96_i5@mstr_discrete.res(c~
hips)',
 PATH='I5',
 DRAWING='@BASEBOARD_FAB2_LIB.BASEBOARD_FAB2(SCH_1):PAGE96',
 WATTAGE='1/16W',
 TOLERANCE='1.0%',
 MATERIAL='CHIP',
 BOM_COST='PROC_SIDEBAND',
 PHYS_PAGE='96',
 XY='(975,4450)',
 ROT='0',
 VER='2',
 VALUE='64.9',
 PACK_TYPE='0402',
 PART_NUMBER='G21796-298',
 LOCATION='R3P29',
 ROOM='PROC_RSTS_PGOODS',
 CDS_LIB='mstr_discrete',
 CDS_PART_NAME='RES_0402-64.9,1.0%,1/16W,CHIP,A',
 PRIM_FILE='./archive_libs/mstr_discrete/res/chips/chips.prt';

PART_NAME
 R3P32 'RES_0402-1.00K,1%,1/16W,CHIP,GA':
 ROOM='PROC_RSTS_PGOODS';

SECTION_NUMBER 1
 '@BASEBOARD_FAB2_LIB.BASEBOARD_FAB2(SCH_1):PAGE96_I71@MSTR_DISCRETE.RES(CHIPS)':
 C_PATH='@baseboard_fab2_lib.baseboard_fab2(sch_1):page96_i71@mstr_discrete.res(~
chips)',
 P_PATH='@baseboard_fab2_lib.baseboard_fab2(sch_1):page96_i71@mstr_discrete.res(~
chips)',
 PATH='I71',
 DRAWING='@BASEBOARD_FAB2_LIB.BASEBOARD_FAB2(SCH_1):PAGE96',
 WATTAGE='1/16W',
 TOLERANCE='1%',
 SEC_TYPE='0402',
 MATERIAL='CHIP',
 BOM_COST='PROC_SIDEBAND',
 PHYS_PAGE='96',
 XY='(-2400,4350)',
 ROT='0',
 VER='1',
 VALUE='1.00K',
 PACK_TYPE='0402',
 PART_NUMBER='G21796-026',
 LOCATION='R3P32',
 ROOM='PROC_RSTS_PGOODS',
 SEC='1',
 CDS_LIB='mstr_discrete',
 CDS_PART_NAME='RES_0402-1.00K,1%,1/16W,CHIP,GA',
 PRIM_FILE='./archive_libs/mstr_discrete/res/chips/chips.prt';

PART_NAME
 R3P34 'RES_0402-0.0,5%,1/16W,CHIP,G21A':
 ROOM='CPLD';

SECTION_NUMBER 1
 '@BASEBOARD_FAB2_LIB.BASEBOARD_FAB2(SCH_1):PAGE190_I116@MSTR_DISCRETE.RES(CHIPS)':
 C_PATH='@baseboard_fab2_lib.baseboard_fab2(sch_1):page190_i116@mstr_discrete.re~
s(chips)',
 P_PATH='@baseboard_fab2_lib.baseboard_fab2(sch_1):page190_i116@mstr_discrete.re~
s(chips)',
 PATH='I116',
 DRAWING='@BASEBOARD_FAB2_LIB.BASEBOARD_FAB2(SCH_1):PAGE190',
 WATTAGE='1/16W',
 TOLERANCE='5%',
 SEC_TYPE='0402',
 MATERIAL='CHIP',
 BOM_COST='CPLD',
 PHYS_PAGE='190',
 XY='(-4150,5200)',
 ROT='0',
 VER='1',
 VALUE='0.0',
 PACK_TYPE='0402',
 PART_NUMBER='G21497-005',
 LOCATION='R3P34',
 ROOM='CPLD',
 SEC='1',
 CDS_LIB='mstr_discrete',
 CDS_PART_NAME='RES_0402-0.0,5%,1/16W,CHIP,G21A',
 PRIM_FILE='./archive_libs/mstr_discrete/res/chips/chips.prt';

PART_NAME
 R3P35 'RES_0402-0.0,5%,1/16W,CHIP,G21A':
 ROOM='CPLD';

SECTION_NUMBER 1
 '@BASEBOARD_FAB2_LIB.BASEBOARD_FAB2(SCH_1):PAGE190_I117@MSTR_DISCRETE.RES(CHIPS)':
 C_PATH='@baseboard_fab2_lib.baseboard_fab2(sch_1):page190_i117@mstr_discrete.re~
s(chips)',
 P_PATH='@baseboard_fab2_lib.baseboard_fab2(sch_1):page190_i117@mstr_discrete.re~
s(chips)',
 PATH='I117',
 DRAWING='@BASEBOARD_FAB2_LIB.BASEBOARD_FAB2(SCH_1):PAGE190',
 WATTAGE='1/16W',
 TOLERANCE='5%',
 SEC_TYPE='0402',
 MATERIAL='CHIP',
 BOM_COST='CPLD',
 PHYS_PAGE='190',
 XY='(-4150,5000)',
 ROT='0',
 VER='1',
 VALUE='0.0',
 PACK_TYPE='0402',
 PART_NUMBER='G21497-005',
 LOCATION='R3P35',
 ROOM='CPLD',
 SEC='1',
 CDS_LIB='mstr_discrete',
 CDS_PART_NAME='RES_0402-0.0,5%,1/16W,CHIP,G21A',
 PRIM_FILE='./archive_libs/mstr_discrete/res/chips/chips.prt';

PART_NAME
 R3P36 'RES_0402-1.00K,1%,1/16W,CHIP,GA':
 ROOM='PROC_RSTS_PGOODS';

SECTION_NUMBER 1
 '@BASEBOARD_FAB2_LIB.BASEBOARD_FAB2(SCH_1):PAGE96_I36@MSTR_DISCRETE.RES(CHIPS)':
 C_PATH='@baseboard_fab2_lib.baseboard_fab2(sch_1):page96_i36@mstr_discrete.res(~
chips)',
 P_PATH='@baseboard_fab2_lib.baseboard_fab2(sch_1):page96_i36@mstr_discrete.res(~
chips)',
 PATH='I36',
 DRAWING='@BASEBOARD_FAB2_LIB.BASEBOARD_FAB2(SCH_1):PAGE96',
 WATTAGE='1/16W',
 TOLERANCE='1%',
 MATERIAL='CHIP',
 BOM_COST='PROC_SIDEBAND',
 PHYS_PAGE='96',
 XY='(-2100,4650)',
 ROT='0',
 VER='2',
 VALUE='1.00K',
 PACK_TYPE='0402',
 PART_NUMBER='G21796-026',
 LOCATION='R3P36',
 ROOM='PROC_RSTS_PGOODS',
 CDS_LIB='mstr_discrete',
 CDS_PART_NAME='RES_0402-1.00K,1%,1/16W,CHIP,GA',
 PRIM_FILE='./archive_libs/mstr_discrete/res/chips/chips.prt';

PART_NAME
 R3P38 'RES_0402-64.9,1.0%,1/16W,CHIP,A':
 ROOM='PROC_RSTS_PGOODS';

SECTION_NUMBER 1
 '@BASEBOARD_FAB2_LIB.BASEBOARD_FAB2(SCH_1):PAGE96_I7@MSTR_DISCRETE.RES(CHIPS)':
 C_PATH='@baseboard_fab2_lib.baseboard_fab2(sch_1):page96_i7@mstr_discrete.res(c~
hips)',
 P_PATH='@baseboard_fab2_lib.baseboard_fab2(sch_1):page96_i7@mstr_discrete.res(c~
hips)',
 PATH='I7',
 DRAWING='@BASEBOARD_FAB2_LIB.BASEBOARD_FAB2(SCH_1):PAGE96',
 WATTAGE='1/16W',
 TOLERANCE='1.0%',
 MATERIAL='CHIP',
 BOM_COST='PROC_SIDEBAND',
 PHYS_PAGE='96',
 XY='(575,4450)',
 ROT='0',
 VER='2',
 VALUE='64.9',
 PACK_TYPE='0402',
 PART_NUMBER='G21796-298',
 LOCATION='R3P38',
 ROOM='PROC_RSTS_PGOODS',
 CDS_LIB='mstr_discrete',
 CDS_PART_NAME='RES_0402-64.9,1.0%,1/16W,CHIP,A',
 PRIM_FILE='./archive_libs/mstr_discrete/res/chips/chips.prt';

PART_NAME
 R3P41 'RES_0402-75,1.0%,1/16W,CHIP,G2A':
 ROOM='PROC_SIDEBAND';

SECTION_NUMBER 1
 '@BASEBOARD_FAB2_LIB.BASEBOARD_FAB2(SCH_1):PAGE92_I9@MSTR_DISCRETE.RES(CHIPS)':
 C_PATH='@baseboard_fab2_lib.baseboard_fab2(sch_1):page92_i9@mstr_discrete.res(c~
hips)',
 P_PATH='@baseboard_fab2_lib.baseboard_fab2(sch_1):page92_i9@mstr_discrete.res(c~
hips)',
 PATH='I9',
 DRAWING='@BASEBOARD_FAB2_LIB.BASEBOARD_FAB2(SCH_1):PAGE92',
 WATTAGE='1/16W',
 TOLERANCE='1.0%',
 SEC_TYPE='0402',
 MATERIAL='CHIP',
 BOM_COST='PROC_SIDEBAND',
 PHYS_PAGE='92',
 XY='(-2900,4525)',
 ROT='0',
 VER='2',
 VALUE='75',
 PACK_TYPE='0402',
 PART_NUMBER='G21796-267',
 LOCATION='R3P41',
 ROOM='PROC_SIDEBAND',
 SEC='1',
 CDS_LIB='mstr_discrete',
 CDS_PART_NAME='RES_0402-75,1.0%,1/16W,CHIP,G2A',
 PRIM_FILE='./archive_libs/mstr_discrete/res/chips/chips.prt';

PART_NAME
 R3P42 'RES_0402-33.2,1%,1/16W,CHIP,G2A':
 ROOM='PROC_SIDEBAND';

SECTION_NUMBER 1
 '@BASEBOARD_FAB2_LIB.BASEBOARD_FAB2(SCH_1):PAGE92_I14@MSTR_DISCRETE.RES(CHIPS)':
 C_PATH='@baseboard_fab2_lib.baseboard_fab2(sch_1):page92_i14@mstr_discrete.res(~
chips)',
 P_PATH='@baseboard_fab2_lib.baseboard_fab2(sch_1):page92_i14@mstr_discrete.res(~
chips)',
 PATH='I14',
 DRAWING='@BASEBOARD_FAB2_LIB.BASEBOARD_FAB2(SCH_1):PAGE92',
 WATTAGE='1/16W',
 TOLERANCE='1%',
 SEC_TYPE='0402',
 MATERIAL='CHIP',
 BOM_COST='PROC_SIDEBAND',
 PHYS_PAGE='92',
 XY='(-125,4250)',
 ROT='0',
 VER='1',
 VALUE='33.2',
 PACK_TYPE='0402',
 PART_NUMBER='G21796-074',
 LOCATION='R3P42',
 ROOM='PROC_SIDEBAND',
 SEC='1',
 CDS_LIB='mstr_discrete',
 CDS_PART_NAME='RES_0402-33.2,1%,1/16W,CHIP,G2A',
 PRIM_FILE='./archive_libs/mstr_discrete/res/chips/chips.prt';

PART_NAME
 R3P43 'RES_0402-33.2,1%,1/16W,CHIP,G2A':
 ROOM='PROC_SIDEBAND';

SECTION_NUMBER 1
 '@BASEBOARD_FAB2_LIB.BASEBOARD_FAB2(SCH_1):PAGE92_I13@MSTR_DISCRETE.RES(CHIPS)':
 C_PATH='@baseboard_fab2_lib.baseboard_fab2(sch_1):page92_i13@mstr_discrete.res(~
chips)',
 P_PATH='@baseboard_fab2_lib.baseboard_fab2(sch_1):page92_i13@mstr_discrete.res(~
chips)',
 PATH='I13',
 DRAWING='@BASEBOARD_FAB2_LIB.BASEBOARD_FAB2(SCH_1):PAGE92',
 WATTAGE='1/16W',
 TOLERANCE='1%',
 SEC_TYPE='0402',
 MATERIAL='CHIP',
 BOM_COST='PROC_SIDEBAND',
 PHYS_PAGE='92',
 XY='(-125,4000)',
 ROT='0',
 VER='1',
 VALUE='33.2',
 PACK_TYPE='0402',
 PART_NUMBER='G21796-074',
 LOCATION='R3P43',
 ROOM='PROC_SIDEBAND',
 SEC='1',
 CDS_LIB='mstr_discrete',
 CDS_PART_NAME='RES_0402-33.2,1%,1/16W,CHIP,G2A',
 PRIM_FILE='./archive_libs/mstr_discrete/res/chips/chips.prt';

PART_NAME
 R3P44 'RES_0402-4.75K,1%,1/16W,CHIP,GA':
 ROOM='V_SUPER';

SECTION_NUMBER 1
 '@BASEBOARD_FAB2_LIB.BASEBOARD_FAB2(SCH_1):PAGE196_I59@MSTR_DISCRETE.RES(CHIPS)':
 C_PATH='@baseboard_fab2_lib.baseboard_fab2(sch_1):page196_i59@mstr_discrete.res~
(chips)',
 P_PATH='@baseboard_fab2_lib.baseboard_fab2(sch_1):page196_i59@mstr_discrete.res~
(chips)',
 PATH='I59',
 DRAWING='@BASEBOARD_FAB2_LIB.BASEBOARD_FAB2(SCH_1):PAGE196',
 WATTAGE='1/16W',
 TOLERANCE='1%',
 SEC_TYPE='0402',
 MATERIAL='CHIP',
 PHYS_PAGE='196',
 XY='(1325,4650)',
 ROT='0',
 VER='2',
 VALUE='4.75K',
 PACK_TYPE='0402',
 PART_NUMBER='G21796-072',
 LOCATION='R3P44',
 ROOM='V_SUPER',
 SEC='1',
 CDS_LIB='mstr_discrete',
 CDS_PART_NAME='RES_0402-4.75K,1%,1/16W,CHIP,GA',
 PRIM_FILE='./archive_libs/mstr_discrete/res/chips/chips.prt';

PART_NAME
 R3P45 '374R2F-1-GP_SMD-RG-374R2F-1-GPA':;

SECTION_NUMBER 1
 '@BASEBOARD_FAB2_LIB.BASEBOARD_FAB2(SCH_1):PAGE92_I110@W_HDL.374R2F-1-GP(CHIPS)':
 C_PATH='@baseboard_fab2_lib.baseboard_fab2(sch_1):page92_i110@w_hdl.\374r2f-1-g~
p\(chips)',
 P_PATH='@baseboard_fab2_lib.baseboard_fab2(sch_1):page92_i110@w_hdl.\374r2f-1-g~
p\(chips)',
 PATH='I110',
 DRAWING='@BASEBOARD_FAB2_LIB.BASEBOARD_FAB2(SCH_1):PAGE92',
 PACK_SIZE='0402',
 RATED='1/16W',
 ATTRIBUTE='374 OHM',
 TOLERANCE='1%',
 PHYS_PAGE='92',
 XY='(100,5325)',
 ROT='0',
 VER='1',
 VALUE='374R2F-1-GP',
 PACK_TYPE='SMD-RG',
 PART_NUMBER='64.37405.6DL',
 LOCATION='R3P45',
 CDS_LIB='w_hdl',
 CDS_PART_NAME='374R2F-1-GP_SMD-RG-374R2F-1-GPA',
 PRIM_FILE='C:/<user>/w_hdl/374r2f#2d1#2dgp/chips/chips.prt';

PART_NAME
 R3P46 'RES_0402-33.2,1%,1/16W,CHIP,G2A':
 ROOM='PROC_SIDEBAND';

SECTION_NUMBER 1
 '@BASEBOARD_FAB2_LIB.BASEBOARD_FAB2(SCH_1):PAGE92_I12@MSTR_DISCRETE.RES(CHIPS)':
 C_PATH='@baseboard_fab2_lib.baseboard_fab2(sch_1):page92_i12@mstr_discrete.res(~
chips)',
 P_PATH='@baseboard_fab2_lib.baseboard_fab2(sch_1):page92_i12@mstr_discrete.res(~
chips)',
 PATH='I12',
 DRAWING='@BASEBOARD_FAB2_LIB.BASEBOARD_FAB2(SCH_1):PAGE92',
 WATTAGE='1/16W',
 TOLERANCE='1%',
 SEC_TYPE='0402',
 MATERIAL='CHIP',
 BOM_COST='PROC_SIDEBAND',
 PHYS_PAGE='92',
 XY='(-125,3750)',
 ROT='0',
 VER='1',
 VALUE='33.2',
 PACK_TYPE='0402',
 PART_NUMBER='G21796-074',
 LOCATION='R3P46',
 ROOM='PROC_SIDEBAND',
 SEC='1',
 CDS_LIB='mstr_discrete',
 CDS_PART_NAME='RES_0402-33.2,1%,1/16W,CHIP,G2A',
 PRIM_FILE='./archive_libs/mstr_discrete/res/chips/chips.prt';

PART_NAME
 R3P48 'RES_0402-90.9K,1%,1/16W,CHIP,GA':
 ROOM='V_SUPER';

SECTION_NUMBER 1
 '@BASEBOARD_FAB2_LIB.BASEBOARD_FAB2(SCH_1):PAGE196_I74@MSTR_DISCRETE.RES(CHIPS)':
 C_PATH='@baseboard_fab2_lib.baseboard_fab2(sch_1):page196_i74@mstr_discrete.res~
(chips)',
 P_PATH='@baseboard_fab2_lib.baseboard_fab2(sch_1):page196_i74@mstr_discrete.res~
(chips)',
 PATH='I74',
 DRAWING='@BASEBOARD_FAB2_LIB.BASEBOARD_FAB2(SCH_1):PAGE196',
 WATTAGE='1/16W',
 TOLERANCE='1%',
 SEC_TYPE='0402',
 MATERIAL='CHIP',
 PHYS_PAGE='196',
 XY='(-525,4750)',
 ROT='0',
 VER='2',
 VALUE='90.9K',
 PACK_TYPE='0402',
 PART_NUMBER='G21796-058',
 LOCATION='R3P48',
 ROOM='V_SUPER',
 SEC='1',
 CDS_LIB='mstr_discrete',
 CDS_PART_NAME='RES_0402-90.9K,1%,1/16W,CHIP,GA',
 PRIM_FILE='./archive_libs/mstr_discrete/res/chips/chips.prt';

PART_NAME
 R3P49 'RES_0402-100.0,1%,1/16W,CHIP,GA':
 ROOM='PROC_SIDEBAND';

SECTION_NUMBER 1
 '@BASEBOARD_FAB2_LIB.BASEBOARD_FAB2(SCH_1):PAGE92_I38@MSTR_DISCRETE.RES(CHIPS)':
 C_PATH='@baseboard_fab2_lib.baseboard_fab2(sch_1):page92_i38@mstr_discrete.res(~
chips)',
 P_PATH='@baseboard_fab2_lib.baseboard_fab2(sch_1):page92_i38@mstr_discrete.res(~
chips)',
 PATH='I38',
 DRAWING='@BASEBOARD_FAB2_LIB.BASEBOARD_FAB2(SCH_1):PAGE92',
 WATTAGE='1/16W',
 TOLERANCE='1%',
 SEC_TYPE='0402',
 MATERIAL='CHIP',
 BOM_COST='PROC_SIDEBAND',
 PHYS_PAGE='92',
 XY='(100,4800)',
 ROT='0',
 VER='2',
 VALUE='100.0',
 PACK_TYPE='0402',
 PART_NUMBER='G21796-017',
 LOCATION='R3P49',
 ROOM='PROC_SIDEBAND',
 SEC='1',
 CDS_LIB='mstr_discrete',
 CDS_PART_NAME='RES_0402-100.0,1%,1/16W,CHIP,GA',
 PRIM_FILE='./archive_libs/mstr_discrete/res/chips/chips.prt';

PART_NAME
 R3P50 'RES_0402-10.0K,1%,1/16W,EMPTY,A':
 ROOM='V_SUPER';

SECTION_NUMBER 1
 '@BASEBOARD_FAB2_LIB.BASEBOARD_FAB2(SCH_1):PAGE196_I71@MSTR_DISCRETE.RES(CHIPS)':
 C_PATH='@baseboard_fab2_lib.baseboard_fab2(sch_1):page196_i71@mstr_discrete.res~
(chips)',
 P_PATH='@baseboard_fab2_lib.baseboard_fab2(sch_1):page196_i71@mstr_discrete.res~
(chips)',
 PATH='I71',
 DRAWING='@BASEBOARD_FAB2_LIB.BASEBOARD_FAB2(SCH_1):PAGE196',
 WATTAGE='1/16W',
 TOLERANCE='1%',
 SEC_TYPE='0402',
 MATERIAL='EMPTY',
 PHYS_PAGE='196',
 XY='(-25,4750)',
 ROT='0',
 VER='2',
 VALUE='10.0K',
 PACK_TYPE='0402',
 PART_NUMBER='G21796-016',
 LOCATION='R3P50',
 ROOM='V_SUPER',
 SEC='1',
 CDS_LIB='mstr_discrete',
 CDS_PART_NAME='RES_0402-10.0K,1%,1/16W,EMPTY,A',
 PRIM_FILE='./archive_libs/mstr_discrete/res/chips/chips.prt';

PART_NAME
 R3P51 'RES_0402-6.34K,1%,1/16W,CHIP,GA':
 ROOM='V_SUPER';

SECTION_NUMBER 1
 '@BASEBOARD_FAB2_LIB.BASEBOARD_FAB2(SCH_1):PAGE196_I75@MSTR_DISCRETE.RES(CHIPS)':
 C_PATH='@baseboard_fab2_lib.baseboard_fab2(sch_1):page196_i75@mstr_discrete.res~
(chips)',
 P_PATH='@baseboard_fab2_lib.baseboard_fab2(sch_1):page196_i75@mstr_discrete.res~
(chips)',
 PATH='I75',
 DRAWING='@BASEBOARD_FAB2_LIB.BASEBOARD_FAB2(SCH_1):PAGE196',
 WATTAGE='1/16W',
 TOLERANCE='1%',
 SEC_TYPE='0402',
 MATERIAL='CHIP',
 PHYS_PAGE='196',
 XY='(-525,4250)',
 ROT='0',
 VER='2',
 VALUE='6.34K',
 PACK_TYPE='0402',
 PART_NUMBER='G21796-146',
 LOCATION='R3P51',
 ROOM='V_SUPER',
 SEC='1',
 CDS_LIB='mstr_discrete',
 CDS_PART_NAME='RES_0402-6.34K,1%,1/16W,CHIP,GA',
 PRIM_FILE='./archive_libs/mstr_discrete/res/chips/chips.prt';

PART_NAME
 R3P53 'RES_0402-4.75K,1%,1/16W,CHIP,GA':
 ROOM='SB_PU_PD';

SECTION_NUMBER 1
 '@BASEBOARD_FAB2_LIB.BASEBOARD_FAB2(SCH_1):PAGE133_I365@MSTR_DISCRETE.RES(CHIPS)':
 C_PATH='@baseboard_fab2_lib.baseboard_fab2(sch_1):page133_i365@mstr_discrete.re~
s(chips)',
 P_PATH='@baseboard_fab2_lib.baseboard_fab2(sch_1):page133_i365@mstr_discrete.re~
s(chips)',
 PATH='I365',
 DRAWING='@BASEBOARD_FAB2_LIB.BASEBOARD_FAB2(SCH_1):PAGE133',
 WATTAGE='1/16W',
 TOLERANCE='1%',
 MATERIAL='CHIP',
 PHYS_PAGE='133',
 XY='(-375,3525)',
 ROT='0',
 VER='1',
 VALUE='4.75K',
 PACK_TYPE='0402',
 PART_NUMBER='G21796-072',
 LOCATION='R3P53',
 ROOM='SB_PU_PD',
 CDS_LIB='mstr_discrete',
 CDS_PART_NAME='RES_0402-4.75K,1%,1/16W,CHIP,GA',
 PRIM_FILE='./archive_libs/mstr_discrete/res/chips/chips.prt';

PART_NAME
 R3P54 'RES_0402-3.32K,1%,1/16W,EMPTY,A':
 ROOM='CPU0';

SECTION_NUMBER 1
 '@BASEBOARD_FAB2_LIB.BASEBOARD_FAB2(SCH_1):PAGE156_I331@MSTR_DISCRETE.RES(CHIPS)':
 C_PATH='@baseboard_fab2_lib.baseboard_fab2(sch_1):page156_i331@mstr_discrete.re~
s(chips)',
 P_PATH='@baseboard_fab2_lib.baseboard_fab2(sch_1):page156_i331@mstr_discrete.re~
s(chips)',
 PATH='I331',
 DRAWING='@BASEBOARD_FAB2_LIB.BASEBOARD_FAB2(SCH_1):PAGE156',
 WATTAGE='1/16W',
 TOLERANCE='1%',
 SEC_TYPE='0402',
 MATERIAL='EMPTY',
 PHYS_PAGE='156',
 XY='(-7650,1700)',
 ROT='0',
 VER='2',
 VALUE='3.32K',
 PACK_TYPE='0402',
 PART_NUMBER='G21796-027',
 LOCATION='R3P54',
 ROOM='CPU0',
 SEC='1',
 CDS_LIB='mstr_discrete',
 CDS_PART_NAME='RES_0402-3.32K,1%,1/16W,EMPTY,A',
 PRIM_FILE='./archive_libs/mstr_discrete/res/chips/chips.prt';

PART_NAME
 R3P56 'RES_0402-1.00K,1%,1/16W,CHIP,GA':
 ROOM='CPU0';

SECTION_NUMBER 1
 '@BASEBOARD_FAB2_LIB.BASEBOARD_FAB2(SCH_1):PAGE156_I333@MSTR_DISCRETE.RES(CHIPS)':
 C_PATH='@baseboard_fab2_lib.baseboard_fab2(sch_1):page156_i333@mstr_discrete.re~
s(chips)',
 P_PATH='@baseboard_fab2_lib.baseboard_fab2(sch_1):page156_i333@mstr_discrete.re~
s(chips)',
 PATH='I333',
 DRAWING='@BASEBOARD_FAB2_LIB.BASEBOARD_FAB2(SCH_1):PAGE156',
 WATTAGE='1/16W',
 TOLERANCE='1%',
 SEC_TYPE='0402',
 MATERIAL='CHIP',
 PHYS_PAGE='156',
 XY='(-7650,1325)',
 ROT='0',
 VER='2',
 VALUE='1.00K',
 PACK_TYPE='0402',
 PART_NUMBER='G21796-026',
 LOCATION='R3P56',
 ROOM='CPU0',
 SEC='1',
 CDS_LIB='mstr_discrete',
 CDS_PART_NAME='RES_0402-1.00K,1%,1/16W,CHIP,GA',
 PRIM_FILE='./archive_libs/mstr_discrete/res/chips/chips.prt';

PART_NAME
 R3P58 'RES_0402-0.0,5%,1/16W,CHIP,G21A':
 ROOM='PROC_SIDEBAND';

SECTION_NUMBER 1
 '@BASEBOARD_FAB2_LIB.BASEBOARD_FAB2(SCH_1):PAGE92_I98@MSTR_DISCRETE.RES(CHIPS)':
 C_PATH='@baseboard_fab2_lib.baseboard_fab2(sch_1):page92_i98@mstr_discrete.res(~
chips)',
 P_PATH='@baseboard_fab2_lib.baseboard_fab2(sch_1):page92_i98@mstr_discrete.res(~
chips)',
 PATH='I98',
 DRAWING='@BASEBOARD_FAB2_LIB.BASEBOARD_FAB2(SCH_1):PAGE92',
 WATTAGE='1/16W',
 TOLERANCE='5%',
 SEC_TYPE='0402',
 MATERIAL='CHIP',
 BOM_COST='PROC',
 PHYS_PAGE='92',
 XY='(-3750,4100)',
 ROT='0',
 VER='1',
 VALUE='0.0',
 PACK_TYPE='0402',
 PART_NUMBER='G21497-005',
 LOCATION='R3P58',
 ROOM='PROC_SIDEBAND',
 SEC='1',
 CDS_LIB='mstr_discrete',
 CDS_PART_NAME='RES_0402-0.0,5%,1/16W,CHIP,G21A',
 PRIM_FILE='./archive_libs/mstr_discrete/res/chips/chips.prt';

PART_NAME
 R3P59 'RES_0402-0.0,5%,1/16W,CHIP,G21A':
 ROOM='PROC_SIDEBAND';

SECTION_NUMBER 1
 '@BASEBOARD_FAB2_LIB.BASEBOARD_FAB2(SCH_1):PAGE92_I97@MSTR_DISCRETE.RES(CHIPS)':
 C_PATH='@baseboard_fab2_lib.baseboard_fab2(sch_1):page92_i97@mstr_discrete.res(~
chips)',
 P_PATH='@baseboard_fab2_lib.baseboard_fab2(sch_1):page92_i97@mstr_discrete.res(~
chips)',
 PATH='I97',
 DRAWING='@BASEBOARD_FAB2_LIB.BASEBOARD_FAB2(SCH_1):PAGE92',
 WATTAGE='1/16W',
 TOLERANCE='5%',
 SEC_TYPE='0402',
 MATERIAL='CHIP',
 BOM_COST='PROC',
 PHYS_PAGE='92',
 XY='(-3775,4350)',
 ROT='0',
 VER='1',
 VALUE='0.0',
 PACK_TYPE='0402',
 PART_NUMBER='G21497-005',
 LOCATION='R3P59',
 ROOM='PROC_SIDEBAND',
 SEC='1',
 CDS_LIB='mstr_discrete',
 CDS_PART_NAME='RES_0402-0.0,5%,1/16W,CHIP,G21A',
 PRIM_FILE='./archive_libs/mstr_discrete/res/chips/chips.prt';

PART_NAME
 R3P60 'RES_0402-240,1.0%,1/16W,CHIP,GA':
 ROOM='MEM',
 SIGNAL_MODEL='DEFAULT_RESISTOR_750OHM_2_1';

SECTION_NUMBER 1
 '@BASEBOARD_FAB2_LIB.BASEBOARD_FAB2(SCH_1):PAGE99_I67@MSTR_DISCRETE.RES(CHIPS)':
 C_PATH='@baseboard_fab2_lib.baseboard_fab2(sch_1):page99_i67@mstr_discrete.res(~
chips)',
 P_PATH='@baseboard_fab2_lib.baseboard_fab2(sch_1):page99_i67@mstr_discrete.res(~
chips)',
 PATH='I67',
 DRAWING='@BASEBOARD_FAB2_LIB.BASEBOARD_FAB2(SCH_1):PAGE99',
 CD_SEC='1',
 WATTAGE='1/16W',
 TOLERANCE='1.0%',
 MATERIAL='CHIP',
 BOM_COST='SM_CONTROLLER',
 PHYS_PAGE='99',
 XY='(-1050,3600)',
 ROT='2',
 VER='2',
 VALUE='240',
 PACK_TYPE='0402',
 PART_NUMBER='G21796-294',
 LOCATION='R3P60',
 SIGNAL_MODEL='DEFAULT_RESISTOR_750OHM_2_1',
 ROOM='MEM',
 CDS_LIB='mstr_discrete',
 CDS_PART_NAME='RES_0402-240,1.0%,1/16W,CHIP,GA',
 PRIM_FILE='./archive_libs/mstr_discrete/res/chips/chips.prt';

PART_NAME
 R3P61 'RES_0402-2.26K,1.0%,1/16W,CHIPA':
 ROOM='IO_SLOT';

SECTION_NUMBER 1
 '@BASEBOARD_FAB2_LIB.BASEBOARD_FAB2(SCH_1):PAGE181_I81@MSTR_DISCRETE.RES(CHIPS)':
 C_PATH='@baseboard_fab2_lib.baseboard_fab2(sch_1):page181_i81@mstr_discrete.res~
(chips)',
 P_PATH='@baseboard_fab2_lib.baseboard_fab2(sch_1):page181_i81@mstr_discrete.res~
(chips)',
 PATH='I81',
 DRAWING='@BASEBOARD_FAB2_LIB.BASEBOARD_FAB2(SCH_1):PAGE181',
 WATTAGE='1/16W',
 TOLERANCE='1.0%',
 SEC_TYPE='0402',
 MATERIAL='CHIP',
 PHYS_PAGE='181',
 XY='(2650,1875)',
 ROT='0',
 VER='1',
 VALUE='2.26K',
 PACK_TYPE='0402',
 PART_NUMBER='G21796-311',
 LOCATION='R3P61',
 ROOM='IO_SLOT',
 SEC='1',
 CDS_LIB='mstr_discrete',
 CDS_PART_NAME='RES_0402-2.26K,1.0%,1/16W,CHIPA',
 PRIM_FILE='./archive_libs/mstr_discrete/res/chips/chips.prt';

PART_NAME
 R3P62 'RES_0402-4.75K,1%,1/16W,EMPTY,A':;

SECTION_NUMBER 1
 '@BASEBOARD_FAB2_LIB.BASEBOARD_FAB2(SCH_1):PAGE126_I22@MSTR_DISCRETE.RES(CHIPS)':
 C_PATH='@baseboard_fab2_lib.baseboard_fab2(sch_1):page126_i22@mstr_discrete.res~
(chips)',
 P_PATH='@baseboard_fab2_lib.baseboard_fab2(sch_1):page126_i22@mstr_discrete.res~
(chips)',
 PATH='I22',
 DRAWING='@BASEBOARD_FAB2_LIB.BASEBOARD_FAB2(SCH_1):PAGE126',
 WATTAGE='1/16W',
 TOLERANCE='1%',
 SEC_TYPE='0402',
 MATERIAL='EMPTY',
 PHYS_PAGE='126',
 XY='(-4525,2725)',
 ROT='0',
 VER='2',
 VALUE='4.75K',
 PACK_TYPE='0402',
 PART_NUMBER='G21796-072',
 LOCATION='R3P62',
 SEC='1',
 CDS_LIB='mstr_discrete',
 CDS_PART_NAME='RES_0402-4.75K,1%,1/16W,EMPTY,A',
 PRIM_FILE='./archive_libs/mstr_discrete/res/chips/chips.prt';

PART_NAME
 R3P63 'RES_0402-0.0,5%,1/16W,EMPTY,G2A':;

SECTION_NUMBER 1
 '@BASEBOARD_FAB2_LIB.BASEBOARD_FAB2(SCH_1):PAGE152_I100@MSTR_DISCRETE.RES(CHIPS)':
 C_PATH='@baseboard_fab2_lib.baseboard_fab2(sch_1):page152_i100@mstr_discrete.re~
s(chips)',
 P_PATH='@baseboard_fab2_lib.baseboard_fab2(sch_1):page152_i100@mstr_discrete.re~
s(chips)',
 PATH='I100',
 DRAWING='@BASEBOARD_FAB2_LIB.BASEBOARD_FAB2(SCH_1):PAGE152',
 WATTAGE='1/16W',
 TOLERANCE='5%',
 SEC_TYPE='0402',
 MATERIAL='EMPTY',
 PHYS_PAGE='152',
 XY='(-6700,1400)',
 ROT='0',
 VER='1',
 VALUE='0.0',
 PACK_TYPE='0402',
 PART_NUMBER='G21497-005',
 LOCATION='R3P63',
 SEC='1',
 CDS_LIB='mstr_discrete',
 CDS_PART_NAME='RES_0402-0.0,5%,1/16W,EMPTY,G2A',
 PRIM_FILE='./archive_libs/mstr_discrete/res/chips/chips.prt';

PART_NAME
 R3P64 'RES_0402-1.00K,1%,1/16W,EMPTY,A':;

SECTION_NUMBER 1
 '@BASEBOARD_FAB2_LIB.BASEBOARD_FAB2(SCH_1):PAGE126_I23@MSTR_DISCRETE.RES(CHIPS)':
 C_PATH='@baseboard_fab2_lib.baseboard_fab2(sch_1):page126_i23@mstr_discrete.res~
(chips)',
 P_PATH='@baseboard_fab2_lib.baseboard_fab2(sch_1):page126_i23@mstr_discrete.res~
(chips)',
 PATH='I23',
 DRAWING='@BASEBOARD_FAB2_LIB.BASEBOARD_FAB2(SCH_1):PAGE126',
 WATTAGE='1/16W',
 TOLERANCE='1%',
 SEC_TYPE='0402',
 MATERIAL='EMPTY',
 PHYS_PAGE='126',
 XY='(-4525,2275)',
 ROT='0',
 VER='2',
 VALUE='1.00K',
 PACK_TYPE='0402',
 PART_NUMBER='G21796-026',
 LOCATION='R3P64',
 SEC='1',
 CDS_LIB='mstr_discrete',
 CDS_PART_NAME='RES_0402-1.00K,1%,1/16W,EMPTY,A',
 PRIM_FILE='./archive_libs/mstr_discrete/res/chips/chips.prt';

PART_NAME
 R3R1 'RES_0402-1.00K,1%,1/16W,CHIP,GA':
 ROOM='PROC_SIDEBAND';

SECTION_NUMBER 1
 '@BASEBOARD_FAB2_LIB.BASEBOARD_FAB2(SCH_1):PAGE92_I46@MSTR_DISCRETE.RES(CHIPS)':
 C_PATH='@baseboard_fab2_lib.baseboard_fab2(sch_1):page92_i46@mstr_discrete.res(~
chips)',
 P_PATH='@baseboard_fab2_lib.baseboard_fab2(sch_1):page92_i46@mstr_discrete.res(~
chips)',
 PATH='I46',
 DRAWING='@BASEBOARD_FAB2_LIB.BASEBOARD_FAB2(SCH_1):PAGE92',
 WATTAGE='1/16W',
 TOLERANCE='1%',
 SEC_TYPE='0402',
 MATERIAL='CHIP',
 BOM_COST='PROC_SIDEBAND',
 PHYS_PAGE='92',
 XY='(-675,4400)',
 ROT='0',
 VER='1',
 VALUE='1.00K',
 PACK_TYPE='0402',
 PART_NUMBER='G21796-026',
 LOCATION='R3R1',
 ROOM='PROC_SIDEBAND',
 SEC='1',
 CDS_LIB='mstr_discrete',
 CDS_PART_NAME='RES_0402-1.00K,1%,1/16W,CHIP,GA',
 PRIM_FILE='./archive_libs/mstr_discrete/res/chips/chips.prt';

PART_NAME
 R3R2 'RES_0402-1.00K,1%,1/16W,CHIP,GA':
 ROOM='PROC_SIDEBAND';

SECTION_NUMBER 1
 '@BASEBOARD_FAB2_LIB.BASEBOARD_FAB2(SCH_1):PAGE92_I75@MSTR_DISCRETE.RES(CHIPS)':
 C_PATH='@baseboard_fab2_lib.baseboard_fab2(sch_1):page92_i75@mstr_discrete.res(~
chips)',
 P_PATH='@baseboard_fab2_lib.baseboard_fab2(sch_1):page92_i75@mstr_discrete.res(~
chips)',
 PATH='I75',
 DRAWING='@BASEBOARD_FAB2_LIB.BASEBOARD_FAB2(SCH_1):PAGE92',
 WATTAGE='1/16W',
 TOLERANCE='1%',
 SEC_TYPE='0402',
 MATERIAL='CHIP',
 PHYS_PAGE='92',
 XY='(-2925,3900)',
 ROT='0',
 VER='2',
 VALUE='1.00K',
 PACK_TYPE='0402',
 PART_NUMBER='G21796-026',
 LOCATION='R3R2',
 ROOM='PROC_SIDEBAND',
 SEC='1',
 CDS_LIB='mstr_discrete',
 CDS_PART_NAME='RES_0402-1.00K,1%,1/16W,CHIP,GA',
 PRIM_FILE='./archive_libs/mstr_discrete/res/chips/chips.prt';

PART_NAME
 R3R3 'RES_0402-33.2,1%,1/16W,CHIP,G2A':
 ROOM='PROC_SIDEBAND';

SECTION_NUMBER 1
 '@BASEBOARD_FAB2_LIB.BASEBOARD_FAB2(SCH_1):PAGE92_I61@MSTR_DISCRETE.RES(CHIPS)':
 C_PATH='@baseboard_fab2_lib.baseboard_fab2(sch_1):page92_i61@mstr_discrete.res(~
chips)',
 P_PATH='@baseboard_fab2_lib.baseboard_fab2(sch_1):page92_i61@mstr_discrete.res(~
chips)',
 PATH='I61',
 DRAWING='@BASEBOARD_FAB2_LIB.BASEBOARD_FAB2(SCH_1):PAGE92',
 WATTAGE='1/16W',
 TOLERANCE='1%',
 SEC_TYPE='0402',
 MATERIAL='CHIP',
 BOM_COST='PROC_SIDEBAND',
 PHYS_PAGE='92',
 XY='(-125,3550)',
 ROT='0',
 VER='1',
 VALUE='33.2',
 PACK_TYPE='0402',
 PART_NUMBER='G21796-074',
 LOCATION='R3R3',
 ROOM='PROC_SIDEBAND',
 SEC='1',
 CDS_LIB='mstr_discrete',
 CDS_PART_NAME='RES_0402-33.2,1%,1/16W,CHIP,G2A',
 PRIM_FILE='./archive_libs/mstr_discrete/res/chips/chips.prt';

PART_NAME
 R3R4 'RES_0402-4.75K,1%,1/16W,CHIP,GA':
 ROOM='PROC_SIDEBAND';

SECTION_NUMBER 1
 '@BASEBOARD_FAB2_LIB.BASEBOARD_FAB2(SCH_1):PAGE94_I66@MSTR_DISCRETE.RES(CHIPS)':
 C_PATH='@baseboard_fab2_lib.baseboard_fab2(sch_1):page94_i66@mstr_discrete.res(~
chips)',
 P_PATH='@baseboard_fab2_lib.baseboard_fab2(sch_1):page94_i66@mstr_discrete.res(~
chips)',
 PATH='I66',
 DRAWING='@BASEBOARD_FAB2_LIB.BASEBOARD_FAB2(SCH_1):PAGE94',
 WATTAGE='1/16W',
 TOLERANCE='1%',
 MATERIAL='CHIP',
 BOM_COST='PROC_SIDEBAND',
 PHYS_PAGE='94',
 XY='(-2150,1275)',
 ROT='2',
 VER='2',
 VALUE='4.75K',
 PACK_TYPE='0402',
 PART_NUMBER='G21796-072',
 LOCATION='R3R4',
 ROOM='PROC_SIDEBAND',
 CDS_LIB='mstr_discrete',
 CDS_PART_NAME='RES_0402-4.75K,1%,1/16W,CHIP,GA',
 PRIM_FILE='./archive_libs/mstr_discrete/res/chips/chips.prt';

PART_NAME
 R3R5 'RES_0402-665,1.0%,1/16W,CHIP,GA':
 ROOM='MEM';

SECTION_NUMBER 1
 '@BASEBOARD_FAB2_LIB.BASEBOARD_FAB2(SCH_1):PAGE99_I103@MSTR_DISCRETE.RES(CHIPS)':
 C_PATH='@baseboard_fab2_lib.baseboard_fab2(sch_1):page99_i103@mstr_discrete.res~
(chips)',
 P_PATH='@baseboard_fab2_lib.baseboard_fab2(sch_1):page99_i103@mstr_discrete.res~
(chips)',
 PATH='I103',
 DRAWING='@BASEBOARD_FAB2_LIB.BASEBOARD_FAB2(SCH_1):PAGE99',
 WATTAGE='1/16W',
 TOLERANCE='1.0%',
 SEC_TYPE='0402',
 MATERIAL='CHIP',
 BOM_COST='SM_CONTROLLER',
 PHYS_PAGE='99',
 XY='(925,3600)',
 ROT='0',
 VER='2',
 VALUE='665',
 PACK_TYPE='0402',
 PART_NUMBER='G21796-235',
 LOCATION='R3R5',
 ROOM='MEM',
 SEC='1',
 CDS_LIB='mstr_discrete',
 CDS_PART_NAME='RES_0402-665,1.0%,1/16W,CHIP,GA',
 PRIM_FILE='./archive_libs/mstr_discrete/res/chips/chips.prt';

PART_NAME
 R3R7 'RES_0402-10.0,1%,1/16W,CHIP,G2A':
 ROOM='MEM';

SECTION_NUMBER 1
 '@BASEBOARD_FAB2_LIB.BASEBOARD_FAB2(SCH_1):PAGE99_I88@MSTR_DISCRETE.RES(CHIPS)':
 C_PATH='@baseboard_fab2_lib.baseboard_fab2(sch_1):page99_i88@mstr_discrete.res(~
chips)',
 P_PATH='@baseboard_fab2_lib.baseboard_fab2(sch_1):page99_i88@mstr_discrete.res(~
chips)',
 PATH='I88',
 DRAWING='@BASEBOARD_FAB2_LIB.BASEBOARD_FAB2(SCH_1):PAGE99',
 WATTAGE='1/16W',
 TOLERANCE='1%',
 MATERIAL='CHIP',
 BOM_COST='SM_CONTROLLER',
 PHYS_PAGE='99',
 XY='(-1575,3300)',
 ROT='0',
 VER='1',
 VALUE='10.0',
 PACK_TYPE='0402',
 PART_NUMBER='G21796-066',
 LOCATION='R3R7',
 ROOM='MEM',
 CDS_LIB='mstr_discrete',
 CDS_PART_NAME='RES_0402-10.0,1%,1/16W,CHIP,G2A',
 PRIM_FILE='./archive_libs/mstr_discrete/res/chips/chips.prt';

PART_NAME
 R3R8 'RES_0402-20.0,1%,1/16W,CHIP,G2A':
 ROOM='MEM';

SECTION_NUMBER 1
 '@BASEBOARD_FAB2_LIB.BASEBOARD_FAB2(SCH_1):PAGE99_I35@MSTR_DISCRETE.RES(CHIPS)':
 C_PATH='@baseboard_fab2_lib.baseboard_fab2(sch_1):page99_i35@mstr_discrete.res(~
chips)',
 P_PATH='@baseboard_fab2_lib.baseboard_fab2(sch_1):page99_i35@mstr_discrete.res(~
chips)',
 PATH='I35',
 DRAWING='@BASEBOARD_FAB2_LIB.BASEBOARD_FAB2(SCH_1):PAGE99',
 WATTAGE='1/16W',
 TOLERANCE='1%',
 MATERIAL='CHIP',
 PHYS_PAGE='99',
 XY='(1600,3300)',
 ROT='0',
 VER='1',
 VALUE='20.0',
 PACK_TYPE='0402',
 PART_NUMBER='G21796-173',
 LOCATION='R3R8',
 ROOM='MEM',
 CDS_LIB='mstr_discrete',
 CDS_PART_NAME='RES_0402-20.0,1%,1/16W,CHIP,G2A',
 PRIM_FILE='./archive_libs/mstr_discrete/res/chips/chips.prt';

PART_NAME
 R3R9 'RES_0402-20.0,1%,1/16W,CHIP,G2A':
 ROOM='MEM';

SECTION_NUMBER 1
 '@BASEBOARD_FAB2_LIB.BASEBOARD_FAB2(SCH_1):PAGE99_I34@MSTR_DISCRETE.RES(CHIPS)':
 C_PATH='@baseboard_fab2_lib.baseboard_fab2(sch_1):page99_i34@mstr_discrete.res(~
chips)',
 P_PATH='@baseboard_fab2_lib.baseboard_fab2(sch_1):page99_i34@mstr_discrete.res(~
chips)',
 PATH='I34',
 DRAWING='@BASEBOARD_FAB2_LIB.BASEBOARD_FAB2(SCH_1):PAGE99',
 WATTAGE='1/16W',
 TOLERANCE='1%',
 MATERIAL='CHIP',
 PHYS_PAGE='99',
 XY='(1600,3250)',
 ROT='0',
 VER='1',
 VALUE='20.0',
 PACK_TYPE='0402',
 PART_NUMBER='G21796-173',
 LOCATION='R3R9',
 ROOM='MEM',
 CDS_LIB='mstr_discrete',
 CDS_PART_NAME='RES_0402-20.0,1%,1/16W,CHIP,G2A',
 PRIM_FILE='./archive_libs/mstr_discrete/res/chips/chips.prt';

PART_NAME
 R3R10 'RES_0402-4.75K,1%,1/16W,CHIP,GA':
 ROOM='PROC_SIDEBAND';

SECTION_NUMBER 1
 '@BASEBOARD_FAB2_LIB.BASEBOARD_FAB2(SCH_1):PAGE94_I79@MSTR_DISCRETE.RES(CHIPS)':
 C_PATH='@baseboard_fab2_lib.baseboard_fab2(sch_1):page94_i79@mstr_discrete.res(~
chips)',
 P_PATH='@baseboard_fab2_lib.baseboard_fab2(sch_1):page94_i79@mstr_discrete.res(~
chips)',
 PATH='I79',
 DRAWING='@BASEBOARD_FAB2_LIB.BASEBOARD_FAB2(SCH_1):PAGE94',
 WATTAGE='1/16W',
 TOLERANCE='1%',
 MATERIAL='CHIP',
 BOM_COST='PROC_SIDEBAND',
 PHYS_PAGE='94',
 XY='(1175,2425)',
 ROT='2',
 VER='2',
 VALUE='4.75K',
 PACK_TYPE='0402',
 PART_NUMBER='G21796-072',
 LOCATION='R3R10',
 ROOM='PROC_SIDEBAND',
 CDS_LIB='mstr_discrete',
 CDS_PART_NAME='RES_0402-4.75K,1%,1/16W,CHIP,GA',
 PRIM_FILE='./archive_libs/mstr_discrete/res/chips/chips.prt';

PART_NAME
 R3R11 'RES_0402-10.0K,1%,1/16W,EMPTY,A':
 ROOM='BMC_DEBUG_HEADER';

SECTION_NUMBER 1
 '@BASEBOARD_FAB2_LIB.BASEBOARD_FAB2(SCH_1):PAGE189_I45@MSTR_DISCRETE.RES(CHIPS)':
 C_PATH='@baseboard_fab2_lib.baseboard_fab2(sch_1):page189_i45@mstr_discrete.res~
(chips)',
 P_PATH='@baseboard_fab2_lib.baseboard_fab2(sch_1):page189_i45@mstr_discrete.res~
(chips)',
 PATH='I45',
 DRAWING='@BASEBOARD_FAB2_LIB.BASEBOARD_FAB2(SCH_1):PAGE189',
 WATTAGE='1/16W',
 TOLERANCE='1%',
 SEC_TYPE='0402',
 MATERIAL='EMPTY',
 PHYS_PAGE='189',
 XY='(175,1600)',
 ROT='0',
 VER='2',
 VALUE='10.0K',
 PACK_TYPE='0402',
 PART_NUMBER='G21796-016',
 LOCATION='R3R11',
 ROOM='BMC_DEBUG_HEADER',
 SEC='1',
 CDS_LIB='mstr_discrete',
 CDS_PART_NAME='RES_0402-10.0K,1%,1/16W,EMPTY,A',
 PRIM_FILE='./archive_libs/mstr_discrete/res/chips/chips.prt';

PART_NAME
 R3R12 'RES_0402-665,1.0%,1/16W,CHIP,GA':
 ROOM='MEM';

SECTION_NUMBER 1
 '@BASEBOARD_FAB2_LIB.BASEBOARD_FAB2(SCH_1):PAGE99_I101@MSTR_DISCRETE.RES(CHIPS)':
 C_PATH='@baseboard_fab2_lib.baseboard_fab2(sch_1):page99_i101@mstr_discrete.res~
(chips)',
 P_PATH='@baseboard_fab2_lib.baseboard_fab2(sch_1):page99_i101@mstr_discrete.res~
(chips)',
 PATH='I101',
 DRAWING='@BASEBOARD_FAB2_LIB.BASEBOARD_FAB2(SCH_1):PAGE99',
 WATTAGE='1/16W',
 TOLERANCE='1.0%',
 SEC_TYPE='0402',
 MATERIAL='CHIP',
 BOM_COST='SM_CONTROLLER',
 PHYS_PAGE='99',
 XY='(1275,3600)',
 ROT='0',
 VER='2',
 VALUE='665',
 PACK_TYPE='0402',
 PART_NUMBER='G21796-235',
 LOCATION='R3R12',
 ROOM='MEM',
 SEC='1',
 CDS_LIB='mstr_discrete',
 CDS_PART_NAME='RES_0402-665,1.0%,1/16W,CHIP,GA',
 PRIM_FILE='./archive_libs/mstr_discrete/res/chips/chips.prt';

PART_NAME
 R3R13 'RES_0402-240,1.0%,1/16W,CHIP,GA':
 ROOM='MEM',
 SIGNAL_MODEL='DEFAULT_RESISTOR_750OHM_2_1';

SECTION_NUMBER 1
 '@BASEBOARD_FAB2_LIB.BASEBOARD_FAB2(SCH_1):PAGE99_I65@MSTR_DISCRETE.RES(CHIPS)':
 C_PATH='@baseboard_fab2_lib.baseboard_fab2(sch_1):page99_i65@mstr_discrete.res(~
chips)',
 P_PATH='@baseboard_fab2_lib.baseboard_fab2(sch_1):page99_i65@mstr_discrete.res(~
chips)',
 PATH='I65',
 DRAWING='@BASEBOARD_FAB2_LIB.BASEBOARD_FAB2(SCH_1):PAGE99',
 CD_SEC='1',
 WATTAGE='1/16W',
 TOLERANCE='1.0%',
 MATERIAL='CHIP',
 BOM_COST='SM_CONTROLLER',
 PHYS_PAGE='99',
 XY='(-675,3600)',
 ROT='2',
 VER='2',
 VALUE='240',
 PACK_TYPE='0402',
 PART_NUMBER='G21796-294',
 LOCATION='R3R13',
 SIGNAL_MODEL='DEFAULT_RESISTOR_750OHM_2_1',
 ROOM='MEM',
 CDS_LIB='mstr_discrete',
 CDS_PART_NAME='RES_0402-240,1.0%,1/16W,CHIP,GA',
 PRIM_FILE='./archive_libs/mstr_discrete/res/chips/chips.prt';

PART_NAME
 R3R14 'RES_0402-10.0,1%,1/16W,CHIP,G2A':
 ROOM='MEM';

SECTION_NUMBER 1
 '@BASEBOARD_FAB2_LIB.BASEBOARD_FAB2(SCH_1):PAGE99_I110@MSTR_DISCRETE.RES(CHIPS)':
 C_PATH='@baseboard_fab2_lib.baseboard_fab2(sch_1):page99_i110@mstr_discrete.res~
(chips)',
 P_PATH='@baseboard_fab2_lib.baseboard_fab2(sch_1):page99_i110@mstr_discrete.res~
(chips)',
 PATH='I110',
 DRAWING='@BASEBOARD_FAB2_LIB.BASEBOARD_FAB2(SCH_1):PAGE99',
 WATTAGE='1/16W',
 TOLERANCE='1%',
 MATERIAL='CHIP',
 BOM_COST='SM_CONTROLLER',
 PHYS_PAGE='99',
 XY='(-1175,3250)',
 ROT='0',
 VER='1',
 VALUE='10.0',
 PACK_TYPE='0402',
 PART_NUMBER='G21796-066',
 LOCATION='R3R14',
 ROOM='MEM',
 CDS_LIB='mstr_discrete',
 CDS_PART_NAME='RES_0402-10.0,1%,1/16W,CHIP,G2A',
 PRIM_FILE='./archive_libs/mstr_discrete/res/chips/chips.prt';

PART_NAME
 R3R15 'RES_0402-1.00K,1%,1/16W,CHIP,GA':
 ROOM='BMC_DEBUG_HEADER';

SECTION_NUMBER 1
 '@BASEBOARD_FAB2_LIB.BASEBOARD_FAB2(SCH_1):PAGE189_I44@MSTR_DISCRETE.RES(CHIPS)':
 C_PATH='@baseboard_fab2_lib.baseboard_fab2(sch_1):page189_i44@mstr_discrete.res~
(chips)',
 P_PATH='@baseboard_fab2_lib.baseboard_fab2(sch_1):page189_i44@mstr_discrete.res~
(chips)',
 PATH='I44',
 DRAWING='@BASEBOARD_FAB2_LIB.BASEBOARD_FAB2(SCH_1):PAGE189',
 WATTAGE='1/16W',
 TOLERANCE='1%',
 SEC_TYPE='0402',
 MATERIAL='CHIP',
 PHYS_PAGE='189',
 XY='(175,2000)',
 ROT='0',
 VER='2',
 VALUE='1.00K',
 PACK_TYPE='0402',
 PART_NUMBER='G21796-026',
 LOCATION='R3R15',
 ROOM='BMC_DEBUG_HEADER',
 SEC='1',
 CDS_LIB='mstr_discrete',
 CDS_PART_NAME='RES_0402-1.00K,1%,1/16W,CHIP,GA',
 PRIM_FILE='./archive_libs/mstr_discrete/res/chips/chips.prt';

PART_NAME
 R3R16 'RES_0402-4.75K,1%,1/16W,CHIP,GA':
 ROOM='CPLD';

SECTION_NUMBER 1
 '@BASEBOARD_FAB2_LIB.BASEBOARD_FAB2(SCH_1):PAGE192_I48@MSTR_DISCRETE.RES(CHIPS)':
 C_PATH='@baseboard_fab2_lib.baseboard_fab2(sch_1):page192_i48@mstr_discrete.res~
(chips)',
 P_PATH='@baseboard_fab2_lib.baseboard_fab2(sch_1):page192_i48@mstr_discrete.res~
(chips)',
 PATH='I48',
 DRAWING='@BASEBOARD_FAB2_LIB.BASEBOARD_FAB2(SCH_1):PAGE192',
 WATTAGE='1/16W',
 TOLERANCE='1%',
 SEC_TYPE='0402',
 MATERIAL='CHIP',
 BOM_COST='CPLD',
 PHYS_PAGE='192',
 XY='(-6150,2800)',
 ROT='0',
 VER='2',
 VALUE='4.75K',
 PACK_TYPE='0402',
 PART_NUMBER='G21796-072',
 LOCATION='R3R16',
 ROOM='CPLD',
 SEC='1',
 CDS_LIB='mstr_discrete',
 CDS_PART_NAME='RES_0402-4.75K,1%,1/16W,CHIP,GA',
 PRIM_FILE='./archive_libs/mstr_discrete/res/chips/chips.prt';

PART_NAME
 R3T1 'RES_0402-33.2,1%,1/16W,CHIP,G2A':
 GROUP='NI_BIOS_ROM2',
 ROOM='SB_SPI',
 NO_XNET_CONNECTION='1';

SECTION_NUMBER 1
 '@BASEBOARD_FAB2_LIB.BASEBOARD_FAB2(SCH_1):PAGE153_I157@MSTR_DISCRETE.RES(CHIPS)':
 C_PATH='@baseboard_fab2_lib.baseboard_fab2(sch_1):page153_i157@mstr_discrete.re~
s(chips)',
 P_PATH='@baseboard_fab2_lib.baseboard_fab2(sch_1):page153_i157@mstr_discrete.re~
s(chips)',
 PATH='I157',
 DRAWING='@BASEBOARD_FAB2_LIB.BASEBOARD_FAB2(SCH_1):PAGE153',
 WATTAGE='1/16W',
 TOLERANCE='1%',
 SEC_TYPE='0402',
 MATERIAL='CHIP',
 BOM_COST='MIO_BIOS_MEM',
 NO_XNET_CONNECTION='1',
 PHYS_PAGE='153',
 XY='(-6425,1200)',
 ROT='0',
 VER='1',
 VALUE='33.2',
 PACK_TYPE='0402',
 PART_NUMBER='G21796-074',
 LOCATION='R3T1',
 ROOM='SB_SPI',
 GROUP='NI_BIOS_ROM2',
 SEC='1',
 CDS_LIB='mstr_discrete',
 CDS_PART_NAME='RES_0402-33.2,1%,1/16W,CHIP,G2A',
 PRIM_FILE='./archive_libs/mstr_discrete/res/chips/chips.prt';

PART_NAME
 R3T2 'RES_0402-33.2,1%,1/16W,CHIP,G2A':
 GROUP='NI_BIOS_ROM2',
 ROOM='SB_SPI';

SECTION_NUMBER 1
 '@BASEBOARD_FAB2_LIB.BASEBOARD_FAB2(SCH_1):PAGE153_I155@MSTR_DISCRETE.RES(CHIPS)':
 C_PATH='@baseboard_fab2_lib.baseboard_fab2(sch_1):page153_i155@mstr_discrete.re~
s(chips)',
 P_PATH='@baseboard_fab2_lib.baseboard_fab2(sch_1):page153_i155@mstr_discrete.re~
s(chips)',
 PATH='I155',
 DRAWING='@BASEBOARD_FAB2_LIB.BASEBOARD_FAB2(SCH_1):PAGE153',
 WATTAGE='1/16W',
 TOLERANCE='1%',
 SEC_TYPE='0402',
 MATERIAL='CHIP',
 BOM_COST='MIO_BIOS_MEM',
 PHYS_PAGE='153',
 XY='(-6275,1675)',
 ROT='0',
 VER='1',
 VALUE='33.2',
 PACK_TYPE='0402',
 PART_NUMBER='G21796-074',
 LOCATION='R3T2',
 ROOM='SB_SPI',
 GROUP='NI_BIOS_ROM2',
 SEC='1',
 CDS_LIB='mstr_discrete',
 CDS_PART_NAME='RES_0402-33.2,1%,1/16W,CHIP,G2A',
 PRIM_FILE='./archive_libs/mstr_discrete/res/chips/chips.prt';

PART_NAME
 R3T3 'RES_0402-4.75K,1%,1/16W,EMPTY,A':
 GROUP='NI_BIOS_ROM2',
 ROOM='SB_SPI',
 NO_XNET_CONNECTION='1';

SECTION_NUMBER 1
 '@BASEBOARD_FAB2_LIB.BASEBOARD_FAB2(SCH_1):PAGE153_I150@MSTR_DISCRETE.RES(CHIPS)':
 C_PATH='@baseboard_fab2_lib.baseboard_fab2(sch_1):page153_i150@mstr_discrete.re~
s(chips)',
 P_PATH='@baseboard_fab2_lib.baseboard_fab2(sch_1):page153_i150@mstr_discrete.re~
s(chips)',
 PATH='I150',
 DRAWING='@BASEBOARD_FAB2_LIB.BASEBOARD_FAB2(SCH_1):PAGE153',
 WATTAGE='1/16W',
 TOLERANCE='1%',
 SEC_TYPE='0402',
 MATERIAL='EMPTY',
 BOM_COST='MIO_BIOS_MEM',
 NO_XNET_CONNECTION='1',
 PHYS_PAGE='153',
 XY='(-5875,2325)',
 ROT='2',
 VER='2',
 VALUE='4.75K',
 PACK_TYPE='0402',
 PART_NUMBER='G21796-072',
 LOCATION='R3T3',
 ROOM='SB_SPI',
 GROUP='NI_BIOS_ROM2',
 SEC='1',
 CDS_LIB='mstr_discrete',
 CDS_PART_NAME='RES_0402-4.75K,1%,1/16W,EMPTY,A',
 PRIM_FILE='./archive_libs/mstr_discrete/res/chips/chips.prt';

PART_NAME
 R3T4 'RES_0402-10.0K,1%,1/16W,CHIP,GA':
 GROUP='NI_BIOS_ROM2',
 ROOM='SB_SPI';

SECTION_NUMBER 1
 '@BASEBOARD_FAB2_LIB.BASEBOARD_FAB2(SCH_1):PAGE153_I174@MSTR_DISCRETE.RES(CHIPS)':
 C_PATH='@baseboard_fab2_lib.baseboard_fab2(sch_1):page153_i174@mstr_discrete.re~
s(chips)',
 P_PATH='@baseboard_fab2_lib.baseboard_fab2(sch_1):page153_i174@mstr_discrete.re~
s(chips)',
 PATH='I174',
 DRAWING='@BASEBOARD_FAB2_LIB.BASEBOARD_FAB2(SCH_1):PAGE153',
 WATTAGE='1/16W',
 TOLERANCE='1%',
 SEC_TYPE='0402',
 MATERIAL='CHIP',
 BOM_COST='MIO_BIOS_MEM',
 PHYS_PAGE='153',
 XY='(-1450,2325)',
 ROT='0',
 VER='1',
 VALUE='10.0K',
 PACK_TYPE='0402',
 PART_NUMBER='G21796-016',
 LOCATION='R3T4',
 ROOM='SB_SPI',
 GROUP='NI_BIOS_ROM2',
 SEC='1',
 CDS_LIB='mstr_discrete',
 CDS_PART_NAME='RES_0402-10.0K,1%,1/16W,CHIP,GA',
 PRIM_FILE='./archive_libs/mstr_discrete/res/chips/chips.prt';

PART_NAME
 R3T5 'RES_0402-4.75K,1%,1/16W,CHIP,GA':
 GROUP='NI_BIOS_ROM2',
 ROOM='SB_SPI',
 NO_XNET_CONNECTION='1';

SECTION_NUMBER 1
 '@BASEBOARD_FAB2_LIB.BASEBOARD_FAB2(SCH_1):PAGE153_I152@MSTR_DISCRETE.RES(CHIPS)':
 C_PATH='@baseboard_fab2_lib.baseboard_fab2(sch_1):page153_i152@mstr_discrete.re~
s(chips)',
 P_PATH='@baseboard_fab2_lib.baseboard_fab2(sch_1):page153_i152@mstr_discrete.re~
s(chips)',
 PATH='I152',
 DRAWING='@BASEBOARD_FAB2_LIB.BASEBOARD_FAB2(SCH_1):PAGE153',
 WATTAGE='1/16W',
 TOLERANCE='1%',
 SEC_TYPE='0402',
 MATERIAL='CHIP',
 BOM_COST='MIO_BIOS_MEM',
 NO_XNET_CONNECTION='1',
 PHYS_PAGE='153',
 XY='(-6175,2325)',
 ROT='2',
 VER='2',
 VALUE='4.75K',
 PACK_TYPE='0402',
 PART_NUMBER='G21796-072',
 LOCATION='R3T5',
 ROOM='SB_SPI',
 GROUP='NI_BIOS_ROM2',
 SEC='1',
 CDS_LIB='mstr_discrete',
 CDS_PART_NAME='RES_0402-4.75K,1%,1/16W,CHIP,GA',
 PRIM_FILE='./archive_libs/mstr_discrete/res/chips/chips.prt';

PART_NAME
 R3T9 'RES_0402-10.0K,1%,1/16W,EMPTY,A':
 GROUP='NI_BIOS_ROM2',
 ROOM='SB_SPI';

SECTION_NUMBER 1
 '@BASEBOARD_FAB2_LIB.BASEBOARD_FAB2(SCH_1):PAGE153_I179@MSTR_DISCRETE.RES(CHIPS)':
 C_PATH='@baseboard_fab2_lib.baseboard_fab2(sch_1):page153_i179@mstr_discrete.re~
s(chips)',
 P_PATH='@baseboard_fab2_lib.baseboard_fab2(sch_1):page153_i179@mstr_discrete.re~
s(chips)',
 PATH='I179',
 DRAWING='@BASEBOARD_FAB2_LIB.BASEBOARD_FAB2(SCH_1):PAGE153',
 WATTAGE='1/16W',
 TOLERANCE='1%',
 SEC_TYPE='0402',
 MATERIAL='EMPTY',
 BOM_COST='MIO_BIOS_MEM',
 PHYS_PAGE='153',
 XY='(-1750,1450)',
 ROT='0',
 VER='2',
 VALUE='10.0K',
 PACK_TYPE='0402',
 PART_NUMBER='G21796-016',
 LOCATION='R3T9',
 ROOM='SB_SPI',
 GROUP='NI_BIOS_ROM2',
 SEC='1',
 CDS_LIB='mstr_discrete',
 CDS_PART_NAME='RES_0402-10.0K,1%,1/16W,EMPTY,A',
 PRIM_FILE='./archive_libs/mstr_discrete/res/chips/chips.prt';

PART_NAME
 R3T10 'RES_0402-33.2,1%,1/16W,CHIP,G2A':
 GROUP='NI_BIOS_ROM2',
 ROOM='SB_SPI';

SECTION_NUMBER 1
 '@BASEBOARD_FAB2_LIB.BASEBOARD_FAB2(SCH_1):PAGE153_I184@MSTR_DISCRETE.RES(CHIPS)':
 C_PATH='@baseboard_fab2_lib.baseboard_fab2(sch_1):page153_i184@mstr_discrete.re~
s(chips)',
 P_PATH='@baseboard_fab2_lib.baseboard_fab2(sch_1):page153_i184@mstr_discrete.re~
s(chips)',
 PATH='I184',
 DRAWING='@BASEBOARD_FAB2_LIB.BASEBOARD_FAB2(SCH_1):PAGE153',
 WATTAGE='1/16W',
 TOLERANCE='1%',
 SEC_TYPE='0402',
 MATERIAL='CHIP',
 BOM_COST='MIO_BIOS_MEM',
 PHYS_PAGE='153',
 XY='(-6275,1725)',
 ROT='0',
 VER='1',
 VALUE='33.2',
 PACK_TYPE='0402',
 PART_NUMBER='G21796-074',
 LOCATION='R3T10',
 ROOM='SB_SPI',
 GROUP='NI_BIOS_ROM2',
 SEC='1',
 CDS_LIB='mstr_discrete',
 CDS_PART_NAME='RES_0402-33.2,1%,1/16W,CHIP,G2A',
 PRIM_FILE='./archive_libs/mstr_discrete/res/chips/chips.prt';

PART_NAME
 R3T11 'RES_0402-49.9,1%,1/16W,CHIP,G2A':
 ROOM='VDDQ_DEF_PWR_VR';

SECTION_NUMBER 1
 '@BASEBOARD_FAB2_LIB.BASEBOARD_FAB2(SCH_1):PAGE215_I70@MSTR_DISCRETE.RES(CHIPS)':
 C_PATH='@baseboard_fab2_lib.baseboard_fab2(sch_1):page215_i70@mstr_discrete.res~
(chips)',
 P_PATH='@baseboard_fab2_lib.baseboard_fab2(sch_1):page215_i70@mstr_discrete.res~
(chips)',
 PATH='I70',
 DRAWING='@BASEBOARD_FAB2_LIB.BASEBOARD_FAB2(SCH_1):PAGE215',
 WATTAGE='1/16W',
 TOLERANCE='1%',
 SEC_TYPE='0402',
 MATERIAL='CHIP',
 PHYS_PAGE='215',
 XY='(450,3325)',
 ROT='0',
 VER='2',
 VALUE='49.9',
 PACK_TYPE='0402',
 PART_NUMBER='G21796-047',
 LOCATION='R3T11',
 ROOM='VDDQ_DEF_PWR_VR',
 SEC='1',
 CDS_LIB='mstr_discrete',
 CDS_PART_NAME='RES_0402-49.9,1%,1/16W,CHIP,G2A',
 PRIM_FILE='./archive_libs/mstr_discrete/res/chips/chips.prt';

PART_NAME
 R3T12 'RES_0402-10.0K,1%,1/16W,CHIP,GA':
 GROUP='NI_BIOS_ROM2',
 ROOM='SB_SPI';

SECTION_NUMBER 1
 '@BASEBOARD_FAB2_LIB.BASEBOARD_FAB2(SCH_1):PAGE153_I178@MSTR_DISCRETE.RES(CHIPS)':
 C_PATH='@baseboard_fab2_lib.baseboard_fab2(sch_1):page153_i178@mstr_discrete.re~
s(chips)',
 P_PATH='@baseboard_fab2_lib.baseboard_fab2(sch_1):page153_i178@mstr_discrete.re~
s(chips)',
 PATH='I178',
 DRAWING='@BASEBOARD_FAB2_LIB.BASEBOARD_FAB2(SCH_1):PAGE153',
 WATTAGE='1/16W',
 TOLERANCE='1%',
 SEC_TYPE='0402',
 MATERIAL='CHIP',
 BOM_COST='MIO_BIOS_MEM',
 PHYS_PAGE='153',
 XY='(-1750,1825)',
 ROT='0',
 VER='2',
 VALUE='10.0K',
 PACK_TYPE='0402',
 PART_NUMBER='G21796-016',
 LOCATION='R3T12',
 ROOM='SB_SPI',
 GROUP='NI_BIOS_ROM2',
 SEC='1',
 CDS_LIB='mstr_discrete',
 CDS_PART_NAME='RES_0402-10.0K,1%,1/16W,CHIP,GA',
 PRIM_FILE='./archive_libs/mstr_discrete/res/chips/chips.prt';

PART_NAME
 R3T13 'RES_0402-0.0,5%,1/16W,CHIP,G21A':
 ROOM='VDDQ_ABC_PWR_VR';

SECTION_NUMBER 1
 '@BASEBOARD_FAB2_LIB.BASEBOARD_FAB2(SCH_1):PAGE215_I33@MSTR_DISCRETE.RES(CHIPS)':
 C_PATH='@baseboard_fab2_lib.baseboard_fab2(sch_1):page215_i33@mstr_discrete.res~
(chips)',
 P_PATH='@baseboard_fab2_lib.baseboard_fab2(sch_1):page215_i33@mstr_discrete.res~
(chips)',
 PATH='I33',
 DRAWING='@BASEBOARD_FAB2_LIB.BASEBOARD_FAB2(SCH_1):PAGE215',
 WATTAGE='1/16W',
 TOLERANCE='5%',
 SEC_TYPE='0402',
 MATERIAL='CHIP',
 PHYS_PAGE='215',
 XY='(1675,3250)',
 ROT='0',
 VER='2',
 VALUE='0.0',
 PACK_TYPE='0402',
 PART_NUMBER='G21497-005',
 LOCATION='R3T13',
 ROOM='VDDQ_ABC_PWR_VR',
 SEC='1',
 CDS_LIB='mstr_discrete',
 CDS_PART_NAME='RES_0402-0.0,5%,1/16W,CHIP,G21A',
 PRIM_FILE='./archive_libs/mstr_discrete/res/chips/chips.prt';

PART_NAME
 R3T14 'RES_0402-10.0K,1%,1/16W,CHIP,GA':
 ROOM='SB';

SECTION_NUMBER 1
 '@BASEBOARD_FAB2_LIB.BASEBOARD_FAB2(SCH_1):PAGE136_I156@MSTR_DISCRETE.RES(CHIPS)':
 C_PATH='@baseboard_fab2_lib.baseboard_fab2(sch_1):page136_i156@mstr_discrete.re~
s(chips)',
 P_PATH='@baseboard_fab2_lib.baseboard_fab2(sch_1):page136_i156@mstr_discrete.re~
s(chips)',
 PATH='I156',
 DRAWING='@BASEBOARD_FAB2_LIB.BASEBOARD_FAB2(SCH_1):PAGE136',
 WATTAGE='1/16W',
 TOLERANCE='1%',
 SEC_TYPE='0402',
 MATERIAL='CHIP',
 BOM_COST='SB',
 PHYS_PAGE='136',
 XY='(-300,3900)',
 ROT='0',
 VER='2',
 VALUE='10.0K',
 PACK_TYPE='0402',
 PART_NUMBER='G21796-016',
 LOCATION='R3T14',
 ROOM='SB',
 SEC='1',
 CDS_LIB='mstr_discrete',
 CDS_PART_NAME='RES_0402-10.0K,1%,1/16W,CHIP,GA',
 PRIM_FILE='./archive_libs/mstr_discrete/res/chips/chips.prt';

PART_NAME
 R3U1 'RES_0402-33.2,1%,1/16W,CHIP,G2A':
 GROUP='NI_BIOS_ROM2',
 ROOM='SB_SPI',
 NO_XNET_CONNECTION='1';

SECTION_NUMBER 1
 '@BASEBOARD_FAB2_LIB.BASEBOARD_FAB2(SCH_1):PAGE153_I156@MSTR_DISCRETE.RES(CHIPS)':
 C_PATH='@baseboard_fab2_lib.baseboard_fab2(sch_1):page153_i156@mstr_discrete.re~
s(chips)',
 P_PATH='@baseboard_fab2_lib.baseboard_fab2(sch_1):page153_i156@mstr_discrete.re~
s(chips)',
 PATH='I156',
 DRAWING='@BASEBOARD_FAB2_LIB.BASEBOARD_FAB2(SCH_1):PAGE153',
 WATTAGE='1/16W',
 TOLERANCE='1%',
 SEC_TYPE='0402',
 MATERIAL='CHIP',
 BOM_COST='MIO_BIOS_MEM',
 NO_XNET_CONNECTION='1',
 PHYS_PAGE='153',
 XY='(-6425,1425)',
 ROT='0',
 VER='1',
 VALUE='33.2',
 PACK_TYPE='0402',
 PART_NUMBER='G21796-074',
 LOCATION='R3U1',
 ROOM='SB_SPI',
 GROUP='NI_BIOS_ROM2',
 SEC='1',
 CDS_LIB='mstr_discrete',
 CDS_PART_NAME='RES_0402-33.2,1%,1/16W,CHIP,G2A',
 PRIM_FILE='./archive_libs/mstr_discrete/res/chips/chips.prt';

PART_NAME
 R3U2 'RES_0402-100.0,1%,1/16W,CHIP,GA':
 ROOM='VDDQ_ABC_PWR_VR';

SECTION_NUMBER 1
 '@BASEBOARD_FAB2_LIB.BASEBOARD_FAB2(SCH_1):PAGE215_I58@MSTR_DISCRETE.RES(CHIPS)':
 C_PATH='@baseboard_fab2_lib.baseboard_fab2(sch_1):page215_i58@mstr_discrete.res~
(chips)',
 P_PATH='@baseboard_fab2_lib.baseboard_fab2(sch_1):page215_i58@mstr_discrete.res~
(chips)',
 PATH='I58',
 DRAWING='@BASEBOARD_FAB2_LIB.BASEBOARD_FAB2(SCH_1):PAGE215',
 WATTAGE='1/16W',
 TOLERANCE='1%',
 SEC_TYPE='0402',
 MATERIAL='CHIP',
 PHYS_PAGE='215',
 XY='(4750,2650)',
 ROT='0',
 VER='2',
 VALUE='100.0',
 PACK_TYPE='0402',
 PART_NUMBER='G21796-017',
 LOCATION='R3U2',
 ROOM='VDDQ_ABC_PWR_VR',
 SEC='1',
 CDS_LIB='mstr_discrete',
 CDS_PART_NAME='RES_0402-100.0,1%,1/16W,CHIP,GA',
 PRIM_FILE='./archive_libs/mstr_discrete/res/chips/chips.prt';

PART_NAME
 R3U4 'RES_0603-120.0,1%,1/10W,CHIP,GA':
 ROOM='VDDQ_ABC_PWR_VR';

SECTION_NUMBER 1
 '@BASEBOARD_FAB2_LIB.BASEBOARD_FAB2(SCH_1):PAGE217_I58@MSTR_DISCRETE.RES(CHIPS)':
 C_PATH='@baseboard_fab2_lib.baseboard_fab2(sch_1):page217_i58@mstr_discrete.res~
(chips)',
 P_PATH='@baseboard_fab2_lib.baseboard_fab2(sch_1):page217_i58@mstr_discrete.res~
(chips)',
 PATH='I58',
 DRAWING='@BASEBOARD_FAB2_LIB.BASEBOARD_FAB2(SCH_1):PAGE217',
 WATTAGE='1/10W',
 TOLERANCE='1%',
 MATERIAL='CHIP',
 BOM_COST='MEM_VRD_PVPP_AB',
 PHYS_PAGE='217',
 XY='(4550,-400)',
 ROT='0',
 VER='2',
 VALUE='120.0',
 PACK_TYPE='0603',
 PART_NUMBER='G22026-003',
 LOCATION='R3U4',
 ROOM='VDDQ_ABC_PWR_VR',
 CDS_LIB='mstr_discrete',
 CDS_PART_NAME='RES_0603-120.0,1%,1/10W,CHIP,GA',
 PRIM_FILE='./archive_libs/mstr_discrete/res/chips/chips.prt';

PART_NAME
 R3U6 'RES_0402-0.0,5%,1/16W,CHIP,G21A':
 ROOM='CPU0';

SECTION_NUMBER 1
 '@BASEBOARD_FAB2_LIB.BASEBOARD_FAB2(SCH_1):PAGE216_I145@MSTR_DISCRETE.RES(CHIPS)':
 C_PATH='@baseboard_fab2_lib.baseboard_fab2(sch_1):page216_i145@mstr_discrete.re~
s(chips)',
 P_PATH='@baseboard_fab2_lib.baseboard_fab2(sch_1):page216_i145@mstr_discrete.re~
s(chips)',
 PATH='I145',
 DRAWING='@BASEBOARD_FAB2_LIB.BASEBOARD_FAB2(SCH_1):PAGE216',
 WATTAGE='1/16W',
 TOLERANCE='5%',
 SEC_TYPE='0402',
 MATERIAL='CHIP',
 BOM_COST='PROC_SIDEBAND',
 PHYS_PAGE='216',
 XY='(-575,3100)',
 ROT='0',
 VER='1',
 VALUE='0.0',
 PACK_TYPE='0402',
 PART_NUMBER='G21497-005',
 LOCATION='R3U6',
 ROOM='CPU0',
 SEC='1',
 CDS_LIB='mstr_discrete',
 CDS_PART_NAME='RES_0402-0.0,5%,1/16W,CHIP,G21A',
 PRIM_FILE='./archive_libs/mstr_discrete/res/chips/chips.prt';

PART_NAME
 R3U9 'RES_0402-0.0,5%,1/16W,CHIP,G21A':
 ROOM='CPU0';

SECTION_NUMBER 1
 '@BASEBOARD_FAB2_LIB.BASEBOARD_FAB2(SCH_1):PAGE216_I146@MSTR_DISCRETE.RES(CHIPS)':
 C_PATH='@baseboard_fab2_lib.baseboard_fab2(sch_1):page216_i146@mstr_discrete.re~
s(chips)',
 P_PATH='@baseboard_fab2_lib.baseboard_fab2(sch_1):page216_i146@mstr_discrete.re~
s(chips)',
 PATH='I146',
 DRAWING='@BASEBOARD_FAB2_LIB.BASEBOARD_FAB2(SCH_1):PAGE216',
 BOM_SS='NOPOP',
 WATTAGE='1/16W',
 TOLERANCE='5%',
 SEC_TYPE='0402',
 MATERIAL='CHIP',
 BOM_COST='PROC_SIDEBAND',
 PHYS_PAGE='216',
 XY='(-600,725)',
 ROT='0',
 VER='1',
 VALUE='0.0',
 PACK_TYPE='0402',
 PART_NUMBER='G21497-005',
 LOCATION='R3U9',
 ROOM='CPU0',
 SEC='1',
 CDS_LIB='mstr_discrete',
 CDS_PART_NAME='RES_0402-0.0,5%,1/16W,CHIP,G21A',
 PRIM_FILE='./archive_libs/mstr_discrete/res/chips/chips.prt';

PART_NAME
 R3W1 'RES_0402-1.00K,1%,1/16W,CHIP,GA':
 ROOM='BMC_DEBUG_HEADER';

SECTION_NUMBER 1
 '@BASEBOARD_FAB2_LIB.BASEBOARD_FAB2(SCH_1):PAGE249_I2@MSTR_DISCRETE.RES(CHIPS)':
 C_PATH='@baseboard_fab2_lib.baseboard_fab2(sch_1):page249_i2@mstr_discrete.res(~
chips)',
 P_PATH='@baseboard_fab2_lib.baseboard_fab2(sch_1):page249_i2@mstr_discrete.res(~
chips)',
 PATH='I2',
 DRAWING='@BASEBOARD_FAB2_LIB.BASEBOARD_FAB2(SCH_1):PAGE249',
 NEW_VALUE='470K',
 CONFIG='64.47035.L0L',
 WATTAGE='1/16W',
 TOLERANCE='1%',
 SEC_TYPE='0402',
 MATERIAL='CHIP',
 PHYS_PAGE='249',
 XY='(-6850,1950)',
 ROT='0',
 VER='2',
 VALUE='1.00K',
 PACK_TYPE='0402',
 PART_NUMBER='G21796-026',
 LOCATION='R3W1',
 ROOM='BMC_DEBUG_HEADER',
 SEC='1',
 CDS_LIB='mstr_discrete',
 CDS_PART_NAME='RES_0402-1.00K,1%,1/16W,CHIP,GA',
 PRIM_FILE='./archive_libs/mstr_discrete/res/chips/chips.prt';

PART_NAME
 R3W2 'RES_0402-100.0K,1%,1/16W,CHIP,A':
 ROOM='SB';

SECTION_NUMBER 1
 '@BASEBOARD_FAB2_LIB.BASEBOARD_FAB2(SCH_1):PAGE249_I56@MSTR_DISCRETE.RES(CHIPS)':
 C_PATH='@baseboard_fab2_lib.baseboard_fab2(sch_1):page249_i56@mstr_discrete.res~
(chips)',
 P_PATH='@baseboard_fab2_lib.baseboard_fab2(sch_1):page249_i56@mstr_discrete.res~
(chips)',
 PATH='I56',
 DRAWING='@BASEBOARD_FAB2_LIB.BASEBOARD_FAB2(SCH_1):PAGE249',
 WATTAGE='1/16W',
 TOLERANCE='1%',
 MATERIAL='CHIP',
 PHYS_PAGE='249',
 XY='(-6350,1950)',
 ROT='0',
 VER='2',
 VALUE='100.0K',
 PACK_TYPE='0402',
 PART_NUMBER='G21796-010',
 LOCATION='R3W2',
 ROOM='SB',
 CDS_LIB='mstr_discrete',
 CDS_PART_NAME='RES_0402-100.0K,1%,1/16W,CHIP,A',
 PRIM_FILE='./archive_libs/mstr_discrete/res/chips/chips.prt';

PART_NAME
 R3W3 'RES_0402-10.0K,1%,1/16W,EMPTY,A':
 ROOM='DB1200ZL';

SECTION_NUMBER 1
 '@BASEBOARD_FAB2_LIB.BASEBOARD_FAB2(SCH_1):PAGE249_I36@MSTR_DISCRETE.RES(CHIPS)':
 C_PATH='@baseboard_fab2_lib.baseboard_fab2(sch_1):page249_i36@mstr_discrete.res~
(chips)',
 P_PATH='@baseboard_fab2_lib.baseboard_fab2(sch_1):page249_i36@mstr_discrete.res~
(chips)',
 PATH='I36',
 DRAWING='@BASEBOARD_FAB2_LIB.BASEBOARD_FAB2(SCH_1):PAGE249',
 WATTAGE='1/16W',
 TOLERANCE='1%',
 SEC_TYPE='0402',
 MATERIAL='EMPTY',
 BOM_COST='SYS_CLOCK',
 PHYS_PAGE='249',
 XY='(-4850,2850)',
 ROT='0',
 VER='2',
 VALUE='10.0K',
 PACK_TYPE='0402',
 PART_NUMBER='G21796-016',
 LOCATION='R3W3',
 ROOM='DB1200ZL',
 SEC='1',
 CDS_LIB='mstr_discrete',
 CDS_PART_NAME='RES_0402-10.0K,1%,1/16W,EMPTY,A',
 PRIM_FILE='./archive_libs/mstr_discrete/res/chips/chips.prt';

PART_NAME
 R3W4 '47KR2F-GP_RCL_GP-47KR2F-GP,64.A':;

SECTION_NUMBER 1
 '@BASEBOARD_FAB2_LIB.BASEBOARD_FAB2(SCH_1):PAGE249_I31@W_HDL.47KR2F-GP(CHIPS)':
 C_PATH='@baseboard_fab2_lib.baseboard_fab2(sch_1):page249_i31@w_hdl.\47kr2f-gp\~
(chips)',
 P_PATH='@baseboard_fab2_lib.baseboard_fab2(sch_1):page249_i31@w_hdl.\47kr2f-gp\~
(chips)',
 PATH='I31',
 DRAWING='@BASEBOARD_FAB2_LIB.BASEBOARD_FAB2(SCH_1):PAGE249',
 PACK_SIZE='0402',
 RATED='1/16W',
 ATTRIBUTE='47KOHM',
 TOLERANCE='1%',
 PHYS_PAGE='249',
 XY='(-4325,3850)',
 ROT='1',
 VER='1',
 VALUE='47KR2F-GP',
 PACK_TYPE='RCL_GP',
 PART_NUMBER='64.47025.6DL',
 LOCATION='R3W4',
 CDS_LIB='w_hdl',
 CDS_PART_NAME='47KR2F-GP_RCL_GP-47KR2F-GP,64.A',
 PRIM_FILE='C:/<user>/w_hdl/47kr2f#2dgp/chips/chips.prt';

PART_NAME
 R3W5 'RES_0402-10.0K,1%,1/16W,CHIP,GA':
 ROOM='CPU0';

SECTION_NUMBER 1
 '@BASEBOARD_FAB2_LIB.BASEBOARD_FAB2(SCH_1):PAGE249_I58@MSTR_DISCRETE.RES(CHIPS)':
 C_PATH='@baseboard_fab2_lib.baseboard_fab2(sch_1):page249_i58@mstr_discrete.res~
(chips)',
 P_PATH='@baseboard_fab2_lib.baseboard_fab2(sch_1):page249_i58@mstr_discrete.res~
(chips)',
 PATH='I58',
 DRAWING='@BASEBOARD_FAB2_LIB.BASEBOARD_FAB2(SCH_1):PAGE249',
 WATTAGE='1/16W',
 TOLERANCE='1%',
 SEC_TYPE='0402',
 MATERIAL='CHIP',
 BOM_COST='PROC_SIDEBAND',
 PHYS_PAGE='249',
 XY='(-3200,4350)',
 ROT='0',
 VER='2',
 VALUE='10.0K',
 PACK_TYPE='0402',
 PART_NUMBER='G21796-016',
 LOCATION='R3W5',
 ROOM='CPU0',
 SEC='1',
 CDS_LIB='mstr_discrete',
 CDS_PART_NAME='RES_0402-10.0K,1%,1/16W,CHIP,GA',
 PRIM_FILE='./archive_libs/mstr_discrete/res/chips/chips.prt';

PART_NAME
 R3W6 'RES_0402-4.75K,1%,1/16W,CHIP,GA':
 ROOM='SB_SPI',
 NO_XNET_CONNECTION='1';

SECTION_NUMBER 1
 '@BASEBOARD_FAB2_LIB.BASEBOARD_FAB2(SCH_1):PAGE249_I48@MSTR_DISCRETE.RES(CHIPS)':
 C_PATH='@baseboard_fab2_lib.baseboard_fab2(sch_1):page249_i48@mstr_discrete.res~
(chips)',
 P_PATH='@baseboard_fab2_lib.baseboard_fab2(sch_1):page249_i48@mstr_discrete.res~
(chips)',
 PATH='I48',
 DRAWING='@BASEBOARD_FAB2_LIB.BASEBOARD_FAB2(SCH_1):PAGE249',
 WATTAGE='1/16W',
 TOLERANCE='1%',
 SEC_TYPE='0402',
 MATERIAL='CHIP',
 BOM_COST='MIO_BIOS_MEM',
 NO_XNET_CONNECTION='1',
 PHYS_PAGE='249',
 XY='(-2300,4450)',
 ROT='2',
 VER='2',
 VALUE='4.75K',
 PACK_TYPE='0402',
 PART_NUMBER='G21796-072',
 LOCATION='R3W6',
 ROOM='SB_SPI',
 SEC='1',
 CDS_LIB='mstr_discrete',
 CDS_PART_NAME='RES_0402-4.75K,1%,1/16W,CHIP,GA',
 PRIM_FILE='./archive_libs/mstr_discrete/res/chips/chips.prt';

PART_NAME
 R3W7 'RES_0402-4.75K,1%,1/16W,CHIP,GA':
 ROOM='SB_SPI',
 NO_XNET_CONNECTION='1';

SECTION_NUMBER 1
 '@BASEBOARD_FAB2_LIB.BASEBOARD_FAB2(SCH_1):PAGE249_I8@MSTR_DISCRETE.RES(CHIPS)':
 C_PATH='@baseboard_fab2_lib.baseboard_fab2(sch_1):page249_i8@mstr_discrete.res(~
chips)',
 P_PATH='@baseboard_fab2_lib.baseboard_fab2(sch_1):page249_i8@mstr_discrete.res(~
chips)',
 PATH='I8',
 DRAWING='@BASEBOARD_FAB2_LIB.BASEBOARD_FAB2(SCH_1):PAGE249',
 WATTAGE='1/16W',
 TOLERANCE='1%',
 SEC_TYPE='0402',
 MATERIAL='CHIP',
 BOM_COST='MIO_BIOS_MEM',
 NO_XNET_CONNECTION='1',
 PHYS_PAGE='249',
 XY='(-3325,2775)',
 ROT='2',
 VER='2',
 VALUE='4.75K',
 PACK_TYPE='0402',
 PART_NUMBER='G21796-072',
 LOCATION='R3W7',
 ROOM='SB_SPI',
 SEC='1',
 CDS_LIB='mstr_discrete',
 CDS_PART_NAME='RES_0402-4.75K,1%,1/16W,CHIP,GA',
 PRIM_FILE='./archive_libs/mstr_discrete/res/chips/chips.prt';

PART_NAME
 R3W9 'RES_0402-10.0K,1%,1/16W,CHIP,GA':
 ROOM='M_2';

SECTION_NUMBER 1
 '@BASEBOARD_FAB2_LIB.BASEBOARD_FAB2(SCH_1):PAGE249_I7@MSTR_DISCRETE.RES(CHIPS)':
 C_PATH='@baseboard_fab2_lib.baseboard_fab2(sch_1):page249_i7@mstr_discrete.res(~
chips)',
 P_PATH='@baseboard_fab2_lib.baseboard_fab2(sch_1):page249_i7@mstr_discrete.res(~
chips)',
 PATH='I7',
 DRAWING='@BASEBOARD_FAB2_LIB.BASEBOARD_FAB2(SCH_1):PAGE249',
 WATTAGE='1/16W',
 TOLERANCE='1%',
 SEC_TYPE='0402',
 MATERIAL='CHIP',
 BOM_COST='ST_FLASH',
 PHYS_PAGE='249',
 XY='(-3325,2300)',
 ROT='0',
 VER='2',
 VALUE='10.0K',
 PACK_TYPE='0402',
 PART_NUMBER='G21796-016',
 LOCATION='R3W9',
 ROOM='M_2',
 SEC='1',
 CDS_LIB='mstr_discrete',
 CDS_PART_NAME='RES_0402-10.0K,1%,1/16W,CHIP,GA',
 PRIM_FILE='./archive_libs/mstr_discrete/res/chips/chips.prt';

PART_NAME
 R3W10 'RES_0402-49.9,1%,1/16W,EMPTY,GA':
 ROOM='SB';

SECTION_NUMBER 1
 '@BASEBOARD_FAB2_LIB.BASEBOARD_FAB2(SCH_1):PAGE92_I108@MSTR_DISCRETE.RES(CHIPS)':
 C_PATH='@baseboard_fab2_lib.baseboard_fab2(sch_1):page92_i108@mstr_discrete.res~
(chips)',
 P_PATH='@baseboard_fab2_lib.baseboard_fab2(sch_1):page92_i108@mstr_discrete.res~
(chips)',
 PATH='I108',
 DRAWING='@BASEBOARD_FAB2_LIB.BASEBOARD_FAB2(SCH_1):PAGE92',
 WATTAGE='1/16W',
 TOLERANCE='1%',
 SEC_TYPE='0402',
 MATERIAL='EMPTY',
 PHYS_PAGE='92',
 XY='(-400,5350)',
 ROT='0',
 VER='2',
 VALUE='49.9',
 PACK_TYPE='0402',
 PART_NUMBER='G21796-047',
 LOCATION='R3W10',
 ROOM='SB',
 SEC='1',
 CDS_LIB='mstr_discrete',
 CDS_PART_NAME='RES_0402-49.9,1%,1/16W,EMPTY,GA',
 PRIM_FILE='./archive_libs/mstr_discrete/res/chips/chips.prt';

PART_NAME
 R4A2 'RES_0402-0.0,5%,1/16W,CHIP,G21A':
 ROOM='VTT_DEF_PWR_VR';

SECTION_NUMBER 1
 '@BASEBOARD_FAB2_LIB.BASEBOARD_FAB2(SCH_1):PAGE222_I4@MSTR_DISCRETE.RES(CHIPS)':
 C_PATH='@baseboard_fab2_lib.baseboard_fab2(sch_1):page222_i4@mstr_discrete.res(~
chips)',
 P_PATH='@baseboard_fab2_lib.baseboard_fab2(sch_1):page222_i4@mstr_discrete.res(~
chips)',
 PATH='I4',
 DRAWING='@BASEBOARD_FAB2_LIB.BASEBOARD_FAB2(SCH_1):PAGE222',
 WATTAGE='1/16W',
 TOLERANCE='5%',
 SEC_TYPE='0402',
 MATERIAL='CHIP',
 BOM_COST='MEM_VRD_VTT_DEF',
 PHYS_PAGE='222',
 XY='(-1300,-325)',
 ROT='0',
 VER='1',
 VALUE='0.0',
 PACK_TYPE='0402',
 PART_NUMBER='G21497-005',
 LOCATION='R4A2',
 ROOM='VTT_DEF_PWR_VR',
 SEC='1',
 CDS_LIB='mstr_discrete',
 CDS_PART_NAME='RES_0402-0.0,5%,1/16W,CHIP,G21A',
 PRIM_FILE='./archive_libs/mstr_discrete/res/chips/chips.prt';

PART_NAME
 R4A3 'RES_0402-0.0,5%,1/16W,CHIP,G21A':
 ROOM='VTT_KLM_PWR_VR';

SECTION_NUMBER 1
 '@BASEBOARD_FAB2_LIB.BASEBOARD_FAB2(SCH_1):PAGE230_I4@MSTR_DISCRETE.RES(CHIPS)':
 C_PATH='@baseboard_fab2_lib.baseboard_fab2(sch_1):page230_i4@mstr_discrete.res(~
chips)',
 P_PATH='@baseboard_fab2_lib.baseboard_fab2(sch_1):page230_i4@mstr_discrete.res(~
chips)',
 PATH='I4',
 DRAWING='@BASEBOARD_FAB2_LIB.BASEBOARD_FAB2(SCH_1):PAGE230',
 WATTAGE='1/16W',
 TOLERANCE='5%',
 SEC_TYPE='0402',
 MATERIAL='CHIP',
 BOM_COST='MEM_VRD_VTT_KLM',
 PHYS_PAGE='230',
 XY='(-2225,-600)',
 ROT='0',
 VER='1',
 VALUE='0.0',
 PACK_TYPE='0402',
 PART_NUMBER='G21497-005',
 LOCATION='R4A3',
 ROOM='VTT_KLM_PWR_VR',
 SEC='1',
 CDS_LIB='mstr_discrete',
 CDS_PART_NAME='RES_0402-0.0,5%,1/16W,CHIP,G21A',
 PRIM_FILE='./archive_libs/mstr_discrete/res/chips/chips.prt';

PART_NAME
 R4A4 'RES_0402-33.2,1%,1/16W,CHIP,G2A':;

SECTION_NUMBER 1
 '@BASEBOARD_FAB2_LIB.BASEBOARD_FAB2(SCH_1):PAGE230_I32@MSTR_DISCRETE.RES(CHIPS)':
 C_PATH='@baseboard_fab2_lib.baseboard_fab2(sch_1):page230_i32@mstr_discrete.res~
(chips)',
 P_PATH='@baseboard_fab2_lib.baseboard_fab2(sch_1):page230_i32@mstr_discrete.res~
(chips)',
 PATH='I32',
 DRAWING='@BASEBOARD_FAB2_LIB.BASEBOARD_FAB2(SCH_1):PAGE230',
 WATTAGE='1/16W',
 TOLERANCE='1%',
 SEC_TYPE='0402',
 MATERIAL='CHIP',
 PHYS_PAGE='230',
 XY='(2575,1100)',
 ROT='0',
 VER='1',
 VALUE='33.2',
 PACK_TYPE='0402',
 PART_NUMBER='G21796-074',
 LOCATION='R4A4',
 SEC='1',
 CDS_LIB='mstr_discrete',
 CDS_PART_NAME='RES_0402-33.2,1%,1/16W,CHIP,G2A',
 PRIM_FILE='./archive_libs/mstr_discrete/res/chips/chips.prt';

PART_NAME
 R4A5 'RES_0402-10.0K,1%,1/16W,CHIP,GA':
 ROOM='VTT_KLM_PWR_VR';

SECTION_NUMBER 1
 '@BASEBOARD_FAB2_LIB.BASEBOARD_FAB2(SCH_1):PAGE230_I21@MSTR_DISCRETE.RES(CHIPS)':
 C_PATH='@baseboard_fab2_lib.baseboard_fab2(sch_1):page230_i21@mstr_discrete.res~
(chips)',
 P_PATH='@baseboard_fab2_lib.baseboard_fab2(sch_1):page230_i21@mstr_discrete.res~
(chips)',
 PATH='I21',
 DRAWING='@BASEBOARD_FAB2_LIB.BASEBOARD_FAB2(SCH_1):PAGE230',
 WATTAGE='1/16W',
 TOLERANCE='1%',
 SEC_TYPE='0402',
 MATERIAL='CHIP',
 BOM_COST='MEM_VRD_VTT_KLM',
 PHYS_PAGE='230',
 XY='(1800,1250)',
 ROT='2',
 VER='2',
 VALUE='10.0K',
 PACK_TYPE='0402',
 PART_NUMBER='G21796-016',
 LOCATION='R4A5',
 ROOM='VTT_KLM_PWR_VR',
 SEC='1',
 CDS_LIB='mstr_discrete',
 CDS_PART_NAME='RES_0402-10.0K,1%,1/16W,CHIP,GA',
 PRIM_FILE='./archive_libs/mstr_discrete/res/chips/chips.prt';

PART_NAME
 R4A6 'RES_0402-33.2,1%,1/16W,CHIP,G2A':;

SECTION_NUMBER 1
 '@BASEBOARD_FAB2_LIB.BASEBOARD_FAB2(SCH_1):PAGE222_I31@MSTR_DISCRETE.RES(CHIPS)':
 C_PATH='@baseboard_fab2_lib.baseboard_fab2(sch_1):page222_i31@mstr_discrete.res~
(chips)',
 P_PATH='@baseboard_fab2_lib.baseboard_fab2(sch_1):page222_i31@mstr_discrete.res~
(chips)',
 PATH='I31',
 DRAWING='@BASEBOARD_FAB2_LIB.BASEBOARD_FAB2(SCH_1):PAGE222',
 WATTAGE='1/16W',
 TOLERANCE='1%',
 SEC_TYPE='0402',
 MATERIAL='CHIP',
 PHYS_PAGE='222',
 XY='(3475,1375)',
 ROT='0',
 VER='1',
 VALUE='33.2',
 PACK_TYPE='0402',
 PART_NUMBER='G21796-074',
 LOCATION='R4A6',
 SEC='1',
 CDS_LIB='mstr_discrete',
 CDS_PART_NAME='RES_0402-33.2,1%,1/16W,CHIP,G2A',
 PRIM_FILE='./archive_libs/mstr_discrete/res/chips/chips.prt';

PART_NAME
 R4A7 'RES_0402-2.2,5%,1/16W,EMPTY,G2A':
 ROOM='PVPP_KLM_VR',
 REUSE_ID='29';

SECTION_NUMBER 1
 '@BASEBOARD_FAB2_LIB.BASEBOARD_FAB2(SCH_1):PAGE234_I162@MSTR_DISCRETE.RES(CHIPS)':
 C_PATH='@baseboard_fab2_lib.baseboard_fab2(sch_1):page234_i162@mstr_discrete.re~
s(chips)',
 P_PATH='@baseboard_fab2_lib.baseboard_fab2(sch_1):page234_i162@mstr_discrete.re~
s(chips)',
 PATH='I162',
 DRAWING='@BASEBOARD_FAB2_LIB.BASEBOARD_FAB2(SCH_1):PAGE234',
 WATTAGE='1/16W',
 TOLERANCE='5%',
 MATERIAL='EMPTY',
 BOM_COST='PVPP_KLM_VR',
 PHYS_PAGE='234',
 REUSE_ID='29',
 XY='(-2575,3275)',
 ROT='0',
 VER='2',
 VALUE='2.2',
 PACK_TYPE='0402',
 PART_NUMBER='G21497-016',
 LOCATION='R4A7',
 ROOM='PVPP_KLM_VR',
 CDS_LIB='mstr_discrete',
 CDS_PART_NAME='RES_0402-2.2,5%,1/16W,EMPTY,G2A',
 PRIM_FILE='./archive_libs/mstr_discrete/res/chips/chips.prt';

PART_NAME
 R4A8 'RES_0402-0.0,5%,1/16W,CHIP,G21A':
 ROOM='CPU0';

SECTION_NUMBER 1
 '@BASEBOARD_FAB2_LIB.BASEBOARD_FAB2(SCH_1):PAGE156_I322@MSTR_DISCRETE.RES(CHIPS)':
 C_PATH='@baseboard_fab2_lib.baseboard_fab2(sch_1):page156_i322@mstr_discrete.re~
s(chips)',
 P_PATH='@baseboard_fab2_lib.baseboard_fab2(sch_1):page156_i322@mstr_discrete.re~
s(chips)',
 PATH='I322',
 DRAWING='@BASEBOARD_FAB2_LIB.BASEBOARD_FAB2(SCH_1):PAGE156',
 WATTAGE='1/16W',
 TOLERANCE='5%',
 SEC_TYPE='0402',
 MATERIAL='CHIP',
 PHYS_PAGE='156',
 XY='(-6425,700)',
 ROT='0',
 VER='1',
 VALUE='0.0',
 PACK_TYPE='0402',
 PART_NUMBER='G21497-005',
 LOCATION='R4A8',
 ROOM='CPU0',
 SEC='1',
 CDS_LIB='mstr_discrete',
 CDS_PART_NAME='RES_0402-0.0,5%,1/16W,CHIP,G21A',
 PRIM_FILE='./archive_libs/mstr_discrete/res/chips/chips.prt';

PART_NAME
 R4A9 'RES_0402-0.0,5%,1/16W,CHIP,G21A':
 ROOM='CPU0';

SECTION_NUMBER 1
 '@BASEBOARD_FAB2_LIB.BASEBOARD_FAB2(SCH_1):PAGE156_I324@MSTR_DISCRETE.RES(CHIPS)':
 C_PATH='@baseboard_fab2_lib.baseboard_fab2(sch_1):page156_i324@mstr_discrete.re~
s(chips)',
 P_PATH='@baseboard_fab2_lib.baseboard_fab2(sch_1):page156_i324@mstr_discrete.re~
s(chips)',
 PATH='I324',
 DRAWING='@BASEBOARD_FAB2_LIB.BASEBOARD_FAB2(SCH_1):PAGE156',
 WATTAGE='1/16W',
 TOLERANCE='5%',
 SEC_TYPE='0402',
 MATERIAL='CHIP',
 PHYS_PAGE='156',
 XY='(-6425,400)',
 ROT='0',
 VER='1',
 VALUE='0.0',
 PACK_TYPE='0402',
 PART_NUMBER='G21497-005',
 LOCATION='R4A9',
 ROOM='CPU0',
 SEC='1',
 CDS_LIB='mstr_discrete',
 CDS_PART_NAME='RES_0402-0.0,5%,1/16W,CHIP,G21A',
 PRIM_FILE='./archive_libs/mstr_discrete/res/chips/chips.prt';

PART_NAME
 R4B1 'RES_0402-0.0,5%,1/16W,CHIP,G21A':
 ROOM='PVCCIN_CPU0_VR';

SECTION_NUMBER 1
 '@BASEBOARD_FAB2_LIB.BASEBOARD_FAB2(SCH_1):PAGE234_I220@MSTR_DISCRETE.RES(CHIPS)':
 C_PATH='@baseboard_fab2_lib.baseboard_fab2(sch_1):page234_i220@mstr_discrete.re~
s(chips)',
 P_PATH='@baseboard_fab2_lib.baseboard_fab2(sch_1):page234_i220@mstr_discrete.re~
s(chips)',
 PATH='I220',
 DRAWING='@BASEBOARD_FAB2_LIB.BASEBOARD_FAB2(SCH_1):PAGE234',
 WATTAGE='1/16W',
 TOLERANCE='5%',
 SEC_TYPE='0402',
 MATERIAL='CHIP',
 PHYS_PAGE='234',
 XY='(-5925,2825)',
 ROT='0',
 VER='1',
 VALUE='0.0',
 PACK_TYPE='0402',
 PART_NUMBER='G21497-005',
 LOCATION='R4B1',
 ROOM='PVCCIN_CPU0_VR',
 SEC='1',
 CDS_LIB='mstr_discrete',
 CDS_PART_NAME='RES_0402-0.0,5%,1/16W,CHIP,G21A',
 PRIM_FILE='./archive_libs/mstr_discrete/res/chips/chips.prt';

PART_NAME
 R4B2 'RES_0603-120.0,1%,1/10W,CHIP,GA':
 ROOM='PVPP_KLM_VR',
 REUSE_ID='34';

SECTION_NUMBER 1
 '@BASEBOARD_FAB2_LIB.BASEBOARD_FAB2(SCH_1):PAGE234_I183@MSTR_DISCRETE.RES(CHIPS)':
 C_PATH='@baseboard_fab2_lib.baseboard_fab2(sch_1):page234_i183@mstr_discrete.re~
s(chips)',
 P_PATH='@baseboard_fab2_lib.baseboard_fab2(sch_1):page234_i183@mstr_discrete.re~
s(chips)',
 PATH='I183',
 DRAWING='@BASEBOARD_FAB2_LIB.BASEBOARD_FAB2(SCH_1):PAGE234',
 WATTAGE='1/10W',
 TOLERANCE='1%',
 MATERIAL='CHIP',
 BOM_COST='PVPP_KLM_VR',
 PHYS_PAGE='234',
 REUSE_ID='34',
 XY='(-2050,3650)',
 ROT='0',
 VER='2',
 VALUE='120.0',
 PACK_TYPE='0603',
 PART_NUMBER='G22026-003',
 LOCATION='R4B2',
 ROOM='PVPP_KLM_VR',
 CDS_LIB='mstr_discrete',
 CDS_PART_NAME='RES_0603-120.0,1%,1/10W,CHIP,GA',
 PRIM_FILE='./archive_libs/mstr_discrete/res/chips/chips.prt';

PART_NAME
 R4B3 'RES_0402-0.0,5%,1/16W,CHIP,G21A':
 ROOM='PVPP_KLM_VR';

SECTION_NUMBER 1
 '@BASEBOARD_FAB2_LIB.BASEBOARD_FAB2(SCH_1):PAGE234_I214@MSTR_DISCRETE.RES(CHIPS)':
 C_PATH='@baseboard_fab2_lib.baseboard_fab2(sch_1):page234_i214@mstr_discrete.re~
s(chips)',
 P_PATH='@baseboard_fab2_lib.baseboard_fab2(sch_1):page234_i214@mstr_discrete.re~
s(chips)',
 PATH='I214',
 DRAWING='@BASEBOARD_FAB2_LIB.BASEBOARD_FAB2(SCH_1):PAGE234',
 SPOF='TRUE',
 WATTAGE='1/16W',
 TOLERANCE='5%',
 SEC_TYPE='0402',
 MATERIAL='CHIP',
 PHYS_PAGE='234',
 XY='(-1350,3050)',
 ROT='5',
 VER='1',
 VALUE='0.0',
 PACK_TYPE='0402',
 PART_NUMBER='G21497-005',
 LOCATION='R4B3',
 ROOM='PVPP_KLM_VR',
 SEC='1',
 CDS_LIB='mstr_discrete',
 CDS_PART_NAME='RES_0402-0.0,5%,1/16W,CHIP,G21A',
 PRIM_FILE='./archive_libs/mstr_discrete/res/chips/chips.prt';

PART_NAME
 R4B4 'RES_0402-6.19K,1%,1/16W,CHIP,GA':
 ROOM='IO_SLOT';

SECTION_NUMBER 1
 '@BASEBOARD_FAB2_LIB.BASEBOARD_FAB2(SCH_1):PAGE234_I227@MSTR_DISCRETE.RES(CHIPS)':
 C_PATH='@baseboard_fab2_lib.baseboard_fab2(sch_1):page234_i227@mstr_discrete.re~
s(chips)',
 P_PATH='@baseboard_fab2_lib.baseboard_fab2(sch_1):page234_i227@mstr_discrete.re~
s(chips)',
 PATH='I227',
 DRAWING='@BASEBOARD_FAB2_LIB.BASEBOARD_FAB2(SCH_1):PAGE234',
 WATTAGE='1/16W',
 TOLERANCE='1%',
 SEC_TYPE='0402',
 MATERIAL='CHIP',
 BOM_COST='IO_SLOT',
 PHYS_PAGE='234',
 XY='(-1350,1450)',
 ROT='0',
 VER='2',
 VALUE='6.19K',
 PACK_TYPE='0402',
 PART_NUMBER='G21796-161',
 LOCATION='R4B4',
 ROOM='IO_SLOT',
 SEC='1',
 CDS_LIB='mstr_discrete',
 CDS_PART_NAME='RES_0402-6.19K,1%,1/16W,CHIP,GA',
 PRIM_FILE='./archive_libs/mstr_discrete/res/chips/chips.prt';

PART_NAME
 R4B5 'RES_0402-20.0K,1%,1/16W,CHIP,GA':
 ROOM='PVPP_KLM_VR',
 REUSE_ID='9';

SECTION_NUMBER 1
 '@BASEBOARD_FAB2_LIB.BASEBOARD_FAB2(SCH_1):PAGE234_I215@MSTR_DISCRETE.RES(CHIPS)':
 C_PATH='@baseboard_fab2_lib.baseboard_fab2(sch_1):page234_i215@mstr_discrete.re~
s(chips)',
 P_PATH='@baseboard_fab2_lib.baseboard_fab2(sch_1):page234_i215@mstr_discrete.re~
s(chips)',
 PATH='I215',
 DRAWING='@BASEBOARD_FAB2_LIB.BASEBOARD_FAB2(SCH_1):PAGE234',
 SPOF='TRUE',
 WATTAGE='1/16W',
 TOLERANCE='1%',
 MATERIAL='CHIP',
 BOM_COST='PVPP_KLM_VR',
 PHYS_PAGE='234',
 REUSE_ID='9',
 XY='(-1350,2175)',
 ROT='0',
 VER='2',
 VALUE='20.0K',
 PACK_TYPE='0402',
 PART_NUMBER='G21796-040',
 LOCATION='R4B5',
 ROOM='PVPP_KLM_VR',
 CDS_LIB='mstr_discrete',
 CDS_PART_NAME='RES_0402-20.0K,1%,1/16W,CHIP,GA',
 PRIM_FILE='./archive_libs/mstr_discrete/res/chips/chips.prt';

PART_NAME
 R4B6 'RES_0402-7.87K,1.0%,1/16W,CHIPA':
 ROOM='PVPP_KLM_VR';

SECTION_NUMBER 1
 '@BASEBOARD_FAB2_LIB.BASEBOARD_FAB2(SCH_1):PAGE234_I228@MSTR_DISCRETE.RES(CHIPS)':
 C_PATH='@baseboard_fab2_lib.baseboard_fab2(sch_1):page234_i228@mstr_discrete.re~
s(chips)',
 P_PATH='@baseboard_fab2_lib.baseboard_fab2(sch_1):page234_i228@mstr_discrete.re~
s(chips)',
 PATH='I228',
 DRAWING='@BASEBOARD_FAB2_LIB.BASEBOARD_FAB2(SCH_1):PAGE234',
 NEW_VALUE='3.9K',
 CONFIG='64.39015.6DL',
 WATTAGE='1/16W',
 TOLERANCE='1.0%',
 MATERIAL='CHIP',
 BOM_COST='PVPP_KLM_VR',
 PHYS_PAGE='234',
 XY='(-4750,1650)',
 ROT='2',
 VER='2',
 VALUE='7.87K',
 PACK_TYPE='0402',
 PART_NUMBER='G21796-242',
 LOCATION='R4B6',
 ROOM='PVPP_KLM_VR',
 CDS_LIB='mstr_discrete',
 CDS_PART_NAME='RES_0402-7.87K,1.0%,1/16W,CHIPA',
 PRIM_FILE='./archive_libs/mstr_discrete/res/chips/chips.prt';

PART_NAME
 R4B7 'RES_0402-22.1,1.0%,1/16W,CHIP,A':
 ROOM='PVPP_KLM_VR';

SECTION_NUMBER 1
 '@BASEBOARD_FAB2_LIB.BASEBOARD_FAB2(SCH_1):PAGE234_I201@MSTR_DISCRETE.RES(CHIPS)':
 C_PATH='@baseboard_fab2_lib.baseboard_fab2(sch_1):page234_i201@mstr_discrete.re~
s(chips)',
 P_PATH='@baseboard_fab2_lib.baseboard_fab2(sch_1):page234_i201@mstr_discrete.re~
s(chips)',
 PATH='I201',
 DRAWING='@BASEBOARD_FAB2_LIB.BASEBOARD_FAB2(SCH_1):PAGE234',
 WATTAGE='1/16W',
 TOLERANCE='1.0%',
 SEC_TYPE='0402',
 MATERIAL='CHIP',
 PHYS_PAGE='234',
 XY='(-3350,975)',
 ROT='0',
 VER='1',
 VALUE='22.1',
 PACK_TYPE='0402',
 PART_NUMBER='G21796-250',
 LOCATION='R4B7',
 ROOM='PVPP_KLM_VR',
 SEC='1',
 CDS_LIB='mstr_discrete',
 CDS_PART_NAME='RES_0402-22.1,1.0%,1/16W,CHIP,A',
 PRIM_FILE='./archive_libs/mstr_discrete/res/chips/chips.prt';

PART_NAME
 R4B8 'RES_0402-7.87K,1.0%,1/16W,CHIPA':
 ROOM='PVPP_KLM_VR',
 REUSE_ID='13';

SECTION_NUMBER 1
 '@BASEBOARD_FAB2_LIB.BASEBOARD_FAB2(SCH_1):PAGE234_I213@MSTR_DISCRETE.RES(CHIPS)':
 C_PATH='@baseboard_fab2_lib.baseboard_fab2(sch_1):page234_i213@mstr_discrete.re~
s(chips)',
 P_PATH='@baseboard_fab2_lib.baseboard_fab2(sch_1):page234_i213@mstr_discrete.re~
s(chips)',
 PATH='I213',
 DRAWING='@BASEBOARD_FAB2_LIB.BASEBOARD_FAB2(SCH_1):PAGE234',
 WATTAGE='1/16W',
 TOLERANCE='1.0%',
 SEC_TYPE='0402',
 MATERIAL='CHIP',
 BOM_COST='PVPP_KLM_VR',
 PHYS_PAGE='234',
 REUSE_ID='13',
 XY='(-2150,2450)',
 ROT='0',
 VER='1',
 VALUE='7.87K',
 PACK_TYPE='0402',
 PART_NUMBER='G21796-242',
 LOCATION='R4B8',
 ROOM='PVPP_KLM_VR',
 SEC='1',
 CDS_LIB='mstr_discrete',
 CDS_PART_NAME='RES_0402-7.87K,1.0%,1/16W,CHIPA',
 PRIM_FILE='./archive_libs/mstr_discrete/res/chips/chips.prt';

PART_NAME
 R4B9 'RES_0402-1.0K,0.1%,1/16W,CHIP,A':
 ROOM='PVPP_KLM_VR',
 REUSE_ID='9';

SECTION_NUMBER 1
 '@BASEBOARD_FAB2_LIB.BASEBOARD_FAB2(SCH_1):PAGE234_I219@MSTR_DISCRETE.RES(CHIPS)':
 C_PATH='@baseboard_fab2_lib.baseboard_fab2(sch_1):page234_i219@mstr_discrete.re~
s(chips)',
 P_PATH='@baseboard_fab2_lib.baseboard_fab2(sch_1):page234_i219@mstr_discrete.re~
s(chips)',
 PATH='I219',
 DRAWING='@BASEBOARD_FAB2_LIB.BASEBOARD_FAB2(SCH_1):PAGE234',
 SPOF='TRUE',
 WATTAGE='1/16W',
 TOLERANCE='0.1%',
 SEC_TYPE='0402',
 MATERIAL='CHIP',
 BOM_COST='PVPP_KLM_VR',
 PHYS_PAGE='234',
 REUSE_ID='9',
 XY='(-1025,2750)',
 ROT='0',
 VER='2',
 VALUE='1.0K',
 PACK_TYPE='0402',
 PART_NUMBER='G85996-004',
 LOCATION='R4B9',
 ROOM='PVPP_KLM_VR',
 SEC='1',
 CDS_LIB='mstr_discrete',
 CDS_PART_NAME='RES_0402-1.0K,0.1%,1/16W,CHIP,A',
 PRIM_FILE='./archive_libs/mstr_discrete/res/chips/chips.prt';

PART_NAME
 R4B10 'RES_0402-1.00K,1%,1/16W,CHIP,GA':
 ROOM='PVPP_KLM_VR',
 REUSE_ID='21';

SECTION_NUMBER 1
 '@BASEBOARD_FAB2_LIB.BASEBOARD_FAB2(SCH_1):PAGE234_I143@MSTR_DISCRETE.RES(CHIPS)':
 C_PATH='@baseboard_fab2_lib.baseboard_fab2(sch_1):page234_i143@mstr_discrete.re~
s(chips)',
 P_PATH='@baseboard_fab2_lib.baseboard_fab2(sch_1):page234_i143@mstr_discrete.re~
s(chips)',
 PATH='I143',
 DRAWING='@BASEBOARD_FAB2_LIB.BASEBOARD_FAB2(SCH_1):PAGE234',
 WATTAGE='1/16W',
 TOLERANCE='1%',
 SEC_TYPE='0402',
 MATERIAL='CHIP',
 BOM_COST='PVPP_KLM_VR',
 PHYS_PAGE='234',
 REUSE_ID='21',
 XY='(-4225,1250)',
 ROT='0',
 VER='2',
 VALUE='1.00K',
 PACK_TYPE='0402',
 PART_NUMBER='G21796-026',
 LOCATION='R4B10',
 ROOM='PVPP_KLM_VR',
 SEC='1',
 CDS_LIB='mstr_discrete',
 CDS_PART_NAME='RES_0402-1.00K,1%,1/16W,CHIP,GA',
 PRIM_FILE='./archive_libs/mstr_discrete/res/chips/chips.prt';

PART_NAME
 R4B12 'RES_1206-0.002,1%,1W,CHIP,G521A':
 ROOM='PVDDQ_ABC_PWR_VR';

SECTION_NUMBER 1
 '@BASEBOARD_FAB2_LIB.BASEBOARD_FAB2(SCH_1):PAGE197_I6@MSTR_DISCRETE.RES(CHIPS)':
 C_PATH='@baseboard_fab2_lib.baseboard_fab2(sch_1):page197_i6@mstr_discrete.res(~
chips)',
 P_PATH='@baseboard_fab2_lib.baseboard_fab2(sch_1):page197_i6@mstr_discrete.res(~
chips)',
 PATH='I6',
 DRAWING='@BASEBOARD_FAB2_LIB.BASEBOARD_FAB2(SCH_1):PAGE197',
 NEW_VALUE='0.004 OHM',
 CONFIG='064.R0045.0711',
 WATTAGE='1W',
 TOLERANCE='1%',
 SEC_TYPE='1206',
 MATERIAL='CHIP',
 BOM_COST='PVDDQ_ABC_VR',
 PHYS_PAGE='197',
 XY='(-4275,2700)',
 ROT='0',
 VER='1',
 VALUE='0.002',
 PACK_TYPE='1206',
 PART_NUMBER='G52199-004',
 LOCATION='R4B12',
 ROOM='PVDDQ_ABC_PWR_VR',
 SEC='1',
 CDS_LIB='mstr_discrete',
 CDS_PART_NAME='RES_1206-0.002,1%,1W,CHIP,G521A',
 PRIM_FILE='./archive_libs/mstr_discrete/res/chips/chips.prt';

PART_NAME
 R4B13 'RES_0603-0,5.0%,1/10W,CHIP,G22A':
 ROOM='NIC_SPRV';

SECTION_NUMBER 1
 '@BASEBOARD_FAB2_LIB.BASEBOARD_FAB2(SCH_1):PAGE234_I226@MSTR_DISCRETE.RES(CHIPS)':
 C_PATH='@baseboard_fab2_lib.baseboard_fab2(sch_1):page234_i226@mstr_discrete.re~
s(chips)',
 P_PATH='@baseboard_fab2_lib.baseboard_fab2(sch_1):page234_i226@mstr_discrete.re~
s(chips)',
 PATH='I226',
 DRAWING='@BASEBOARD_FAB2_LIB.BASEBOARD_FAB2(SCH_1):PAGE234',
 WATTAGE='1/10W',
 TOLERANCE='5.0%',
 SEC_TYPE='0603',
 MATERIAL='CHIP',
 BOM_COST='NT_GBE_BASE',
 PHYS_PAGE='234',
 XY='(-4150,4200)',
 ROT='0',
 VER='1',
 VALUE='0',
 PACK_TYPE='0603',
 PART_NUMBER='G22178-002',
 LOCATION='R4B13',
 ROOM='NIC_SPRV',
 SEC='1',
 CDS_LIB='mstr_discrete',
 CDS_PART_NAME='RES_0603-0,5.0%,1/10W,CHIP,G22A',
 PRIM_FILE='./archive_libs/mstr_discrete/res/chips/chips.prt';

PART_NAME
 R4B14 'RES_0402-0.0,5%,1/16W,CHIP,G21A':
 ROOM='PVPP_KLM_VR';

SECTION_NUMBER 1
 '@BASEBOARD_FAB2_LIB.BASEBOARD_FAB2(SCH_1):PAGE234_I29@MSTR_DISCRETE.RES(CHIPS)':
 C_PATH='@baseboard_fab2_lib.baseboard_fab2(sch_1):page234_i29@mstr_discrete.res~
(chips)',
 P_PATH='@baseboard_fab2_lib.baseboard_fab2(sch_1):page234_i29@mstr_discrete.res~
(chips)',
 PATH='I29',
 DRAWING='@BASEBOARD_FAB2_LIB.BASEBOARD_FAB2(SCH_1):PAGE234',
 WATTAGE='1/16W',
 TOLERANCE='5%',
 MATERIAL='CHIP',
 PHYS_PAGE='234',
 XY='(-1150,650)',
 ROT='0',
 VER='1',
 VALUE='0.0',
 PACK_TYPE='0402',
 PART_NUMBER='G21497-005',
 LOCATION='R4B14',
 ROOM='PVPP_KLM_VR',
 CDS_LIB='mstr_discrete',
 CDS_PART_NAME='RES_0402-0.0,5%,1/16W,CHIP,G21A',
 PRIM_FILE='./archive_libs/mstr_discrete/res/chips/chips.prt';

PART_NAME
 R4C1 'RES_0402-100.0,1%,1/16W,CHIP,GA':
 ROOM='PVSA_CPU0_VSENSE_VR';

SECTION_NUMBER 1
 '@BASEBOARD_FAB2_LIB.BASEBOARD_FAB2(SCH_1):PAGE205_I29@MSTR_DISCRETE.RES(CHIPS)':
 C_PATH='@baseboard_fab2_lib.baseboard_fab2(sch_1):page205_i29@mstr_discrete.res~
(chips)',
 P_PATH='@baseboard_fab2_lib.baseboard_fab2(sch_1):page205_i29@mstr_discrete.res~
(chips)',
 PATH='I29',
 DRAWING='@BASEBOARD_FAB2_LIB.BASEBOARD_FAB2(SCH_1):PAGE205',
 WATTAGE='1/16W',
 TOLERANCE='1%',
 SEC_TYPE='0402',
 MATERIAL='CHIP',
 BOM_COST='PROC_VRD_VCCIN_CPU0',
 PHYS_PAGE='205',
 XY='(-5075,1200)',
 ROT='0',
 VER='1',
 VALUE='100.0',
 PACK_TYPE='0402',
 PART_NUMBER='G21796-017',
 LOCATION='R4C1',
 ROOM='PVSA_CPU0_VSENSE_VR',
 SEC='1',
 CDS_LIB='mstr_discrete',
 CDS_PART_NAME='RES_0402-100.0,1%,1/16W,CHIP,GA',
 PRIM_FILE='./archive_libs/mstr_discrete/res/chips/chips.prt';

PART_NAME
 R4C2 'RES_0402-0.0,5%,1/16W,CHIP,G21A':
 ROOM='PVSA_CPU0_VSENSE_VR';

SECTION_NUMBER 1
 '@BASEBOARD_FAB2_LIB.BASEBOARD_FAB2(SCH_1):PAGE205_I30@MSTR_DISCRETE.RES(CHIPS)':
 C_PATH='@baseboard_fab2_lib.baseboard_fab2(sch_1):page205_i30@mstr_discrete.res~
(chips)',
 P_PATH='@baseboard_fab2_lib.baseboard_fab2(sch_1):page205_i30@mstr_discrete.res~
(chips)',
 PATH='I30',
 DRAWING='@BASEBOARD_FAB2_LIB.BASEBOARD_FAB2(SCH_1):PAGE205',
 WATTAGE='1/16W',
 TOLERANCE='5%',
 SEC_TYPE='0402',
 MATERIAL='CHIP',
 BOM_COST='PROC_VRD_VCCIN_CPU0',
 PHYS_PAGE='205',
 XY='(-5075,1575)',
 ROT='0',
 VER='1',
 VALUE='0.0',
 PACK_TYPE='0402',
 PART_NUMBER='G21497-005',
 LOCATION='R4C2',
 ROOM='PVSA_CPU0_VSENSE_VR',
 SEC='1',
 CDS_LIB='mstr_discrete',
 CDS_PART_NAME='RES_0402-0.0,5%,1/16W,CHIP,G21A',
 PRIM_FILE='./archive_libs/mstr_discrete/res/chips/chips.prt';

PART_NAME
 R4C3 'RES_0402-1.00K,1%,1/16W,EMPTY,A':
 ROOM='PVSA_CPU0_VSENSE_VR',
 NO_XNET_CONNECTION='1';

SECTION_NUMBER 1
 '@BASEBOARD_FAB2_LIB.BASEBOARD_FAB2(SCH_1):PAGE205_I37@MSTR_DISCRETE.RES(CHIPS)':
 C_PATH='@baseboard_fab2_lib.baseboard_fab2(sch_1):page205_i37@mstr_discrete.res~
(chips)',
 P_PATH='@baseboard_fab2_lib.baseboard_fab2(sch_1):page205_i37@mstr_discrete.res~
(chips)',
 PATH='I37',
 DRAWING='@BASEBOARD_FAB2_LIB.BASEBOARD_FAB2(SCH_1):PAGE205',
 WATTAGE='1/16W',
 TOLERANCE='1%',
 SEC_TYPE='0402',
 MATERIAL='EMPTY',
 BOM_COST='PROC_VRD_VCCIN_CPU0',
 NO_XNET_CONNECTION='1',
 PHYS_PAGE='205',
 XY='(-5750,1825)',
 ROT='0',
 VER='2',
 VALUE='1.00K',
 PACK_TYPE='0402',
 PART_NUMBER='G21796-026',
 LOCATION='R4C3',
 ROOM='PVSA_CPU0_VSENSE_VR',
 SEC='1',
 CDS_LIB='mstr_discrete',
 CDS_PART_NAME='RES_0402-1.00K,1%,1/16W,EMPTY,A',
 PRIM_FILE='./archive_libs/mstr_discrete/res/chips/chips.prt';

PART_NAME
 R4C4 'RES_0402-0.0,5%,1/16W,CHIP,G21A':
 ROOM='PVSA_CPU0_VSENSE_VR';

SECTION_NUMBER 1
 '@BASEBOARD_FAB2_LIB.BASEBOARD_FAB2(SCH_1):PAGE205_I26@MSTR_DISCRETE.RES(CHIPS)':
 C_PATH='@baseboard_fab2_lib.baseboard_fab2(sch_1):page205_i26@mstr_discrete.res~
(chips)',
 P_PATH='@baseboard_fab2_lib.baseboard_fab2(sch_1):page205_i26@mstr_discrete.res~
(chips)',
 PATH='I26',
 DRAWING='@BASEBOARD_FAB2_LIB.BASEBOARD_FAB2(SCH_1):PAGE205',
 WATTAGE='1/16W',
 TOLERANCE='5%',
 SEC_TYPE='0402',
 MATERIAL='CHIP',
 BOM_COST='PROC_VRD_VCCIN_CPU0',
 PHYS_PAGE='205',
 XY='(-5075,2025)',
 ROT='0',
 VER='1',
 VALUE='0.0',
 PACK_TYPE='0402',
 PART_NUMBER='G21497-005',
 LOCATION='R4C4',
 ROOM='PVSA_CPU0_VSENSE_VR',
 SEC='1',
 CDS_LIB='mstr_discrete',
 CDS_PART_NAME='RES_0402-0.0,5%,1/16W,CHIP,G21A',
 PRIM_FILE='./archive_libs/mstr_discrete/res/chips/chips.prt';

PART_NAME
 R4C5 'RES_0402-100.0,1%,1/16W,CHIP,GA':
 ROOM='PVSA_CPU0_VSENSE_VR';

SECTION_NUMBER 1
 '@BASEBOARD_FAB2_LIB.BASEBOARD_FAB2(SCH_1):PAGE205_I24@MSTR_DISCRETE.RES(CHIPS)':
 C_PATH='@baseboard_fab2_lib.baseboard_fab2(sch_1):page205_i24@mstr_discrete.res~
(chips)',
 P_PATH='@baseboard_fab2_lib.baseboard_fab2(sch_1):page205_i24@mstr_discrete.res~
(chips)',
 PATH='I24',
 DRAWING='@BASEBOARD_FAB2_LIB.BASEBOARD_FAB2(SCH_1):PAGE205',
 WATTAGE='1/16W',
 TOLERANCE='1%',
 SEC_TYPE='0402',
 MATERIAL='CHIP',
 BOM_COST='PROC_VRD_VCCIN_CPU0',
 PHYS_PAGE='205',
 XY='(-5100,2425)',
 ROT='0',
 VER='1',
 VALUE='100.0',
 PACK_TYPE='0402',
 PART_NUMBER='G21796-017',
 LOCATION='R4C5',
 ROOM='PVSA_CPU0_VSENSE_VR',
 SEC='1',
 CDS_LIB='mstr_discrete',
 CDS_PART_NAME='RES_0402-100.0,1%,1/16W,CHIP,GA',
 PRIM_FILE='./archive_libs/mstr_discrete/res/chips/chips.prt';

PART_NAME
 R4C8 'RES_0402-1.00K,1%,1/16W,CHIP,GA':
 ROOM='PROC_RSTS_PGOODS';

SECTION_NUMBER 1
 '@BASEBOARD_FAB2_LIB.BASEBOARD_FAB2(SCH_1):PAGE96_I55@MSTR_DISCRETE.RES(CHIPS)':
 C_PATH='@baseboard_fab2_lib.baseboard_fab2(sch_1):page96_i55@mstr_discrete.res(~
chips)',
 P_PATH='@baseboard_fab2_lib.baseboard_fab2(sch_1):page96_i55@mstr_discrete.res(~
chips)',
 PATH='I55',
 DRAWING='@BASEBOARD_FAB2_LIB.BASEBOARD_FAB2(SCH_1):PAGE96',
 WATTAGE='1/16W',
 TOLERANCE='1%',
 MATERIAL='CHIP',
 BOM_COST='PROC_SIDEBAND',
 PHYS_PAGE='96',
 XY='(-2100,2350)',
 ROT='0',
 VER='2',
 VALUE='1.00K',
 PACK_TYPE='0402',
 PART_NUMBER='G21796-026',
 LOCATION='R4C8',
 ROOM='PROC_RSTS_PGOODS',
 CDS_LIB='mstr_discrete',
 CDS_PART_NAME='RES_0402-1.00K,1%,1/16W,CHIP,GA',
 PRIM_FILE='./archive_libs/mstr_discrete/res/chips/chips.prt';

PART_NAME
 R4C9 'RES_0402-1.00K,1%,1/16W,CHIP,GA':
 ROOM='PROC_RSTS_PGOODS';

SECTION_NUMBER 1
 '@BASEBOARD_FAB2_LIB.BASEBOARD_FAB2(SCH_1):PAGE96_I69@MSTR_DISCRETE.RES(CHIPS)':
 C_PATH='@baseboard_fab2_lib.baseboard_fab2(sch_1):page96_i69@mstr_discrete.res(~
chips)',
 P_PATH='@baseboard_fab2_lib.baseboard_fab2(sch_1):page96_i69@mstr_discrete.res(~
chips)',
 PATH='I69',
 DRAWING='@BASEBOARD_FAB2_LIB.BASEBOARD_FAB2(SCH_1):PAGE96',
 WATTAGE='1/16W',
 TOLERANCE='1%',
 SEC_TYPE='0402',
 MATERIAL='CHIP',
 BOM_COST='PROC_SIDEBAND',
 PHYS_PAGE='96',
 XY='(-2400,2050)',
 ROT='0',
 VER='1',
 VALUE='1.00K',
 PACK_TYPE='0402',
 PART_NUMBER='G21796-026',
 LOCATION='R4C9',
 ROOM='PROC_RSTS_PGOODS',
 SEC='1',
 CDS_LIB='mstr_discrete',
 CDS_PART_NAME='RES_0402-1.00K,1%,1/16W,CHIP,GA',
 PRIM_FILE='./archive_libs/mstr_discrete/res/chips/chips.prt';

PART_NAME
 R4C10 'RES_0402-240,1.0%,1/16W,CHIP,GA':
 ROOM='PROC_SIDEBAND';

SECTION_NUMBER 1
 '@BASEBOARD_FAB2_LIB.BASEBOARD_FAB2(SCH_1):PAGE97_I76@MSTR_DISCRETE.RES(CHIPS)':
 C_PATH='@baseboard_fab2_lib.baseboard_fab2(sch_1):page97_i76@mstr_discrete.res(~
chips)',
 P_PATH='@baseboard_fab2_lib.baseboard_fab2(sch_1):page97_i76@mstr_discrete.res(~
chips)',
 PATH='I76',
 DRAWING='@BASEBOARD_FAB2_LIB.BASEBOARD_FAB2(SCH_1):PAGE97',
 WATTAGE='1/16W',
 TOLERANCE='1.0%',
 SEC_TYPE='0402',
 MATERIAL='CHIP',
 BOM_COST='PROC_SIDEBAND',
 PHYS_PAGE='97',
 XY='(-2600,800)',
 ROT='0',
 VER='1',
 VALUE='240',
 PACK_TYPE='0402',
 PART_NUMBER='G21796-294',
 LOCATION='R4C10',
 ROOM='PROC_SIDEBAND',
 SEC='1',
 CDS_LIB='mstr_discrete',
 CDS_PART_NAME='RES_0402-240,1.0%,1/16W,CHIP,GA',
 PRIM_FILE='./archive_libs/mstr_discrete/res/chips/chips.prt';

PART_NAME
 R4C11 'RES_0402-3.16K,1%,1/16W,CHIP,GA':
 GROUP='MCP',
 ROOM='PVCCIN_CPU0_VR';

SECTION_NUMBER 1
 '@BASEBOARD_FAB2_LIB.BASEBOARD_FAB2(SCH_1):PAGE193_I170@MSTR_DISCRETE.RES(CHIPS)':
 C_PATH='@baseboard_fab2_lib.baseboard_fab2(sch_1):page193_i170@mstr_discrete.re~
s(chips)',
 P_PATH='@baseboard_fab2_lib.baseboard_fab2(sch_1):page193_i170@mstr_discrete.re~
s(chips)',
 PATH='I170',
 DRAWING='@BASEBOARD_FAB2_LIB.BASEBOARD_FAB2(SCH_1):PAGE193',
 WATTAGE='1/16W',
 TOLERANCE='1%',
 SEC_TYPE='0402',
 MATERIAL='CHIP',
 PHYS_PAGE='193',
 XY='(-7600,750)',
 ROT='0',
 VER='2',
 VALUE='3.16K',
 PACK_TYPE='0402',
 PART_NUMBER='G21796-043',
 LOCATION='R4C11',
 ROOM='PVCCIN_CPU0_VR',
 GROUP='MCP',
 SEC='1',
 CDS_LIB='mstr_discrete',
 CDS_PART_NAME='RES_0402-3.16K,1%,1/16W,CHIP,GA',
 PRIM_FILE='./archive_libs/mstr_discrete/res/chips/chips.prt';

PART_NAME
 R4C12 'RES_0402-8.06K,1%,1/16W,CHIP,GA':
 GROUP='MCP',
 ROOM='PVCCIN_CPU0_VR';

SECTION_NUMBER 1
 '@BASEBOARD_FAB2_LIB.BASEBOARD_FAB2(SCH_1):PAGE193_I169@MSTR_DISCRETE.RES(CHIPS)':
 C_PATH='@baseboard_fab2_lib.baseboard_fab2(sch_1):page193_i169@mstr_discrete.re~
s(chips)',
 P_PATH='@baseboard_fab2_lib.baseboard_fab2(sch_1):page193_i169@mstr_discrete.re~
s(chips)',
 PATH='I169',
 DRAWING='@BASEBOARD_FAB2_LIB.BASEBOARD_FAB2(SCH_1):PAGE193',
 WATTAGE='1/16W',
 TOLERANCE='1%',
 SEC_TYPE='0402',
 MATERIAL='CHIP',
 PHYS_PAGE='193',
 XY='(-7950,775)',
 ROT='0',
 VER='2',
 VALUE='8.06K',
 PACK_TYPE='0402',
 PART_NUMBER='G21796-078',
 LOCATION='R4C12',
 ROOM='PVCCIN_CPU0_VR',
 GROUP='MCP',
 SEC='1',
 CDS_LIB='mstr_discrete',
 CDS_PART_NAME='RES_0402-8.06K,1%,1/16W,CHIP,GA',
 PRIM_FILE='./archive_libs/mstr_discrete/res/chips/chips.prt';

PART_NAME
 R4C13 'RES_0402-68.1K,1%,1/16W,EMPTY,A':;

SECTION_NUMBER 1
 '@BASEBOARD_FAB2_LIB.BASEBOARD_FAB2(SCH_1):PAGE205_I62@MSTR_DISCRETE.RES(CHIPS)':
 C_PATH='@baseboard_fab2_lib.baseboard_fab2(sch_1):page205_i62@mstr_discrete.res~
(chips)',
 P_PATH='@baseboard_fab2_lib.baseboard_fab2(sch_1):page205_i62@mstr_discrete.res~
(chips)',
 PATH='I62',
 DRAWING='@BASEBOARD_FAB2_LIB.BASEBOARD_FAB2(SCH_1):PAGE205',
 WATTAGE='1/16W',
 TOLERANCE='1%',
 MATERIAL='EMPTY',
 PHYS_PAGE='205',
 XY='(-775,4100)',
 ROT='0',
 VER='2',
 VALUE='68.1K',
 PACK_TYPE='0402',
 PART_NUMBER='G21796-187',
 LOCATION='R4C13',
 CDS_LIB='mstr_discrete',
 CDS_PART_NAME='RES_0402-68.1K,1%,1/16W,EMPTY,A',
 PRIM_FILE='./archive_libs/mstr_discrete/res/chips/chips.prt';

PART_NAME
 R4D1 'RES_0402-27.4,1%,1/16W,CHIP,G2A':
 ROOM='DB1200Z';

SECTION_NUMBER 1
 '@BASEBOARD_FAB2_LIB.BASEBOARD_FAB2(SCH_1):PAGE103_I54@MSTR_DISCRETE.RES(CHIPS)':
 C_PATH='@baseboard_fab2_lib.baseboard_fab2(sch_1):page103_i54@mstr_discrete.res~
(chips)',
 P_PATH='@baseboard_fab2_lib.baseboard_fab2(sch_1):page103_i54@mstr_discrete.res~
(chips)',
 PATH='I54',
 DRAWING='@BASEBOARD_FAB2_LIB.BASEBOARD_FAB2(SCH_1):PAGE103',
 WATTAGE='1/16W',
 TOLERANCE='1%',
 SEC_TYPE='0402',
 MATERIAL='CHIP',
 BOM_COST='SYS_CLOCK',
 PHYS_PAGE='103',
 XY='(-3925,1900)',
 ROT='0',
 VER='1',
 VALUE='27.4',
 PACK_TYPE='0402',
 PART_NUMBER='G21796-182',
 LOCATION='R4D1',
 ROOM='DB1200Z',
 SEC='1',
 CDS_LIB='mstr_discrete',
 CDS_PART_NAME='RES_0402-27.4,1%,1/16W,CHIP,G2A',
 PRIM_FILE='./archive_libs/mstr_discrete/res/chips/chips.prt';

PART_NAME
 R4D2 'RES_0402-27.4,1%,1/16W,CHIP,G2A':
 ROOM='DB1200Z';

SECTION_NUMBER 1
 '@BASEBOARD_FAB2_LIB.BASEBOARD_FAB2(SCH_1):PAGE103_I49@MSTR_DISCRETE.RES(CHIPS)':
 C_PATH='@baseboard_fab2_lib.baseboard_fab2(sch_1):page103_i49@mstr_discrete.res~
(chips)',
 P_PATH='@baseboard_fab2_lib.baseboard_fab2(sch_1):page103_i49@mstr_discrete.res~
(chips)',
 PATH='I49',
 DRAWING='@BASEBOARD_FAB2_LIB.BASEBOARD_FAB2(SCH_1):PAGE103',
 WATTAGE='1/16W',
 TOLERANCE='1%',
 MATERIAL='CHIP',
 BOM_COST='SYS_CLOCK',
 PHYS_PAGE='103',
 XY='(-3925,2225)',
 ROT='0',
 VER='1',
 VALUE='27.4',
 PACK_TYPE='0402',
 PART_NUMBER='G21796-182',
 LOCATION='R4D2',
 ROOM='DB1200Z',
 CDS_LIB='mstr_discrete',
 CDS_PART_NAME='RES_0402-27.4,1%,1/16W,CHIP,G2A',
 PRIM_FILE='./archive_libs/mstr_discrete/res/chips/chips.prt';

PART_NAME
 R4D3 'RES_0402-27.4,1%,1/16W,CHIP,G2A':
 ROOM='DB1200Z';

SECTION_NUMBER 1
 '@BASEBOARD_FAB2_LIB.BASEBOARD_FAB2(SCH_1):PAGE103_I64@MSTR_DISCRETE.RES(CHIPS)':
 C_PATH='@baseboard_fab2_lib.baseboard_fab2(sch_1):page103_i64@mstr_discrete.res~
(chips)',
 P_PATH='@baseboard_fab2_lib.baseboard_fab2(sch_1):page103_i64@mstr_discrete.res~
(chips)',
 PATH='I64',
 DRAWING='@BASEBOARD_FAB2_LIB.BASEBOARD_FAB2(SCH_1):PAGE103',
 WATTAGE='1/16W',
 TOLERANCE='1%',
 SEC_TYPE='0402',
 MATERIAL='CHIP',
 BOM_COST='SYS_CLOCK',
 PHYS_PAGE='103',
 XY='(-3925,1250)',
 ROT='0',
 VER='1',
 VALUE='27.4',
 PACK_TYPE='0402',
 PART_NUMBER='G21796-182',
 LOCATION='R4D3',
 ROOM='DB1200Z',
 SEC='1',
 CDS_LIB='mstr_discrete',
 CDS_PART_NAME='RES_0402-27.4,1%,1/16W,CHIP,G2A',
 PRIM_FILE='./archive_libs/mstr_discrete/res/chips/chips.prt';

PART_NAME
 R4D4 'RES_0402-27.4,1%,1/16W,CHIP,G2A':
 ROOM='DB1200Z';

SECTION_NUMBER 1
 '@BASEBOARD_FAB2_LIB.BASEBOARD_FAB2(SCH_1):PAGE103_I59@MSTR_DISCRETE.RES(CHIPS)':
 C_PATH='@baseboard_fab2_lib.baseboard_fab2(sch_1):page103_i59@mstr_discrete.res~
(chips)',
 P_PATH='@baseboard_fab2_lib.baseboard_fab2(sch_1):page103_i59@mstr_discrete.res~
(chips)',
 PATH='I59',
 DRAWING='@BASEBOARD_FAB2_LIB.BASEBOARD_FAB2(SCH_1):PAGE103',
 WATTAGE='1/16W',
 TOLERANCE='1%',
 SEC_TYPE='0402',
 MATERIAL='CHIP',
 BOM_COST='SYS_CLOCK',
 PHYS_PAGE='103',
 XY='(-3925,1575)',
 ROT='0',
 VER='1',
 VALUE='27.4',
 PACK_TYPE='0402',
 PART_NUMBER='G21796-182',
 LOCATION='R4D4',
 ROOM='DB1200Z',
 SEC='1',
 CDS_LIB='mstr_discrete',
 CDS_PART_NAME='RES_0402-27.4,1%,1/16W,CHIP,G2A',
 PRIM_FILE='./archive_libs/mstr_discrete/res/chips/chips.prt';

PART_NAME
 R4D5 'RES_0402-27.4,1%,1/16W,CHIP,G2A':
 ROOM='DB1200Z';

SECTION_NUMBER 1
 '@BASEBOARD_FAB2_LIB.BASEBOARD_FAB2(SCH_1):PAGE103_I79@MSTR_DISCRETE.RES(CHIPS)':
 C_PATH='@baseboard_fab2_lib.baseboard_fab2(sch_1):page103_i79@mstr_discrete.res~
(chips)',
 P_PATH='@baseboard_fab2_lib.baseboard_fab2(sch_1):page103_i79@mstr_discrete.res~
(chips)',
 PATH='I79',
 DRAWING='@BASEBOARD_FAB2_LIB.BASEBOARD_FAB2(SCH_1):PAGE103',
 WATTAGE='1/16W',
 TOLERANCE='1%',
 SEC_TYPE='0402',
 MATERIAL='CHIP',
 BOM_COST='SYS_CLOCK',
 PHYS_PAGE='103',
 XY='(300,4500)',
 ROT='0',
 VER='1',
 VALUE='27.4',
 PACK_TYPE='0402',
 PART_NUMBER='G21796-182',
 LOCATION='R4D5',
 ROOM='DB1200Z',
 SEC='1',
 CDS_LIB='mstr_discrete',
 CDS_PART_NAME='RES_0402-27.4,1%,1/16W,CHIP,G2A',
 PRIM_FILE='./archive_libs/mstr_discrete/res/chips/chips.prt';

PART_NAME
 R4D6 'RES_0402-27.4,1%,1/16W,CHIP,G2A':
 ROOM='DB1200Z';

SECTION_NUMBER 1
 '@BASEBOARD_FAB2_LIB.BASEBOARD_FAB2(SCH_1):PAGE103_I74@MSTR_DISCRETE.RES(CHIPS)':
 C_PATH='@baseboard_fab2_lib.baseboard_fab2(sch_1):page103_i74@mstr_discrete.res~
(chips)',
 P_PATH='@baseboard_fab2_lib.baseboard_fab2(sch_1):page103_i74@mstr_discrete.res~
(chips)',
 PATH='I74',
 DRAWING='@BASEBOARD_FAB2_LIB.BASEBOARD_FAB2(SCH_1):PAGE103',
 WATTAGE='1/16W',
 TOLERANCE='1%',
 SEC_TYPE='0402',
 MATERIAL='CHIP',
 BOM_COST='SYS_CLOCK',
 PHYS_PAGE='103',
 XY='(300,4825)',
 ROT='0',
 VER='1',
 VALUE='27.4',
 PACK_TYPE='0402',
 PART_NUMBER='G21796-182',
 LOCATION='R4D6',
 ROOM='DB1200Z',
 SEC='1',
 CDS_LIB='mstr_discrete',
 CDS_PART_NAME='RES_0402-27.4,1%,1/16W,CHIP,G2A',
 PRIM_FILE='./archive_libs/mstr_discrete/res/chips/chips.prt';

PART_NAME
 R4D7 'RES_0402-27.4,1%,1/16W,CHIP,G2A':
 ROOM='DB1200Z';

SECTION_NUMBER 1
 '@BASEBOARD_FAB2_LIB.BASEBOARD_FAB2(SCH_1):PAGE103_I89@MSTR_DISCRETE.RES(CHIPS)':
 C_PATH='@baseboard_fab2_lib.baseboard_fab2(sch_1):page103_i89@mstr_discrete.res~
(chips)',
 P_PATH='@baseboard_fab2_lib.baseboard_fab2(sch_1):page103_i89@mstr_discrete.res~
(chips)',
 PATH='I89',
 DRAWING='@BASEBOARD_FAB2_LIB.BASEBOARD_FAB2(SCH_1):PAGE103',
 WATTAGE='1/16W',
 TOLERANCE='1%',
 SEC_TYPE='0402',
 MATERIAL='CHIP',
 BOM_COST='SYS_CLOCK',
 PHYS_PAGE='103',
 XY='(300,3850)',
 ROT='0',
 VER='1',
 VALUE='27.4',
 PACK_TYPE='0402',
 PART_NUMBER='G21796-182',
 LOCATION='R4D7',
 ROOM='DB1200Z',
 SEC='1',
 CDS_LIB='mstr_discrete',
 CDS_PART_NAME='RES_0402-27.4,1%,1/16W,CHIP,G2A',
 PRIM_FILE='./archive_libs/mstr_discrete/res/chips/chips.prt';

PART_NAME
 R4D8 'RES_0402-27.4,1%,1/16W,CHIP,G2A':
 ROOM='DB1200Z';

SECTION_NUMBER 1
 '@BASEBOARD_FAB2_LIB.BASEBOARD_FAB2(SCH_1):PAGE103_I84@MSTR_DISCRETE.RES(CHIPS)':
 C_PATH='@baseboard_fab2_lib.baseboard_fab2(sch_1):page103_i84@mstr_discrete.res~
(chips)',
 P_PATH='@baseboard_fab2_lib.baseboard_fab2(sch_1):page103_i84@mstr_discrete.res~
(chips)',
 PATH='I84',
 DRAWING='@BASEBOARD_FAB2_LIB.BASEBOARD_FAB2(SCH_1):PAGE103',
 WATTAGE='1/16W',
 TOLERANCE='1%',
 SEC_TYPE='0402',
 MATERIAL='CHIP',
 BOM_COST='SYS_CLOCK',
 PHYS_PAGE='103',
 XY='(300,4175)',
 ROT='0',
 VER='1',
 VALUE='27.4',
 PACK_TYPE='0402',
 PART_NUMBER='G21796-182',
 LOCATION='R4D8',
 ROOM='DB1200Z',
 SEC='1',
 CDS_LIB='mstr_discrete',
 CDS_PART_NAME='RES_0402-27.4,1%,1/16W,CHIP,G2A',
 PRIM_FILE='./archive_libs/mstr_discrete/res/chips/chips.prt';

PART_NAME
 R4D9 'RES_0402-27.4,1%,1/16W,CHIP,G2A':
 ROOM='DB1200Z';

SECTION_NUMBER 1
 '@BASEBOARD_FAB2_LIB.BASEBOARD_FAB2(SCH_1):PAGE103_I39@MSTR_DISCRETE.RES(CHIPS)':
 C_PATH='@baseboard_fab2_lib.baseboard_fab2(sch_1):page103_i39@mstr_discrete.res~
(chips)',
 P_PATH='@baseboard_fab2_lib.baseboard_fab2(sch_1):page103_i39@mstr_discrete.res~
(chips)',
 PATH='I39',
 DRAWING='@BASEBOARD_FAB2_LIB.BASEBOARD_FAB2(SCH_1):PAGE103',
 WATTAGE='1/16W',
 TOLERANCE='1%',
 SEC_TYPE='0402',
 MATERIAL='CHIP',
 BOM_COST='SYS_CLOCK',
 PHYS_PAGE='103',
 XY='(-3925,2875)',
 ROT='0',
 VER='1',
 VALUE='27.4',
 PACK_TYPE='0402',
 PART_NUMBER='G21796-182',
 LOCATION='R4D9',
 ROOM='DB1200Z',
 SEC='1',
 CDS_LIB='mstr_discrete',
 CDS_PART_NAME='RES_0402-27.4,1%,1/16W,CHIP,G2A',
 PRIM_FILE='./archive_libs/mstr_discrete/res/chips/chips.prt';

PART_NAME
 R4D10 'RES_0402-27.4,1%,1/16W,CHIP,G2A':
 ROOM='DB1200Z';

SECTION_NUMBER 1
 '@BASEBOARD_FAB2_LIB.BASEBOARD_FAB2(SCH_1):PAGE103_I99@MSTR_DISCRETE.RES(CHIPS)':
 C_PATH='@baseboard_fab2_lib.baseboard_fab2(sch_1):page103_i99@mstr_discrete.res~
(chips)',
 P_PATH='@baseboard_fab2_lib.baseboard_fab2(sch_1):page103_i99@mstr_discrete.res~
(chips)',
 PATH='I99',
 DRAWING='@BASEBOARD_FAB2_LIB.BASEBOARD_FAB2(SCH_1):PAGE103',
 WATTAGE='1/16W',
 TOLERANCE='1%',
 SEC_TYPE='0402',
 MATERIAL='CHIP',
 BOM_COST='SYS_CLOCK',
 PHYS_PAGE='103',
 XY='(300,3200)',
 ROT='0',
 VER='1',
 VALUE='27.4',
 PACK_TYPE='0402',
 PART_NUMBER='G21796-182',
 LOCATION='R4D10',
 ROOM='DB1200Z',
 SEC='1',
 CDS_LIB='mstr_discrete',
 CDS_PART_NAME='RES_0402-27.4,1%,1/16W,CHIP,G2A',
 PRIM_FILE='./archive_libs/mstr_discrete/res/chips/chips.prt';

PART_NAME
 R4D11 'RES_0402-27.4,1%,1/16W,CHIP,G2A':
 ROOM='DB1200Z';

SECTION_NUMBER 1
 '@BASEBOARD_FAB2_LIB.BASEBOARD_FAB2(SCH_1):PAGE103_I44@MSTR_DISCRETE.RES(CHIPS)':
 C_PATH='@baseboard_fab2_lib.baseboard_fab2(sch_1):page103_i44@mstr_discrete.res~
(chips)',
 P_PATH='@baseboard_fab2_lib.baseboard_fab2(sch_1):page103_i44@mstr_discrete.res~
(chips)',
 PATH='I44',
 DRAWING='@BASEBOARD_FAB2_LIB.BASEBOARD_FAB2(SCH_1):PAGE103',
 WATTAGE='1/16W',
 TOLERANCE='1%',
 SEC_TYPE='0402',
 MATERIAL='CHIP',
 BOM_COST='SYS_CLOCK',
 PHYS_PAGE='103',
 XY='(-3925,2550)',
 ROT='0',
 VER='1',
 VALUE='27.4',
 PACK_TYPE='0402',
 PART_NUMBER='G21796-182',
 LOCATION='R4D11',
 ROOM='DB1200Z',
 SEC='1',
 CDS_LIB='mstr_discrete',
 CDS_PART_NAME='RES_0402-27.4,1%,1/16W,CHIP,G2A',
 PRIM_FILE='./archive_libs/mstr_discrete/res/chips/chips.prt';

PART_NAME
 R4D12 'RES_0402-27.4,1%,1/16W,CHIP,G2A':
 ROOM='DB1200Z';

SECTION_NUMBER 1
 '@BASEBOARD_FAB2_LIB.BASEBOARD_FAB2(SCH_1):PAGE103_I94@MSTR_DISCRETE.RES(CHIPS)':
 C_PATH='@baseboard_fab2_lib.baseboard_fab2(sch_1):page103_i94@mstr_discrete.res~
(chips)',
 P_PATH='@baseboard_fab2_lib.baseboard_fab2(sch_1):page103_i94@mstr_discrete.res~
(chips)',
 PATH='I94',
 DRAWING='@BASEBOARD_FAB2_LIB.BASEBOARD_FAB2(SCH_1):PAGE103',
 WATTAGE='1/16W',
 TOLERANCE='1%',
 SEC_TYPE='0402',
 MATERIAL='CHIP',
 BOM_COST='SYS_CLOCK',
 PHYS_PAGE='103',
 XY='(300,3525)',
 ROT='0',
 VER='1',
 VALUE='27.4',
 PACK_TYPE='0402',
 PART_NUMBER='G21796-182',
 LOCATION='R4D12',
 ROOM='DB1200Z',
 SEC='1',
 CDS_LIB='mstr_discrete',
 CDS_PART_NAME='RES_0402-27.4,1%,1/16W,CHIP,G2A',
 PRIM_FILE='./archive_libs/mstr_discrete/res/chips/chips.prt';

PART_NAME
 R4D13 'RES_0402-27.4,1%,1/16W,CHIP,G2A':
 ROOM='DB1200Z';

SECTION_NUMBER 1
 '@BASEBOARD_FAB2_LIB.BASEBOARD_FAB2(SCH_1):PAGE103_I29@MSTR_DISCRETE.RES(CHIPS)':
 C_PATH='@baseboard_fab2_lib.baseboard_fab2(sch_1):page103_i29@mstr_discrete.res~
(chips)',
 P_PATH='@baseboard_fab2_lib.baseboard_fab2(sch_1):page103_i29@mstr_discrete.res~
(chips)',
 PATH='I29',
 DRAWING='@BASEBOARD_FAB2_LIB.BASEBOARD_FAB2(SCH_1):PAGE103',
 WATTAGE='1/16W',
 TOLERANCE='1%',
 SEC_TYPE='0402',
 MATERIAL='CHIP',
 BOM_COST='SYS_CLOCK',
 PHYS_PAGE='103',
 XY='(-3925,3525)',
 ROT='0',
 VER='1',
 VALUE='27.4',
 PACK_TYPE='0402',
 PART_NUMBER='G21796-182',
 LOCATION='R4D13',
 ROOM='DB1200Z',
 SEC='1',
 CDS_LIB='mstr_discrete',
 CDS_PART_NAME='RES_0402-27.4,1%,1/16W,CHIP,G2A',
 PRIM_FILE='./archive_libs/mstr_discrete/res/chips/chips.prt';

PART_NAME
 R4D14 'RES_0402-27.4,1%,1/16W,CHIP,G2A':
 ROOM='DB1200Z';

SECTION_NUMBER 1
 '@BASEBOARD_FAB2_LIB.BASEBOARD_FAB2(SCH_1):PAGE103_I109@MSTR_DISCRETE.RES(CHIPS)':
 C_PATH='@baseboard_fab2_lib.baseboard_fab2(sch_1):page103_i109@mstr_discrete.re~
s(chips)',
 P_PATH='@baseboard_fab2_lib.baseboard_fab2(sch_1):page103_i109@mstr_discrete.re~
s(chips)',
 PATH='I109',
 DRAWING='@BASEBOARD_FAB2_LIB.BASEBOARD_FAB2(SCH_1):PAGE103',
 WATTAGE='1/16W',
 TOLERANCE='1%',
 SEC_TYPE='0402',
 MATERIAL='CHIP',
 BOM_COST='SYS_CLOCK',
 PHYS_PAGE='103',
 XY='(300,2550)',
 ROT='0',
 VER='1',
 VALUE='27.4',
 PACK_TYPE='0402',
 PART_NUMBER='G21796-182',
 LOCATION='R4D14',
 ROOM='DB1200Z',
 SEC='1',
 CDS_LIB='mstr_discrete',
 CDS_PART_NAME='RES_0402-27.4,1%,1/16W,CHIP,G2A',
 PRIM_FILE='./archive_libs/mstr_discrete/res/chips/chips.prt';

PART_NAME
 R4D16 'RES_0402-27.4,1%,1/16W,CHIP,G2A':
 ROOM='DB1200Z';

SECTION_NUMBER 1
 '@BASEBOARD_FAB2_LIB.BASEBOARD_FAB2(SCH_1):PAGE103_I34@MSTR_DISCRETE.RES(CHIPS)':
 C_PATH='@baseboard_fab2_lib.baseboard_fab2(sch_1):page103_i34@mstr_discrete.res~
(chips)',
 P_PATH='@baseboard_fab2_lib.baseboard_fab2(sch_1):page103_i34@mstr_discrete.res~
(chips)',
 PATH='I34',
 DRAWING='@BASEBOARD_FAB2_LIB.BASEBOARD_FAB2(SCH_1):PAGE103',
 WATTAGE='1/16W',
 TOLERANCE='1%',
 SEC_TYPE='0402',
 MATERIAL='CHIP',
 BOM_COST='SYS_CLOCK',
 PHYS_PAGE='103',
 XY='(-3925,3200)',
 ROT='0',
 VER='1',
 VALUE='27.4',
 PACK_TYPE='0402',
 PART_NUMBER='G21796-182',
 LOCATION='R4D16',
 ROOM='DB1200Z',
 SEC='1',
 CDS_LIB='mstr_discrete',
 CDS_PART_NAME='RES_0402-27.4,1%,1/16W,CHIP,G2A',
 PRIM_FILE='./archive_libs/mstr_discrete/res/chips/chips.prt';

PART_NAME
 R4D17 'RES_0402-27.4,1%,1/16W,CHIP,G2A':
 ROOM='DB1200Z';

SECTION_NUMBER 1
 '@BASEBOARD_FAB2_LIB.BASEBOARD_FAB2(SCH_1):PAGE103_I104@MSTR_DISCRETE.RES(CHIPS)':
 C_PATH='@baseboard_fab2_lib.baseboard_fab2(sch_1):page103_i104@mstr_discrete.re~
s(chips)',
 P_PATH='@baseboard_fab2_lib.baseboard_fab2(sch_1):page103_i104@mstr_discrete.re~
s(chips)',
 PATH='I104',
 DRAWING='@BASEBOARD_FAB2_LIB.BASEBOARD_FAB2(SCH_1):PAGE103',
 WATTAGE='1/16W',
 TOLERANCE='1%',
 SEC_TYPE='0402',
 MATERIAL='CHIP',
 BOM_COST='SYS_CLOCK',
 PHYS_PAGE='103',
 XY='(300,2875)',
 ROT='0',
 VER='1',
 VALUE='27.4',
 PACK_TYPE='0402',
 PART_NUMBER='G21796-182',
 LOCATION='R4D17',
 ROOM='DB1200Z',
 SEC='1',
 CDS_LIB='mstr_discrete',
 CDS_PART_NAME='RES_0402-27.4,1%,1/16W,CHIP,G2A',
 PRIM_FILE='./archive_libs/mstr_discrete/res/chips/chips.prt';

PART_NAME
 R4D18 'RES_0402-42.2,1.0%,1/16W,EMPTYA':
 ROOM='DB1200Z';

SECTION_NUMBER 1
 '@BASEBOARD_FAB2_LIB.BASEBOARD_FAB2(SCH_1):PAGE103_I163@MSTR_DISCRETE.RES(CHIPS)':
 C_PATH='@baseboard_fab2_lib.baseboard_fab2(sch_1):page103_i163@mstr_discrete.re~
s(chips)',
 P_PATH='@baseboard_fab2_lib.baseboard_fab2(sch_1):page103_i163@mstr_discrete.re~
s(chips)',
 PATH='I163',
 DRAWING='@BASEBOARD_FAB2_LIB.BASEBOARD_FAB2(SCH_1):PAGE103',
 WATTAGE='1/16W',
 TOLERANCE='1.0%',
 SEC_TYPE='0402',
 MATERIAL='EMPTY',
 BOM_COST='SYS_CLOCK',
 PHYS_PAGE='103',
 XY='(1050,1800)',
 ROT='0',
 VER='1',
 VALUE='42.2',
 PACK_TYPE='0402',
 PART_NUMBER='G21796-259',
 LOCATION='R4D18',
 ROOM='DB1200Z',
 SEC='1',
 CDS_LIB='mstr_discrete',
 CDS_PART_NAME='RES_0402-42.2,1.0%,1/16W,EMPTYA',
 PRIM_FILE='./archive_libs/mstr_discrete/res/chips/chips.prt';

PART_NAME
 R4D19 'RES_0402-27.4,1%,1/16W,CHIP,G2A':
 ROOM='DB1200Z';

SECTION_NUMBER 1
 '@BASEBOARD_FAB2_LIB.BASEBOARD_FAB2(SCH_1):PAGE103_I19@MSTR_DISCRETE.RES(CHIPS)':
 C_PATH='@baseboard_fab2_lib.baseboard_fab2(sch_1):page103_i19@mstr_discrete.res~
(chips)',
 P_PATH='@baseboard_fab2_lib.baseboard_fab2(sch_1):page103_i19@mstr_discrete.res~
(chips)',
 PATH='I19',
 DRAWING='@BASEBOARD_FAB2_LIB.BASEBOARD_FAB2(SCH_1):PAGE103',
 WATTAGE='1/16W',
 TOLERANCE='1%',
 SEC_TYPE='0402',
 MATERIAL='CHIP',
 BOM_COST='SYS_CLOCK',
 PHYS_PAGE='103',
 XY='(-3925,4175)',
 ROT='0',
 VER='1',
 VALUE='27.4',
 PACK_TYPE='0402',
 PART_NUMBER='G21796-182',
 LOCATION='R4D19',
 ROOM='DB1200Z',
 SEC='1',
 CDS_LIB='mstr_discrete',
 CDS_PART_NAME='RES_0402-27.4,1%,1/16W,CHIP,G2A',
 PRIM_FILE='./archive_libs/mstr_discrete/res/chips/chips.prt';

PART_NAME
 R4D20 'RES_0402-27.4,1%,1/16W,CHIP,G2A':
 ROOM='DB1200Z';

SECTION_NUMBER 1
 '@BASEBOARD_FAB2_LIB.BASEBOARD_FAB2(SCH_1):PAGE103_I119@MSTR_DISCRETE.RES(CHIPS)':
 C_PATH='@baseboard_fab2_lib.baseboard_fab2(sch_1):page103_i119@mstr_discrete.re~
s(chips)',
 P_PATH='@baseboard_fab2_lib.baseboard_fab2(sch_1):page103_i119@mstr_discrete.re~
s(chips)',
 PATH='I119',
 DRAWING='@BASEBOARD_FAB2_LIB.BASEBOARD_FAB2(SCH_1):PAGE103',
 WATTAGE='1/16W',
 TOLERANCE='1%',
 SEC_TYPE='0402',
 MATERIAL='CHIP',
 BOM_COST='SYS_CLOCK',
 PHYS_PAGE='103',
 XY='(300,1900)',
 ROT='0',
 VER='1',
 VALUE='27.4',
 PACK_TYPE='0402',
 PART_NUMBER='G21796-182',
 LOCATION='R4D20',
 ROOM='DB1200Z',
 SEC='1',
 CDS_LIB='mstr_discrete',
 CDS_PART_NAME='RES_0402-27.4,1%,1/16W,CHIP,G2A',
 PRIM_FILE='./archive_libs/mstr_discrete/res/chips/chips.prt';

PART_NAME
 R4D21 'RES_0402-27.4,1%,1/16W,CHIP,G2A':
 ROOM='DB1200Z';

SECTION_NUMBER 1
 '@BASEBOARD_FAB2_LIB.BASEBOARD_FAB2(SCH_1):PAGE103_I24@MSTR_DISCRETE.RES(CHIPS)':
 C_PATH='@baseboard_fab2_lib.baseboard_fab2(sch_1):page103_i24@mstr_discrete.res~
(chips)',
 P_PATH='@baseboard_fab2_lib.baseboard_fab2(sch_1):page103_i24@mstr_discrete.res~
(chips)',
 PATH='I24',
 DRAWING='@BASEBOARD_FAB2_LIB.BASEBOARD_FAB2(SCH_1):PAGE103',
 WATTAGE='1/16W',
 TOLERANCE='1%',
 SEC_TYPE='0402',
 MATERIAL='CHIP',
 BOM_COST='SYS_CLOCK',
 PHYS_PAGE='103',
 XY='(-3925,3850)',
 ROT='0',
 VER='1',
 VALUE='27.4',
 PACK_TYPE='0402',
 PART_NUMBER='G21796-182',
 LOCATION='R4D21',
 ROOM='DB1200Z',
 SEC='1',
 CDS_LIB='mstr_discrete',
 CDS_PART_NAME='RES_0402-27.4,1%,1/16W,CHIP,G2A',
 PRIM_FILE='./archive_libs/mstr_discrete/res/chips/chips.prt';

PART_NAME
 R4D22 'RES_0402-27.4,1%,1/16W,CHIP,G2A':
 ROOM='DB1200Z';

SECTION_NUMBER 1
 '@BASEBOARD_FAB2_LIB.BASEBOARD_FAB2(SCH_1):PAGE103_I114@MSTR_DISCRETE.RES(CHIPS)':
 C_PATH='@baseboard_fab2_lib.baseboard_fab2(sch_1):page103_i114@mstr_discrete.re~
s(chips)',
 P_PATH='@baseboard_fab2_lib.baseboard_fab2(sch_1):page103_i114@mstr_discrete.re~
s(chips)',
 PATH='I114',
 DRAWING='@BASEBOARD_FAB2_LIB.BASEBOARD_FAB2(SCH_1):PAGE103',
 WATTAGE='1/16W',
 TOLERANCE='1%',
 SEC_TYPE='0402',
 MATERIAL='CHIP',
 BOM_COST='SYS_CLOCK',
 PHYS_PAGE='103',
 XY='(300,2225)',
 ROT='0',
 VER='1',
 VALUE='27.4',
 PACK_TYPE='0402',
 PART_NUMBER='G21796-182',
 LOCATION='R4D22',
 ROOM='DB1200Z',
 SEC='1',
 CDS_LIB='mstr_discrete',
 CDS_PART_NAME='RES_0402-27.4,1%,1/16W,CHIP,G2A',
 PRIM_FILE='./archive_libs/mstr_discrete/res/chips/chips.prt';

PART_NAME
 R4D23 'RES_0402-27.4,1%,1/16W,CHIP,G2A':
 ROOM='DB1200Z';

SECTION_NUMBER 1
 '@BASEBOARD_FAB2_LIB.BASEBOARD_FAB2(SCH_1):PAGE103_I9@MSTR_DISCRETE.RES(CHIPS)':
 C_PATH='@baseboard_fab2_lib.baseboard_fab2(sch_1):page103_i9@mstr_discrete.res(~
chips)',
 P_PATH='@baseboard_fab2_lib.baseboard_fab2(sch_1):page103_i9@mstr_discrete.res(~
chips)',
 PATH='I9',
 DRAWING='@BASEBOARD_FAB2_LIB.BASEBOARD_FAB2(SCH_1):PAGE103',
 WATTAGE='1/16W',
 TOLERANCE='1%',
 SEC_TYPE='0402',
 MATERIAL='CHIP',
 BOM_COST='SYS_CLOCK',
 PHYS_PAGE='103',
 XY='(-3925,4900)',
 ROT='0',
 VER='1',
 VALUE='27.4',
 PACK_TYPE='0402',
 PART_NUMBER='G21796-182',
 LOCATION='R4D23',
 ROOM='DB1200Z',
 SEC='1',
 CDS_LIB='mstr_discrete',
 CDS_PART_NAME='RES_0402-27.4,1%,1/16W,CHIP,G2A',
 PRIM_FILE='./archive_libs/mstr_discrete/res/chips/chips.prt';

PART_NAME
 R4D24 'RES_0402-42.2,1.0%,1/16W,EMPTYA':
 ROOM='DB1200Z';

SECTION_NUMBER 1
 '@BASEBOARD_FAB2_LIB.BASEBOARD_FAB2(SCH_1):PAGE103_I161@MSTR_DISCRETE.RES(CHIPS)':
 C_PATH='@baseboard_fab2_lib.baseboard_fab2(sch_1):page103_i161@mstr_discrete.re~
s(chips)',
 P_PATH='@baseboard_fab2_lib.baseboard_fab2(sch_1):page103_i161@mstr_discrete.re~
s(chips)',
 PATH='I161',
 DRAWING='@BASEBOARD_FAB2_LIB.BASEBOARD_FAB2(SCH_1):PAGE103',
 WATTAGE='1/16W',
 TOLERANCE='1.0%',
 SEC_TYPE='0402',
 MATERIAL='EMPTY',
 BOM_COST='SYS_CLOCK',
 PHYS_PAGE='103',
 XY='(1050,2125)',
 ROT='0',
 VER='1',
 VALUE='42.2',
 PACK_TYPE='0402',
 PART_NUMBER='G21796-259',
 LOCATION='R4D24',
 ROOM='DB1200Z',
 SEC='1',
 CDS_LIB='mstr_discrete',
 CDS_PART_NAME='RES_0402-42.2,1.0%,1/16W,EMPTYA',
 PRIM_FILE='./archive_libs/mstr_discrete/res/chips/chips.prt';

PART_NAME
 R4D25 'RES_0402-27.4,1%,1/16W,CHIP,G2A':
 ROOM='DB1200Z';

SECTION_NUMBER 1
 '@BASEBOARD_FAB2_LIB.BASEBOARD_FAB2(SCH_1):PAGE103_I1@MSTR_DISCRETE.RES(CHIPS)':
 C_PATH='@baseboard_fab2_lib.baseboard_fab2(sch_1):page103_i1@mstr_discrete.res(~
chips)',
 P_PATH='@baseboard_fab2_lib.baseboard_fab2(sch_1):page103_i1@mstr_discrete.res(~
chips)',
 PATH='I1',
 DRAWING='@BASEBOARD_FAB2_LIB.BASEBOARD_FAB2(SCH_1):PAGE103',
 WATTAGE='1/16W',
 TOLERANCE='1%',
 SEC_TYPE='0402',
 MATERIAL='CHIP',
 BOM_COST='SYS_CLOCK',
 PHYS_PAGE='103',
 XY='(300,1250)',
 ROT='0',
 VER='1',
 VALUE='27.4',
 PACK_TYPE='0402',
 PART_NUMBER='G21796-182',
 LOCATION='R4D25',
 ROOM='DB1200Z',
 SEC='1',
 CDS_LIB='mstr_discrete',
 CDS_PART_NAME='RES_0402-27.4,1%,1/16W,CHIP,G2A',
 PRIM_FILE='./archive_libs/mstr_discrete/res/chips/chips.prt';

PART_NAME
 R4D26 'RES_0402-0.0,5%,1/16W,CHIP,G21A':
 ROOM='PVCCIN_CPU0_VR';

SECTION_NUMBER 1
 '@BASEBOARD_FAB2_LIB.BASEBOARD_FAB2(SCH_1):PAGE201_I40@MSTR_DISCRETE.RES(CHIPS)':
 C_PATH='@baseboard_fab2_lib.baseboard_fab2(sch_1):page201_i40@mstr_discrete.res~
(chips)',
 P_PATH='@baseboard_fab2_lib.baseboard_fab2(sch_1):page201_i40@mstr_discrete.res~
(chips)',
 PATH='I40',
 DRAWING='@BASEBOARD_FAB2_LIB.BASEBOARD_FAB2(SCH_1):PAGE201',
 WATTAGE='1/16W',
 TOLERANCE='5%',
 SEC_TYPE='0402',
 MATERIAL='CHIP',
 PHYS_PAGE='201',
 XY='(-4250,4275)',
 ROT='0',
 VER='2',
 VALUE='0.0',
 PACK_TYPE='0402',
 PART_NUMBER='G21497-005',
 LOCATION='R4D26',
 ROOM='PVCCIN_CPU0_VR',
 SEC='1',
 CDS_LIB='mstr_discrete',
 CDS_PART_NAME='RES_0402-0.0,5%,1/16W,CHIP,G21A',
 PRIM_FILE='./archive_libs/mstr_discrete/res/chips/chips.prt';

PART_NAME
 R4D27 'RES_0402-100.0K,1%,1/16W,CHIP,B':
 ROOM='PVCCIN_CPU0_VR';

SECTION_NUMBER 1
 '@BASEBOARD_FAB2_LIB.BASEBOARD_FAB2(SCH_1):PAGE201_I54@MSTR_DISCRETE.RES(CHIPS)':
 C_PATH='@baseboard_fab2_lib.baseboard_fab2(sch_1):page201_i54@mstr_discrete.res~
(chips)',
 P_PATH='@baseboard_fab2_lib.baseboard_fab2(sch_1):page201_i54@mstr_discrete.res~
(chips)',
 PATH='I54',
 DRAWING='@BASEBOARD_FAB2_LIB.BASEBOARD_FAB2(SCH_1):PAGE201',
 WATTAGE='1/16W',
 TOLERANCE='1%',
 SEC_TYPE='0402',
 MATERIAL='CHIP',
 PHYS_PAGE='201',
 XY='(-6050,4625)',
 ROT='0',
 VER='2',
 VALUE='100.0K',
 PACK_TYPE='0402',
 PART_NUMBER='G21796-160',
 LOCATION='R4D27',
 ROOM='PVCCIN_CPU0_VR',
 SEC='1',
 CDS_LIB='mstr_discrete',
 CDS_PART_NAME='RES_0402-100.0K,1%,1/16W,CHIP,B',
 PRIM_FILE='./archive_libs/mstr_discrete/res/chips/chips.prt';

PART_NAME
 R4D28 'RES_0402-27.4,1%,1/16W,CHIP,G2A':
 ROOM='DB1200Z';

SECTION_NUMBER 1
 '@BASEBOARD_FAB2_LIB.BASEBOARD_FAB2(SCH_1):PAGE103_I14@MSTR_DISCRETE.RES(CHIPS)':
 C_PATH='@baseboard_fab2_lib.baseboard_fab2(sch_1):page103_i14@mstr_discrete.res~
(chips)',
 P_PATH='@baseboard_fab2_lib.baseboard_fab2(sch_1):page103_i14@mstr_discrete.res~
(chips)',
 PATH='I14',
 DRAWING='@BASEBOARD_FAB2_LIB.BASEBOARD_FAB2(SCH_1):PAGE103',
 WATTAGE='1/16W',
 TOLERANCE='1%',
 SEC_TYPE='0402',
 MATERIAL='CHIP',
 BOM_COST='SYS_CLOCK',
 PHYS_PAGE='103',
 XY='(-3925,4525)',
 ROT='0',
 VER='1',
 VALUE='27.4',
 PACK_TYPE='0402',
 PART_NUMBER='G21796-182',
 LOCATION='R4D28',
 ROOM='DB1200Z',
 SEC='1',
 CDS_LIB='mstr_discrete',
 CDS_PART_NAME='RES_0402-27.4,1%,1/16W,CHIP,G2A',
 PRIM_FILE='./archive_libs/mstr_discrete/res/chips/chips.prt';

PART_NAME
 R4D29 'RES_0402-27.4,1%,1/16W,CHIP,G2A':
 ROOM='DB1200Z';

SECTION_NUMBER 1
 '@BASEBOARD_FAB2_LIB.BASEBOARD_FAB2(SCH_1):PAGE103_I69@MSTR_DISCRETE.RES(CHIPS)':
 C_PATH='@baseboard_fab2_lib.baseboard_fab2(sch_1):page103_i69@mstr_discrete.res~
(chips)',
 P_PATH='@baseboard_fab2_lib.baseboard_fab2(sch_1):page103_i69@mstr_discrete.res~
(chips)',
 PATH='I69',
 DRAWING='@BASEBOARD_FAB2_LIB.BASEBOARD_FAB2(SCH_1):PAGE103',
 WATTAGE='1/16W',
 TOLERANCE='1%',
 SEC_TYPE='0402',
 MATERIAL='CHIP',
 BOM_COST='SYS_CLOCK',
 PHYS_PAGE='103',
 XY='(300,1575)',
 ROT='0',
 VER='1',
 VALUE='27.4',
 PACK_TYPE='0402',
 PART_NUMBER='G21796-182',
 LOCATION='R4D29',
 ROOM='DB1200Z',
 SEC='1',
 CDS_LIB='mstr_discrete',
 CDS_PART_NAME='RES_0402-27.4,1%,1/16W,CHIP,G2A',
 PRIM_FILE='./archive_libs/mstr_discrete/res/chips/chips.prt';

PART_NAME
 R4D31 'RES_0402-2.26K,1.0%,1/16W,EMPTA':
 ROOM='PVCCIN_CPU0_VR';

SECTION_NUMBER 1
 '@BASEBOARD_FAB2_LIB.BASEBOARD_FAB2(SCH_1):PAGE201_I22@MSTR_DISCRETE.RES(CHIPS)':
 C_PATH='@baseboard_fab2_lib.baseboard_fab2(sch_1):page201_i22@mstr_discrete.res~
(chips)',
 P_PATH='@baseboard_fab2_lib.baseboard_fab2(sch_1):page201_i22@mstr_discrete.res~
(chips)',
 PATH='I22',
 DRAWING='@BASEBOARD_FAB2_LIB.BASEBOARD_FAB2(SCH_1):PAGE201',
 WATTAGE='1/16W',
 TOLERANCE='1.0%',
 SEC_TYPE='0402',
 MATERIAL='EMPTY',
 PHYS_PAGE='201',
 XY='(-2075,3750)',
 ROT='0',
 VER='2',
 VALUE='2.26K',
 PACK_TYPE='0402',
 PART_NUMBER='G21796-311',
 LOCATION='R4D31',
 ROOM='PVCCIN_CPU0_VR',
 SEC='1',
 CDS_LIB='mstr_discrete',
 CDS_PART_NAME='RES_0402-2.26K,1.0%,1/16W,EMPTA',
 PRIM_FILE='./archive_libs/mstr_discrete/res/chips/chips.prt';

PART_NAME
 R4D32 'RES_0402-1.5K,1%,1/16W,CHIP,G2A':
 ROOM='PVCCIN_CPU0_VR';

SECTION_NUMBER 1
 '@BASEBOARD_FAB2_LIB.BASEBOARD_FAB2(SCH_1):PAGE201_I55@MSTR_DISCRETE.RES(CHIPS)':
 C_PATH='@baseboard_fab2_lib.baseboard_fab2(sch_1):page201_i55@mstr_discrete.res~
(chips)',
 P_PATH='@baseboard_fab2_lib.baseboard_fab2(sch_1):page201_i55@mstr_discrete.res~
(chips)',
 PATH='I55',
 DRAWING='@BASEBOARD_FAB2_LIB.BASEBOARD_FAB2(SCH_1):PAGE201',
 WATTAGE='1/16W',
 TOLERANCE='1%',
 SEC_TYPE='0402',
 MATERIAL='CHIP',
 PHYS_PAGE='201',
 XY='(-6050,4200)',
 ROT='0',
 VER='2',
 VALUE='1.5K',
 PACK_TYPE='0402',
 PART_NUMBER='G21796-003',
 LOCATION='R4D32',
 ROOM='PVCCIN_CPU0_VR',
 SEC='1',
 CDS_LIB='mstr_discrete',
 CDS_PART_NAME='RES_0402-1.5K,1%,1/16W,CHIP,G2A',
 PRIM_FILE='./archive_libs/mstr_discrete/res/chips/chips.prt';

PART_NAME
 R4D35 'RES_0402-10.0K,1%,1/16W,EMPTY,A':
 ROOM='DB1200ZL';

SECTION_NUMBER 1
 '@BASEBOARD_FAB2_LIB.BASEBOARD_FAB2(SCH_1):PAGE102_I38@MSTR_DISCRETE.RES(CHIPS)':
 C_PATH='@baseboard_fab2_lib.baseboard_fab2(sch_1):page102_i38@mstr_discrete.res~
(chips)',
 P_PATH='@baseboard_fab2_lib.baseboard_fab2(sch_1):page102_i38@mstr_discrete.res~
(chips)',
 PATH='I38',
 DRAWING='@BASEBOARD_FAB2_LIB.BASEBOARD_FAB2(SCH_1):PAGE102',
 WATTAGE='1/16W',
 TOLERANCE='1%',
 SEC_TYPE='0402',
 MATERIAL='EMPTY',
 BOM_COST='SYS_CLOCK',
 PHYS_PAGE='102',
 XY='(-3225,2850)',
 ROT='0',
 VER='2',
 VALUE='10.0K',
 PACK_TYPE='0402',
 PART_NUMBER='G21796-016',
 LOCATION='R4D35',
 ROOM='DB1200ZL',
 SEC='1',
 CDS_LIB='mstr_discrete',
 CDS_PART_NAME='RES_0402-10.0K,1%,1/16W,EMPTY,A',
 PRIM_FILE='./archive_libs/mstr_discrete/res/chips/chips.prt';

PART_NAME
 R4D38 'RES_0402-10.0K,1%,1/16W,EMPTY,A':
 ROOM='DB1200ZL';

SECTION_NUMBER 1
 '@BASEBOARD_FAB2_LIB.BASEBOARD_FAB2(SCH_1):PAGE102_I37@MSTR_DISCRETE.RES(CHIPS)':
 C_PATH='@baseboard_fab2_lib.baseboard_fab2(sch_1):page102_i37@mstr_discrete.res~
(chips)',
 P_PATH='@baseboard_fab2_lib.baseboard_fab2(sch_1):page102_i37@mstr_discrete.res~
(chips)',
 PATH='I37',
 DRAWING='@BASEBOARD_FAB2_LIB.BASEBOARD_FAB2(SCH_1):PAGE102',
 WATTAGE='1/16W',
 TOLERANCE='1%',
 SEC_TYPE='0402',
 MATERIAL='EMPTY',
 BOM_COST='SYS_CLOCK',
 PHYS_PAGE='102',
 XY='(-2850,2850)',
 ROT='0',
 VER='2',
 VALUE='10.0K',
 PACK_TYPE='0402',
 PART_NUMBER='G21796-016',
 LOCATION='R4D38',
 ROOM='DB1200ZL',
 SEC='1',
 CDS_LIB='mstr_discrete',
 CDS_PART_NAME='RES_0402-10.0K,1%,1/16W,EMPTY,A',
 PRIM_FILE='./archive_libs/mstr_discrete/res/chips/chips.prt';

PART_NAME
 R4D39 'RES_0402-10.0,1%,1/16W,CHIP,G2A':
 ROOM='PVCCIN_CPU0_VR',
 NO_XNET_CONNECTION='1';

SECTION_NUMBER 1
 '@BASEBOARD_FAB2_LIB.BASEBOARD_FAB2(SCH_1):PAGE201_I110@MSTR_DISCRETE.RES(CHIPS)':
 C_PATH='@baseboard_fab2_lib.baseboard_fab2(sch_1):page201_i110@mstr_discrete.re~
s(chips)',
 P_PATH='@baseboard_fab2_lib.baseboard_fab2(sch_1):page201_i110@mstr_discrete.re~
s(chips)',
 PATH='I110',
 DRAWING='@BASEBOARD_FAB2_LIB.BASEBOARD_FAB2(SCH_1):PAGE201',
 WATTAGE='1/16W',
 TOLERANCE='1%',
 SEC_TYPE='0402',
 MATERIAL='CHIP',
 NO_XNET_CONNECTION='1',
 PHYS_PAGE='201',
 XY='(-6250,2075)',
 ROT='0',
 VER='1',
 VALUE='10.0',
 PACK_TYPE='0402',
 PART_NUMBER='G21796-066',
 LOCATION='R4D39',
 ROOM='PVCCIN_CPU0_VR',
 SEC='1',
 CDS_LIB='mstr_discrete',
 CDS_PART_NAME='RES_0402-10.0,1%,1/16W,CHIP,G2A',
 PRIM_FILE='./archive_libs/mstr_discrete/res/chips/chips.prt';

PART_NAME
 R4D40 'RES_0402-4.75K,1%,1/16W,CHIP,GA':
 ROOM='DB1200ZL';

SECTION_NUMBER 1
 '@BASEBOARD_FAB2_LIB.BASEBOARD_FAB2(SCH_1):PAGE102_I45@MSTR_DISCRETE.RES(CHIPS)':
 C_PATH='@baseboard_fab2_lib.baseboard_fab2(sch_1):page102_i45@mstr_discrete.res~
(chips)',
 P_PATH='@baseboard_fab2_lib.baseboard_fab2(sch_1):page102_i45@mstr_discrete.res~
(chips)',
 PATH='I45',
 DRAWING='@BASEBOARD_FAB2_LIB.BASEBOARD_FAB2(SCH_1):PAGE102',
 WATTAGE='1/16W',
 TOLERANCE='1%',
 SEC_TYPE='0402',
 MATERIAL='CHIP',
 BOM_COST='SYS_CLOCK',
 PHYS_PAGE='102',
 XY='(-2675,1425)',
 ROT='0',
 VER='2',
 VALUE='4.75K',
 PACK_TYPE='0402',
 PART_NUMBER='G21796-072',
 LOCATION='R4D40',
 ROOM='DB1200ZL',
 SEC='1',
 CDS_LIB='mstr_discrete',
 CDS_PART_NAME='RES_0402-4.75K,1%,1/16W,CHIP,GA',
 PRIM_FILE='./archive_libs/mstr_discrete/res/chips/chips.prt';

PART_NAME
 R4D41 'RES_0402-4.75K,1%,1/16W,CHIP,GA':
 ROOM='DB1200ZL';

SECTION_NUMBER 1
 '@BASEBOARD_FAB2_LIB.BASEBOARD_FAB2(SCH_1):PAGE102_I53@MSTR_DISCRETE.RES(CHIPS)':
 C_PATH='@baseboard_fab2_lib.baseboard_fab2(sch_1):page102_i53@mstr_discrete.res~
(chips)',
 P_PATH='@baseboard_fab2_lib.baseboard_fab2(sch_1):page102_i53@mstr_discrete.res~
(chips)',
 PATH='I53',
 DRAWING='@BASEBOARD_FAB2_LIB.BASEBOARD_FAB2(SCH_1):PAGE102',
 WATTAGE='1/16W',
 TOLERANCE='1%',
 SEC_TYPE='0402',
 MATERIAL='CHIP',
 BOM_COST='SYS_CLOCK',
 PHYS_PAGE='102',
 XY='(-2925,1425)',
 ROT='2',
 VER='2',
 VALUE='4.75K',
 PACK_TYPE='0402',
 PART_NUMBER='G21796-072',
 LOCATION='R4D41',
 ROOM='DB1200ZL',
 SEC='1',
 CDS_LIB='mstr_discrete',
 CDS_PART_NAME='RES_0402-4.75K,1%,1/16W,CHIP,GA',
 PRIM_FILE='./archive_libs/mstr_discrete/res/chips/chips.prt';

PART_NAME
 R4D42 'RES_0402-1.00K,1%,1/16W,CHIP,GA':
 ROOM='PVCCIO_CPU1';

SECTION_NUMBER 1
 '@BASEBOARD_FAB2_LIB.BASEBOARD_FAB2(SCH_1):PAGE213_I15@MSTR_DISCRETE.RES(CHIPS)':
 C_PATH='@baseboard_fab2_lib.baseboard_fab2(sch_1):page213_i15@mstr_discrete.res~
(chips)',
 P_PATH='@baseboard_fab2_lib.baseboard_fab2(sch_1):page213_i15@mstr_discrete.res~
(chips)',
 PATH='I15',
 DRAWING='@BASEBOARD_FAB2_LIB.BASEBOARD_FAB2(SCH_1):PAGE213',
 WATTAGE='1/16W',
 TOLERANCE='1%',
 SEC_TYPE='0402',
 MATERIAL='CHIP',
 PHYS_PAGE='213',
 XY='(950,4050)',
 ROT='0',
 VER='2',
 VALUE='1.00K',
 PACK_TYPE='0402',
 PART_NUMBER='G21796-026',
 LOCATION='R4D42',
 ROOM='PVCCIO_CPU1',
 SEC='1',
 CDS_LIB='mstr_discrete',
 CDS_PART_NAME='RES_0402-1.00K,1%,1/16W,CHIP,GA',
 PRIM_FILE='./archive_libs/mstr_discrete/res/chips/chips.prt';

PART_NAME
 R4D46 'RES_0402-22.1,1.0%,1/16W,CHIP,A':
 ROOM='PVCCIO_CPU1';

SECTION_NUMBER 1
 '@BASEBOARD_FAB2_LIB.BASEBOARD_FAB2(SCH_1):PAGE213_I13@MSTR_DISCRETE.RES(CHIPS)':
 C_PATH='@baseboard_fab2_lib.baseboard_fab2(sch_1):page213_i13@mstr_discrete.res~
(chips)',
 P_PATH='@baseboard_fab2_lib.baseboard_fab2(sch_1):page213_i13@mstr_discrete.res~
(chips)',
 PATH='I13',
 DRAWING='@BASEBOARD_FAB2_LIB.BASEBOARD_FAB2(SCH_1):PAGE213',
 WATTAGE='1/16W',
 TOLERANCE='1.0%',
 SEC_TYPE='0402',
 MATERIAL='CHIP',
 PHYS_PAGE='213',
 XY='(1950,3575)',
 ROT='0',
 VER='1',
 VALUE='22.1',
 PACK_TYPE='0402',
 PART_NUMBER='G21796-250',
 LOCATION='R4D46',
 ROOM='PVCCIO_CPU1',
 SEC='1',
 CDS_LIB='mstr_discrete',
 CDS_PART_NAME='RES_0402-22.1,1.0%,1/16W,CHIP,A',
 PRIM_FILE='./archive_libs/mstr_discrete/res/chips/chips.prt';

PART_NAME
 R4D47 'RES_0402-0.0,5%,1/16W,CHIP,G21A':
 ROOM='PVCCIO_CPU1';

SECTION_NUMBER 1
 '@BASEBOARD_FAB2_LIB.BASEBOARD_FAB2(SCH_1):PAGE213_I25@MSTR_DISCRETE.RES(CHIPS)':
 C_PATH='@baseboard_fab2_lib.baseboard_fab2(sch_1):page213_i25@mstr_discrete.res~
(chips)',
 P_PATH='@baseboard_fab2_lib.baseboard_fab2(sch_1):page213_i25@mstr_discrete.res~
(chips)',
 PATH='I25',
 DRAWING='@BASEBOARD_FAB2_LIB.BASEBOARD_FAB2(SCH_1):PAGE213',
 WATTAGE='1/16W',
 TOLERANCE='5%',
 SEC_TYPE='0402',
 MATERIAL='CHIP',
 PHYS_PAGE='213',
 XY='(-550,4500)',
 ROT='0',
 VER='2',
 VALUE='0.0',
 PACK_TYPE='0402',
 PART_NUMBER='G21497-005',
 LOCATION='R4D47',
 ROOM='PVCCIO_CPU1',
 SEC='1',
 CDS_LIB='mstr_discrete',
 CDS_PART_NAME='RES_0402-0.0,5%,1/16W,CHIP,G21A',
 PRIM_FILE='./archive_libs/mstr_discrete/res/chips/chips.prt';

PART_NAME
 R4D49 'RES_0402-1.00K,1%,1/16W,CHIP,GA':;

SECTION_NUMBER 1
 '@BASEBOARD_FAB2_LIB.BASEBOARD_FAB2(SCH_1):PAGE213_I63@MSTR_DISCRETE.RES(CHIPS)':
 C_PATH='@baseboard_fab2_lib.baseboard_fab2(sch_1):page213_i63@mstr_discrete.res~
(chips)',
 P_PATH='@baseboard_fab2_lib.baseboard_fab2(sch_1):page213_i63@mstr_discrete.res~
(chips)',
 PATH='I63',
 DRAWING='@BASEBOARD_FAB2_LIB.BASEBOARD_FAB2(SCH_1):PAGE213',
 WATTAGE='1/16W',
 TOLERANCE='1%',
 SEC_TYPE='0402',
 MATERIAL='CHIP',
 PHYS_PAGE='213',
 XY='(2175,4050)',
 ROT='0',
 VER='2',
 VALUE='1.00K',
 PACK_TYPE='0402',
 PART_NUMBER='G21796-026',
 LOCATION='R4D49',
 SEC='1',
 CDS_LIB='mstr_discrete',
 CDS_PART_NAME='RES_0402-1.00K,1%,1/16W,CHIP,GA',
 PRIM_FILE='./archive_libs/mstr_discrete/res/chips/chips.prt';

PART_NAME
 R4D51 'RES_0402-150.0,1%,1/16W,CHIP,GA':
 ROOM='PVCCIO_CPU1';

SECTION_NUMBER 1
 '@BASEBOARD_FAB2_LIB.BASEBOARD_FAB2(SCH_1):PAGE213_I46@MSTR_DISCRETE.RES(CHIPS)':
 C_PATH='@baseboard_fab2_lib.baseboard_fab2(sch_1):page213_i46@mstr_discrete.res~
(chips)',
 P_PATH='@baseboard_fab2_lib.baseboard_fab2(sch_1):page213_i46@mstr_discrete.res~
(chips)',
 PATH='I46',
 DRAWING='@BASEBOARD_FAB2_LIB.BASEBOARD_FAB2(SCH_1):PAGE213',
 WATTAGE='1/16W',
 TOLERANCE='1%',
 SEC_TYPE='0402',
 MATERIAL='CHIP',
 PHYS_PAGE='213',
 XY='(-1825,3925)',
 ROT='0',
 VER='1',
 VALUE='150.0',
 PACK_TYPE='0402',
 PART_NUMBER='G21796-009',
 LOCATION='R4D51',
 ROOM='PVCCIO_CPU1',
 SEC='1',
 CDS_LIB='mstr_discrete',
 CDS_PART_NAME='RES_0402-150.0,1%,1/16W,CHIP,GA',
 PRIM_FILE='./archive_libs/mstr_discrete/res/chips/chips.prt';

PART_NAME
 R4D54 'RES_0402-0.0,5%,1/16W,CHIP,G21A':
 ROOM='PVCCIO_CPU1';

SECTION_NUMBER 1
 '@BASEBOARD_FAB2_LIB.BASEBOARD_FAB2(SCH_1):PAGE213_I37@MSTR_DISCRETE.RES(CHIPS)':
 C_PATH='@baseboard_fab2_lib.baseboard_fab2(sch_1):page213_i37@mstr_discrete.res~
(chips)',
 P_PATH='@baseboard_fab2_lib.baseboard_fab2(sch_1):page213_i37@mstr_discrete.res~
(chips)',
 PATH='I37',
 DRAWING='@BASEBOARD_FAB2_LIB.BASEBOARD_FAB2(SCH_1):PAGE213',
 WATTAGE='1/16W',
 TOLERANCE='5%',
 SEC_TYPE='0402',
 MATERIAL='CHIP',
 PHYS_PAGE='213',
 XY='(-1175,2925)',
 ROT='0',
 VER='1',
 VALUE='0.0',
 PACK_TYPE='0402',
 PART_NUMBER='G21497-005',
 LOCATION='R4D54',
 ROOM='PVCCIO_CPU1',
 SEC='1',
 CDS_LIB='mstr_discrete',
 CDS_PART_NAME='RES_0402-0.0,5%,1/16W,CHIP,G21A',
 PRIM_FILE='./archive_libs/mstr_discrete/res/chips/chips.prt';

PART_NAME
 R4D56 'RES_0402-0.0,5%,1/16W,CHIP,G21A':
 ROOM='PVCCIO_CPU1';

SECTION_NUMBER 1
 '@BASEBOARD_FAB2_LIB.BASEBOARD_FAB2(SCH_1):PAGE213_I16@MSTR_DISCRETE.RES(CHIPS)':
 C_PATH='@baseboard_fab2_lib.baseboard_fab2(sch_1):page213_i16@mstr_discrete.res~
(chips)',
 P_PATH='@baseboard_fab2_lib.baseboard_fab2(sch_1):page213_i16@mstr_discrete.res~
(chips)',
 PATH='I16',
 DRAWING='@BASEBOARD_FAB2_LIB.BASEBOARD_FAB2(SCH_1):PAGE213',
 WATTAGE='1/16W',
 TOLERANCE='5%',
 SEC_TYPE='0402',
 MATERIAL='CHIP',
 PHYS_PAGE='213',
 XY='(1450,3125)',
 ROT='0',
 VER='1',
 VALUE='0.0',
 PACK_TYPE='0402',
 PART_NUMBER='G21497-005',
 LOCATION='R4D56',
 ROOM='PVCCIO_CPU1',
 SEC='1',
 CDS_LIB='mstr_discrete',
 CDS_PART_NAME='RES_0402-0.0,5%,1/16W,CHIP,G21A',
 PRIM_FILE='./archive_libs/mstr_discrete/res/chips/chips.prt';

PART_NAME
 R4D57 'RES_0402-1.5K,1%,1/16W,CHIP,G2A':
 ROOM='PVCCIO_CPU1';

SECTION_NUMBER 1
 '@BASEBOARD_FAB2_LIB.BASEBOARD_FAB2(SCH_1):PAGE213_I32@MSTR_DISCRETE.RES(CHIPS)':
 C_PATH='@baseboard_fab2_lib.baseboard_fab2(sch_1):page213_i32@mstr_discrete.res~
(chips)',
 P_PATH='@baseboard_fab2_lib.baseboard_fab2(sch_1):page213_i32@mstr_discrete.res~
(chips)',
 PATH='I32',
 DRAWING='@BASEBOARD_FAB2_LIB.BASEBOARD_FAB2(SCH_1):PAGE213',
 WATTAGE='1/16W',
 TOLERANCE='1%',
 SEC_TYPE='0402',
 MATERIAL='CHIP',
 PHYS_PAGE='213',
 XY='(-2425,4250)',
 ROT='0',
 VER='2',
 VALUE='1.5K',
 PACK_TYPE='0402',
 PART_NUMBER='G21796-003',
 LOCATION='R4D57',
 ROOM='PVCCIO_CPU1',
 SEC='1',
 CDS_LIB='mstr_discrete',
 CDS_PART_NAME='RES_0402-1.5K,1%,1/16W,CHIP,G2A',
 PRIM_FILE='./archive_libs/mstr_discrete/res/chips/chips.prt';

PART_NAME
 R4D58 'RES_0402-1.00K,1%,1/16W,CHIP,GA':
 ROOM='PVCCIN_CPU0_VR';

SECTION_NUMBER 1
 '@BASEBOARD_FAB2_LIB.BASEBOARD_FAB2(SCH_1):PAGE201_I25@MSTR_DISCRETE.RES(CHIPS)':
 C_PATH='@baseboard_fab2_lib.baseboard_fab2(sch_1):page201_i25@mstr_discrete.res~
(chips)',
 P_PATH='@baseboard_fab2_lib.baseboard_fab2(sch_1):page201_i25@mstr_discrete.res~
(chips)',
 PATH='I25',
 DRAWING='@BASEBOARD_FAB2_LIB.BASEBOARD_FAB2(SCH_1):PAGE201',
 WATTAGE='1/16W',
 TOLERANCE='1%',
 SEC_TYPE='0402',
 MATERIAL='CHIP',
 PHYS_PAGE='201',
 XY='(-2500,3925)',
 ROT='0',
 VER='2',
 VALUE='1.00K',
 PACK_TYPE='0402',
 PART_NUMBER='G21796-026',
 LOCATION='R4D58',
 ROOM='PVCCIN_CPU0_VR',
 SEC='1',
 CDS_LIB='mstr_discrete',
 CDS_PART_NAME='RES_0402-1.00K,1%,1/16W,CHIP,GA',
 PRIM_FILE='./archive_libs/mstr_discrete/res/chips/chips.prt';

PART_NAME
 R4D60 'RES_0402-100.0K,1%,1/16W,CHIP,B':
 ROOM='PVCCIO_CPU1';

SECTION_NUMBER 1
 '@BASEBOARD_FAB2_LIB.BASEBOARD_FAB2(SCH_1):PAGE213_I31@MSTR_DISCRETE.RES(CHIPS)':
 C_PATH='@baseboard_fab2_lib.baseboard_fab2(sch_1):page213_i31@mstr_discrete.res~
(chips)',
 P_PATH='@baseboard_fab2_lib.baseboard_fab2(sch_1):page213_i31@mstr_discrete.res~
(chips)',
 PATH='I31',
 DRAWING='@BASEBOARD_FAB2_LIB.BASEBOARD_FAB2(SCH_1):PAGE213',
 WATTAGE='1/16W',
 TOLERANCE='1%',
 SEC_TYPE='0402',
 MATERIAL='CHIP',
 PHYS_PAGE='213',
 XY='(-2425,4700)',
 ROT='0',
 VER='2',
 VALUE='100.0K',
 PACK_TYPE='0402',
 PART_NUMBER='G21796-160',
 LOCATION='R4D60',
 ROOM='PVCCIO_CPU1',
 SEC='1',
 CDS_LIB='mstr_discrete',
 CDS_PART_NAME='RES_0402-100.0K,1%,1/16W,CHIP,B',
 PRIM_FILE='./archive_libs/mstr_discrete/res/chips/chips.prt';

PART_NAME
 R4D63 'RES_0402-22.1,1.0%,1/16W,CHIP,A':
 ROOM='PVCCIN_CPU0_VR';

SECTION_NUMBER 1
 '@BASEBOARD_FAB2_LIB.BASEBOARD_FAB2(SCH_1):PAGE201_I124@MSTR_DISCRETE.RES(CHIPS)':
 C_PATH='@baseboard_fab2_lib.baseboard_fab2(sch_1):page201_i124@mstr_discrete.re~
s(chips)',
 P_PATH='@baseboard_fab2_lib.baseboard_fab2(sch_1):page201_i124@mstr_discrete.re~
s(chips)',
 PATH='I124',
 DRAWING='@BASEBOARD_FAB2_LIB.BASEBOARD_FAB2(SCH_1):PAGE201',
 WATTAGE='1/16W',
 TOLERANCE='1.0%',
 SEC_TYPE='0402',
 MATERIAL='CHIP',
 PHYS_PAGE='201',
 XY='(-1125,3325)',
 ROT='0',
 VER='1',
 VALUE='22.1',
 PACK_TYPE='0402',
 PART_NUMBER='G21796-250',
 LOCATION='R4D63',
 ROOM='PVCCIN_CPU0_VR',
 SEC='1',
 CDS_LIB='mstr_discrete',
 CDS_PART_NAME='RES_0402-22.1,1.0%,1/16W,CHIP,A',
 PRIM_FILE='./archive_libs/mstr_discrete/res/chips/chips.prt';

PART_NAME
 R4D64 'RES_0402-3.16K,1%,1/16W,CHIP,GA':
 ROOM='PVCCIN_CPU1_VR';

SECTION_NUMBER 1
 '@BASEBOARD_FAB2_LIB.BASEBOARD_FAB2(SCH_1):PAGE213_I104@MSTR_DISCRETE.RES(CHIPS)':
 C_PATH='@baseboard_fab2_lib.baseboard_fab2(sch_1):page213_i104@mstr_discrete.re~
s(chips)',
 P_PATH='@baseboard_fab2_lib.baseboard_fab2(sch_1):page213_i104@mstr_discrete.re~
s(chips)',
 PATH='I104',
 DRAWING='@BASEBOARD_FAB2_LIB.BASEBOARD_FAB2(SCH_1):PAGE213',
 WATTAGE='1/16W',
 TOLERANCE='1%',
 SEC_TYPE='0402',
 MATERIAL='CHIP',
 PHYS_PAGE='213',
 XY='(-850,1175)',
 ROT='0',
 VER='2',
 VALUE='3.16K',
 PACK_TYPE='0402',
 PART_NUMBER='G21796-043',
 LOCATION='R4D64',
 ROOM='PVCCIN_CPU1_VR',
 SEC='1',
 CDS_LIB='mstr_discrete',
 CDS_PART_NAME='RES_0402-3.16K,1%,1/16W,CHIP,GA',
 PRIM_FILE='./archive_libs/mstr_discrete/res/chips/chips.prt';

PART_NAME
 R4D65 'RES_0402-33.2,1%,1/16W,CHIP,G2A':;

SECTION_NUMBER 1
 '@BASEBOARD_FAB2_LIB.BASEBOARD_FAB2(SCH_1):PAGE201_I127@MSTR_DISCRETE.RES(CHIPS)':
 C_PATH='@baseboard_fab2_lib.baseboard_fab2(sch_1):page201_i127@mstr_discrete.re~
s(chips)',
 P_PATH='@baseboard_fab2_lib.baseboard_fab2(sch_1):page201_i127@mstr_discrete.re~
s(chips)',
 PATH='I127',
 DRAWING='@BASEBOARD_FAB2_LIB.BASEBOARD_FAB2(SCH_1):PAGE201',
 WATTAGE='1/16W',
 TOLERANCE='1%',
 SEC_TYPE='0402',
 MATERIAL='CHIP',
 PHYS_PAGE='201',
 XY='(-1800,2675)',
 ROT='0',
 VER='1',
 VALUE='33.2',
 PACK_TYPE='0402',
 PART_NUMBER='G21796-074',
 LOCATION='R4D65',
 SEC='1',
 CDS_LIB='mstr_discrete',
 CDS_PART_NAME='RES_0402-33.2,1%,1/16W,CHIP,G2A',
 PRIM_FILE='./archive_libs/mstr_discrete/res/chips/chips.prt';

PART_NAME
 R4D66 'RES_0402-0.0,5%,1/16W,CHIP,G21A':
 ROOM='PVCCIN_CPU0_VR';

SECTION_NUMBER 1
 '@BASEBOARD_FAB2_LIB.BASEBOARD_FAB2(SCH_1):PAGE201_I98@MSTR_DISCRETE.RES(CHIPS)':
 C_PATH='@baseboard_fab2_lib.baseboard_fab2(sch_1):page201_i98@mstr_discrete.res~
(chips)',
 P_PATH='@baseboard_fab2_lib.baseboard_fab2(sch_1):page201_i98@mstr_discrete.res~
(chips)',
 PATH='I98',
 DRAWING='@BASEBOARD_FAB2_LIB.BASEBOARD_FAB2(SCH_1):PAGE201',
 WATTAGE='1/16W',
 TOLERANCE='5%',
 SEC_TYPE='0402',
 MATERIAL='CHIP',
 PHYS_PAGE='201',
 XY='(-2400,2725)',
 ROT='0',
 VER='1',
 VALUE='0.0',
 PACK_TYPE='0402',
 PART_NUMBER='G21497-005',
 LOCATION='R4D66',
 ROOM='PVCCIN_CPU0_VR',
 SEC='1',
 CDS_LIB='mstr_discrete',
 CDS_PART_NAME='RES_0402-0.0,5%,1/16W,CHIP,G21A',
 PRIM_FILE='./archive_libs/mstr_discrete/res/chips/chips.prt';

PART_NAME
 R4D67 'RES_0402-0.0,5%,1/16W,CHIP,G21A':
 ROOM='PVCCIN_CPU0_VR';

SECTION_NUMBER 1
 '@BASEBOARD_FAB2_LIB.BASEBOARD_FAB2(SCH_1):PAGE201_I26@MSTR_DISCRETE.RES(CHIPS)':
 C_PATH='@baseboard_fab2_lib.baseboard_fab2(sch_1):page201_i26@mstr_discrete.res~
(chips)',
 P_PATH='@baseboard_fab2_lib.baseboard_fab2(sch_1):page201_i26@mstr_discrete.res~
(chips)',
 PATH='I26',
 DRAWING='@BASEBOARD_FAB2_LIB.BASEBOARD_FAB2(SCH_1):PAGE201',
 WATTAGE='1/16W',
 TOLERANCE='5%',
 SEC_TYPE='0402',
 MATERIAL='CHIP',
 PHYS_PAGE='201',
 XY='(-2025,2875)',
 ROT='0',
 VER='1',
 VALUE='0.0',
 PACK_TYPE='0402',
 PART_NUMBER='G21497-005',
 LOCATION='R4D67',
 ROOM='PVCCIN_CPU0_VR',
 SEC='1',
 CDS_LIB='mstr_discrete',
 CDS_PART_NAME='RES_0402-0.0,5%,1/16W,CHIP,G21A',
 PRIM_FILE='./archive_libs/mstr_discrete/res/chips/chips.prt';

PART_NAME
 R4D68 'RES_0402-68.1K,1%,1/16W,EMPTY,A':;

SECTION_NUMBER 1
 '@BASEBOARD_FAB2_LIB.BASEBOARD_FAB2(SCH_1):PAGE204_I83@MSTR_DISCRETE.RES(CHIPS)':
 C_PATH='@baseboard_fab2_lib.baseboard_fab2(sch_1):page204_i83@mstr_discrete.res~
(chips)',
 P_PATH='@baseboard_fab2_lib.baseboard_fab2(sch_1):page204_i83@mstr_discrete.res~
(chips)',
 PATH='I83',
 DRAWING='@BASEBOARD_FAB2_LIB.BASEBOARD_FAB2(SCH_1):PAGE204',
 WATTAGE='1/16W',
 TOLERANCE='1%',
 SEC_TYPE='0402',
 MATERIAL='EMPTY',
 PHYS_PAGE='204',
 XY='(-400,4075)',
 ROT='0',
 VER='2',
 VALUE='68.1K',
 PACK_TYPE='0402',
 PART_NUMBER='G21796-187',
 LOCATION='R4D68',
 SEC='1',
 CDS_LIB='mstr_discrete',
 CDS_PART_NAME='RES_0402-68.1K,1%,1/16W,EMPTY,A',
 PRIM_FILE='./archive_libs/mstr_discrete/res/chips/chips.prt';

PART_NAME
 R4D69 'RES_0402-4.75K,1%,1/16W,CHIP,GA':
 ROOM='DB1200ZL',
 SIGNAL_MODEL='DEFAULT_RESISTOR_47000OHM_2_1';

SECTION_NUMBER 1
 '@BASEBOARD_FAB2_LIB.BASEBOARD_FAB2(SCH_1):PAGE102_I93@MSTR_DISCRETE.RES(CHIPS)':
 C_PATH='@baseboard_fab2_lib.baseboard_fab2(sch_1):page102_i93@mstr_discrete.res~
(chips)',
 P_PATH='@baseboard_fab2_lib.baseboard_fab2(sch_1):page102_i93@mstr_discrete.res~
(chips)',
 PATH='I93',
 DRAWING='@BASEBOARD_FAB2_LIB.BASEBOARD_FAB2(SCH_1):PAGE102',
 WATTAGE='1/16W',
 TOLERANCE='1%',
 SEC_TYPE='0402',
 MATERIAL='CHIP',
 BOM_COST='SYS_CLOCK',
 PHYS_PAGE='102',
 XY='(-125,1075)',
 ROT='2',
 VER='2',
 VALUE='4.75K',
 PACK_TYPE='0402',
 PART_NUMBER='G21796-072',
 LOCATION='R4D69',
 SIGNAL_MODEL='DEFAULT_RESISTOR_47000OHM_2_1',
 ROOM='DB1200ZL',
 SEC='1',
 CDS_LIB='mstr_discrete',
 CDS_PART_NAME='RES_0402-4.75K,1%,1/16W,CHIP,GA',
 PRIM_FILE='./archive_libs/mstr_discrete/res/chips/chips.prt';

PART_NAME
 R4D70 'RES_0402-4.75K,1%,1/16W,CHIP,GA':
 ROOM='DB1200ZL',
 SIGNAL_MODEL='DEFAULT_RESISTOR_47000OHM_2_1';

SECTION_NUMBER 1
 '@BASEBOARD_FAB2_LIB.BASEBOARD_FAB2(SCH_1):PAGE102_I94@MSTR_DISCRETE.RES(CHIPS)':
 C_PATH='@baseboard_fab2_lib.baseboard_fab2(sch_1):page102_i94@mstr_discrete.res~
(chips)',
 P_PATH='@baseboard_fab2_lib.baseboard_fab2(sch_1):page102_i94@mstr_discrete.res~
(chips)',
 PATH='I94',
 DRAWING='@BASEBOARD_FAB2_LIB.BASEBOARD_FAB2(SCH_1):PAGE102',
 WATTAGE='1/16W',
 TOLERANCE='1%',
 SEC_TYPE='0402',
 MATERIAL='CHIP',
 BOM_COST='SYS_CLOCK',
 PHYS_PAGE='102',
 XY='(200,1075)',
 ROT='2',
 VER='2',
 VALUE='4.75K',
 PACK_TYPE='0402',
 PART_NUMBER='G21796-072',
 LOCATION='R4D70',
 SIGNAL_MODEL='DEFAULT_RESISTOR_47000OHM_2_1',
 ROOM='DB1200ZL',
 SEC='1',
 CDS_LIB='mstr_discrete',
 CDS_PART_NAME='RES_0402-4.75K,1%,1/16W,CHIP,GA',
 PRIM_FILE='./archive_libs/mstr_discrete/res/chips/chips.prt';

PART_NAME
 R4D71 'RES_0402-68.1K,1%,1/16W,EMPTY,A':;

SECTION_NUMBER 1
 '@BASEBOARD_FAB2_LIB.BASEBOARD_FAB2(SCH_1):PAGE203_I91@MSTR_DISCRETE.RES(CHIPS)':
 C_PATH='@baseboard_fab2_lib.baseboard_fab2(sch_1):page203_i91@mstr_discrete.res~
(chips)',
 P_PATH='@baseboard_fab2_lib.baseboard_fab2(sch_1):page203_i91@mstr_discrete.res~
(chips)',
 PATH='I91',
 DRAWING='@BASEBOARD_FAB2_LIB.BASEBOARD_FAB2(SCH_1):PAGE203',
 WATTAGE='1/16W',
 TOLERANCE='1%',
 SEC_TYPE='0402',
 MATERIAL='EMPTY',
 PHYS_PAGE='203',
 XY='(-375,1400)',
 ROT='0',
 VER='2',
 VALUE='68.1K',
 PACK_TYPE='0402',
 PART_NUMBER='G21796-187',
 LOCATION='R4D71',
 SEC='1',
 CDS_LIB='mstr_discrete',
 CDS_PART_NAME='RES_0402-68.1K,1%,1/16W,EMPTY,A',
 PRIM_FILE='./archive_libs/mstr_discrete/res/chips/chips.prt';

PART_NAME
 R4D72 'RES_0402-68.1K,1%,1/16W,EMPTY,A':;

SECTION_NUMBER 1
 '@BASEBOARD_FAB2_LIB.BASEBOARD_FAB2(SCH_1):PAGE203_I89@MSTR_DISCRETE.RES(CHIPS)':
 C_PATH='@baseboard_fab2_lib.baseboard_fab2(sch_1):page203_i89@mstr_discrete.res~
(chips)',
 P_PATH='@baseboard_fab2_lib.baseboard_fab2(sch_1):page203_i89@mstr_discrete.res~
(chips)',
 PATH='I89',
 DRAWING='@BASEBOARD_FAB2_LIB.BASEBOARD_FAB2(SCH_1):PAGE203',
 WATTAGE='1/16W',
 TOLERANCE='1%',
 SEC_TYPE='0402',
 MATERIAL='EMPTY',
 PHYS_PAGE='203',
 XY='(-400,4100)',
 ROT='0',
 VER='2',
 VALUE='68.1K',
 PACK_TYPE='0402',
 PART_NUMBER='G21796-187',
 LOCATION='R4D72',
 SEC='1',
 CDS_LIB='mstr_discrete',
 CDS_PART_NAME='RES_0402-68.1K,1%,1/16W,EMPTY,A',
 PRIM_FILE='./archive_libs/mstr_discrete/res/chips/chips.prt';

PART_NAME
 R4E2 'RES_0402-3.16K,1%,1/16W,CHIP,GA':
 ROOM='PVCCIN_CPU1_VR';

SECTION_NUMBER 1
 '@BASEBOARD_FAB2_LIB.BASEBOARD_FAB2(SCH_1):PAGE213_I103@MSTR_DISCRETE.RES(CHIPS)':
 C_PATH='@baseboard_fab2_lib.baseboard_fab2(sch_1):page213_i103@mstr_discrete.re~
s(chips)',
 P_PATH='@baseboard_fab2_lib.baseboard_fab2(sch_1):page213_i103@mstr_discrete.re~
s(chips)',
 PATH='I103',
 DRAWING='@BASEBOARD_FAB2_LIB.BASEBOARD_FAB2(SCH_1):PAGE213',
 WATTAGE='1/16W',
 TOLERANCE='1%',
 SEC_TYPE='0402',
 MATERIAL='CHIP',
 PHYS_PAGE='213',
 XY='(-525,1175)',
 ROT='0',
 VER='2',
 VALUE='3.16K',
 PACK_TYPE='0402',
 PART_NUMBER='G21796-043',
 LOCATION='R4E2',
 ROOM='PVCCIN_CPU1_VR',
 SEC='1',
 CDS_LIB='mstr_discrete',
 CDS_PART_NAME='RES_0402-3.16K,1%,1/16W,CHIP,GA',
 PRIM_FILE='./archive_libs/mstr_discrete/res/chips/chips.prt';

PART_NAME
 R4E3 'RES_0402-1.00K,1%,1/16W,CHIP,GA':
 ROOM='PVCCIN_CPU0_VR';

SECTION_NUMBER 1
 '@BASEBOARD_FAB2_LIB.BASEBOARD_FAB2(SCH_1):PAGE201_I111@MSTR_DISCRETE.RES(CHIPS)':
 C_PATH='@baseboard_fab2_lib.baseboard_fab2(sch_1):page201_i111@mstr_discrete.re~
s(chips)',
 P_PATH='@baseboard_fab2_lib.baseboard_fab2(sch_1):page201_i111@mstr_discrete.re~
s(chips)',
 PATH='I111',
 DRAWING='@BASEBOARD_FAB2_LIB.BASEBOARD_FAB2(SCH_1):PAGE201',
 WATTAGE='1/16W',
 TOLERANCE='1%',
 SEC_TYPE='0402',
 MATERIAL='CHIP',
 PHYS_PAGE='201',
 XY='(-3050,4125)',
 ROT='2',
 VER='2',
 VALUE='1.00K',
 PACK_TYPE='0402',
 PART_NUMBER='G21796-026',
 LOCATION='R4E3',
 ROOM='PVCCIN_CPU0_VR',
 SEC='1',
 CDS_LIB='mstr_discrete',
 CDS_PART_NAME='RES_0402-1.00K,1%,1/16W,CHIP,GA',
 PRIM_FILE='./archive_libs/mstr_discrete/res/chips/chips.prt';

PART_NAME
 R4E4 'RES_0402-1.00K,1%,1/16W,CHIP,GA':
 ROOM='PVCCIN_CPU0_VR';

SECTION_NUMBER 1
 '@BASEBOARD_FAB2_LIB.BASEBOARD_FAB2(SCH_1):PAGE201_I187@MSTR_DISCRETE.RES(CHIPS)':
 C_PATH='@baseboard_fab2_lib.baseboard_fab2(sch_1):page201_i187@mstr_discrete.re~
s(chips)',
 P_PATH='@baseboard_fab2_lib.baseboard_fab2(sch_1):page201_i187@mstr_discrete.re~
s(chips)',
 PATH='I187',
 DRAWING='@BASEBOARD_FAB2_LIB.BASEBOARD_FAB2(SCH_1):PAGE201',
 WATTAGE='1/16W',
 TOLERANCE='1%',
 SEC_TYPE='0402',
 MATERIAL='CHIP',
 PHYS_PAGE='201',
 XY='(-1925,4100)',
 ROT='2',
 VER='2',
 VALUE='1.00K',
 PACK_TYPE='0402',
 PART_NUMBER='G21796-026',
 LOCATION='R4E4',
 ROOM='PVCCIN_CPU0_VR',
 SEC='1',
 CDS_LIB='mstr_discrete',
 CDS_PART_NAME='RES_0402-1.00K,1%,1/16W,CHIP,GA',
 PRIM_FILE='./archive_libs/mstr_discrete/res/chips/chips.prt';

PART_NAME
 R4E5 'RES_0402-1.00K,1%,1/16W,CHIP,GA':
 ROOM='PVCCIN_CPU0_VR';

SECTION_NUMBER 1
 '@BASEBOARD_FAB2_LIB.BASEBOARD_FAB2(SCH_1):PAGE201_I27@MSTR_DISCRETE.RES(CHIPS)':
 C_PATH='@baseboard_fab2_lib.baseboard_fab2(sch_1):page201_i27@mstr_discrete.res~
(chips)',
 P_PATH='@baseboard_fab2_lib.baseboard_fab2(sch_1):page201_i27@mstr_discrete.res~
(chips)',
 PATH='I27',
 DRAWING='@BASEBOARD_FAB2_LIB.BASEBOARD_FAB2(SCH_1):PAGE201',
 WATTAGE='1/16W',
 TOLERANCE='1%',
 SEC_TYPE='0402',
 MATERIAL='CHIP',
 PHYS_PAGE='201',
 XY='(-2775,3925)',
 ROT='2',
 VER='2',
 VALUE='1.00K',
 PACK_TYPE='0402',
 PART_NUMBER='G21796-026',
 LOCATION='R4E5',
 ROOM='PVCCIN_CPU0_VR',
 SEC='1',
 CDS_LIB='mstr_discrete',
 CDS_PART_NAME='RES_0402-1.00K,1%,1/16W,CHIP,GA',
 PRIM_FILE='./archive_libs/mstr_discrete/res/chips/chips.prt';

PART_NAME
 R4E6 'RES_0402-150.0,1%,1/16W,CHIP,GA':
 ROOM='PVCCIN_CPU0_VR';

SECTION_NUMBER 1
 '@BASEBOARD_FAB2_LIB.BASEBOARD_FAB2(SCH_1):PAGE201_I56@MSTR_DISCRETE.RES(CHIPS)':
 C_PATH='@baseboard_fab2_lib.baseboard_fab2(sch_1):page201_i56@mstr_discrete.res~
(chips)',
 P_PATH='@baseboard_fab2_lib.baseboard_fab2(sch_1):page201_i56@mstr_discrete.res~
(chips)',
 PATH='I56',
 DRAWING='@BASEBOARD_FAB2_LIB.BASEBOARD_FAB2(SCH_1):PAGE201',
 WATTAGE='1/16W',
 TOLERANCE='1%',
 SEC_TYPE='0402',
 MATERIAL='CHIP',
 PHYS_PAGE='201',
 XY='(-5400,3950)',
 ROT='0',
 VER='1',
 VALUE='150.0',
 PACK_TYPE='0402',
 PART_NUMBER='G21796-009',
 LOCATION='R4E6',
 ROOM='PVCCIN_CPU0_VR',
 SEC='1',
 CDS_LIB='mstr_discrete',
 CDS_PART_NAME='RES_0402-150.0,1%,1/16W,CHIP,GA',
 PRIM_FILE='./archive_libs/mstr_discrete/res/chips/chips.prt';

PART_NAME
 R4E7 'RES_0402-10.0,1%,1/16W,CHIP,G2A':
 ROOM='PVCCIO_CPU1';

SECTION_NUMBER 1
 '@BASEBOARD_FAB2_LIB.BASEBOARD_FAB2(SCH_1):PAGE213_I84@MSTR_DISCRETE.RES(CHIPS)':
 C_PATH='@baseboard_fab2_lib.baseboard_fab2(sch_1):page213_i84@mstr_discrete.res~
(chips)',
 P_PATH='@baseboard_fab2_lib.baseboard_fab2(sch_1):page213_i84@mstr_discrete.res~
(chips)',
 PATH='I84',
 DRAWING='@BASEBOARD_FAB2_LIB.BASEBOARD_FAB2(SCH_1):PAGE213',
 WATTAGE='1/16W',
 TOLERANCE='1%',
 SEC_TYPE='0402',
 MATERIAL='CHIP',
 PHYS_PAGE='213',
 XY='(-2325,1925)',
 ROT='0',
 VER='1',
 VALUE='10.0',
 PACK_TYPE='0402',
 PART_NUMBER='G21796-066',
 LOCATION='R4E7',
 ROOM='PVCCIO_CPU1',
 SEC='1',
 CDS_LIB='mstr_discrete',
 CDS_PART_NAME='RES_0402-10.0,1%,1/16W,CHIP,G2A',
 PRIM_FILE='./archive_libs/mstr_discrete/res/chips/chips.prt';

PART_NAME
 R4E8 'RES_0402-10.0,1%,1/16W,CHIP,G2A':
 ROOM='PVCCIN_CPU0_VR',
 NO_XNET_CONNECTION='1';

SECTION_NUMBER 1
 '@BASEBOARD_FAB2_LIB.BASEBOARD_FAB2(SCH_1):PAGE201_I109@MSTR_DISCRETE.RES(CHIPS)':
 C_PATH='@baseboard_fab2_lib.baseboard_fab2(sch_1):page201_i109@mstr_discrete.re~
s(chips)',
 P_PATH='@baseboard_fab2_lib.baseboard_fab2(sch_1):page201_i109@mstr_discrete.re~
s(chips)',
 PATH='I109',
 DRAWING='@BASEBOARD_FAB2_LIB.BASEBOARD_FAB2(SCH_1):PAGE201',
 WATTAGE='1/16W',
 TOLERANCE='1%',
 SEC_TYPE='0402',
 MATERIAL='CHIP',
 NO_XNET_CONNECTION='1',
 PHYS_PAGE='201',
 XY='(-6675,2525)',
 ROT='0',
 VER='1',
 VALUE='10.0',
 PACK_TYPE='0402',
 PART_NUMBER='G21796-066',
 LOCATION='R4E8',
 ROOM='PVCCIN_CPU0_VR',
 SEC='1',
 CDS_LIB='mstr_discrete',
 CDS_PART_NAME='RES_0402-10.0,1%,1/16W,CHIP,G2A',
 PRIM_FILE='./archive_libs/mstr_discrete/res/chips/chips.prt';

PART_NAME
 R4E9 'RES_0402-49.9,1%,1/16W,EMPTY,GA':
 ROOM='PVCCIO_CPU0';

SECTION_NUMBER 1
 '@BASEBOARD_FAB2_LIB.BASEBOARD_FAB2(SCH_1):PAGE201_I189@MSTR_DISCRETE.RES(CHIPS)':
 C_PATH='@baseboard_fab2_lib.baseboard_fab2(sch_1):page201_i189@mstr_discrete.re~
s(chips)',
 P_PATH='@baseboard_fab2_lib.baseboard_fab2(sch_1):page201_i189@mstr_discrete.re~
s(chips)',
 PATH='I189',
 DRAWING='@BASEBOARD_FAB2_LIB.BASEBOARD_FAB2(SCH_1):PAGE201',
 WATTAGE='1/16W',
 TOLERANCE='1%',
 SEC_TYPE='0402',
 MATERIAL='EMPTY',
 PHYS_PAGE='201',
 XY='(-5650,4275)',
 ROT='0',
 VER='2',
 VALUE='49.9',
 PACK_TYPE='0402',
 PART_NUMBER='G21796-047',
 LOCATION='R4E9',
 ROOM='PVCCIO_CPU0',
 SEC='1',
 CDS_LIB='mstr_discrete',
 CDS_PART_NAME='RES_0402-49.9,1%,1/16W,EMPTY,GA',
 PRIM_FILE='./archive_libs/mstr_discrete/res/chips/chips.prt';

PART_NAME
 R4E10 'RES_0402-100.0,1%,1/16W,EMPTY,A':
 ROOM='PVCCIO_CPU0';

SECTION_NUMBER 1
 '@BASEBOARD_FAB2_LIB.BASEBOARD_FAB2(SCH_1):PAGE201_I190@MSTR_DISCRETE.RES(CHIPS)':
 C_PATH='@baseboard_fab2_lib.baseboard_fab2(sch_1):page201_i190@mstr_discrete.re~
s(chips)',
 P_PATH='@baseboard_fab2_lib.baseboard_fab2(sch_1):page201_i190@mstr_discrete.re~
s(chips)',
 PATH='I190',
 DRAWING='@BASEBOARD_FAB2_LIB.BASEBOARD_FAB2(SCH_1):PAGE201',
 WATTAGE='1/16W',
 TOLERANCE='1%',
 SEC_TYPE='0402',
 MATERIAL='EMPTY',
 PHYS_PAGE='201',
 XY='(-1275,3750)',
 ROT='0',
 VER='2',
 VALUE='100.0',
 PACK_TYPE='0402',
 PART_NUMBER='G21796-017',
 LOCATION='R4E10',
 ROOM='PVCCIO_CPU0',
 SEC='1',
 CDS_LIB='mstr_discrete',
 CDS_PART_NAME='RES_0402-100.0,1%,1/16W,EMPTY,A',
 PRIM_FILE='./archive_libs/mstr_discrete/res/chips/chips.prt';

PART_NAME
 R4E13 'RES_0603-100.0,1%,1/10W,CHIP,GA':
 ROOM='PVCCIN_CPU0_DECAP_VR';

SECTION_NUMBER 1
 '@BASEBOARD_FAB2_LIB.BASEBOARD_FAB2(SCH_1):PAGE203_I67@MSTR_DISCRETE.RES(CHIPS)':
 C_PATH='@baseboard_fab2_lib.baseboard_fab2(sch_1):page203_i67@mstr_discrete.res~
(chips)',
 P_PATH='@baseboard_fab2_lib.baseboard_fab2(sch_1):page203_i67@mstr_discrete.res~
(chips)',
 PATH='I67',
 DRAWING='@BASEBOARD_FAB2_LIB.BASEBOARD_FAB2(SCH_1):PAGE203',
 WATTAGE='1/10W',
 TOLERANCE='1%',
 SEC_TYPE='0603',
 MATERIAL='CHIP',
 BOM_COST='PROC_VRD_VCCIN_CPU0',
 PHYS_PAGE='203',
 XY='(-475,2550)',
 ROT='0',
 VER='2',
 VALUE='100.0',
 PACK_TYPE='0603',
 PART_NUMBER='G22026-038',
 LOCATION='R4E13',
 ROOM='PVCCIN_CPU0_DECAP_VR',
 SEC='1',
 CDS_LIB='mstr_discrete',
 CDS_PART_NAME='RES_0603-100.0,1%,1/10W,CHIP,GA',
 PRIM_FILE='./archive_libs/mstr_discrete/res/chips/chips.prt';

PART_NAME
 R4E14 'RES_0402-100.0,1%,1/16W,CHIP,GA':
 ROOM='PVCCIN_CPU0_VSENSE_VR';

SECTION_NUMBER 1
 '@BASEBOARD_FAB2_LIB.BASEBOARD_FAB2(SCH_1):PAGE204_I60@MSTR_DISCRETE.RES(CHIPS)':
 C_PATH='@baseboard_fab2_lib.baseboard_fab2(sch_1):page204_i60@mstr_discrete.res~
(chips)',
 P_PATH='@baseboard_fab2_lib.baseboard_fab2(sch_1):page204_i60@mstr_discrete.res~
(chips)',
 PATH='I60',
 DRAWING='@BASEBOARD_FAB2_LIB.BASEBOARD_FAB2(SCH_1):PAGE204',
 WATTAGE='1/16W',
 TOLERANCE='1%',
 MATERIAL='CHIP',
 BOM_COST='PROC_VRD_VCCIN_CPU0',
 PHYS_PAGE='204',
 XY='(-5475,2225)',
 ROT='0',
 VER='1',
 VALUE='100.0',
 PACK_TYPE='0402',
 PART_NUMBER='G21796-017',
 LOCATION='R4E14',
 ROOM='PVCCIN_CPU0_VSENSE_VR',
 CDS_LIB='mstr_discrete',
 CDS_PART_NAME='RES_0402-100.0,1%,1/16W,CHIP,GA',
 PRIM_FILE='./archive_libs/mstr_discrete/res/chips/chips.prt';

PART_NAME
 R4E15 'RES_0402-1.00K,1%,1/16W,EMPTY,A':
 ROOM='PVCCIN_CPU0_VSENSE_VR',
 NO_XNET_CONNECTION='1';

SECTION_NUMBER 1
 '@BASEBOARD_FAB2_LIB.BASEBOARD_FAB2(SCH_1):PAGE204_I63@MSTR_DISCRETE.RES(CHIPS)':
 C_PATH='@baseboard_fab2_lib.baseboard_fab2(sch_1):page204_i63@mstr_discrete.res~
(chips)',
 P_PATH='@baseboard_fab2_lib.baseboard_fab2(sch_1):page204_i63@mstr_discrete.res~
(chips)',
 PATH='I63',
 DRAWING='@BASEBOARD_FAB2_LIB.BASEBOARD_FAB2(SCH_1):PAGE204',
 WATTAGE='1/16W',
 TOLERANCE='1%',
 MATERIAL='EMPTY',
 BOM_COST='PROC_VRD_VCCIN_CPU0',
 NO_XNET_CONNECTION='1',
 PHYS_PAGE='204',
 XY='(-6275,1625)',
 ROT='0',
 VER='2',
 VALUE='1.00K',
 PACK_TYPE='0402',
 PART_NUMBER='G21796-026',
 LOCATION='R4E15',
 ROOM='PVCCIN_CPU0_VSENSE_VR',
 CDS_LIB='mstr_discrete',
 CDS_PART_NAME='RES_0402-1.00K,1%,1/16W,EMPTY,A',
 PRIM_FILE='./archive_libs/mstr_discrete/res/chips/chips.prt';

PART_NAME
 R4E16 'RES_0402-0.0,5%,1/16W,CHIP,G21A':
 ROOM='PVCCIN_CPU0_VSENSE_VR',
 NO_XNET_CONNECTION='1';

SECTION_NUMBER 1
 '@BASEBOARD_FAB2_LIB.BASEBOARD_FAB2(SCH_1):PAGE204_I61@MSTR_DISCRETE.RES(CHIPS)':
 C_PATH='@baseboard_fab2_lib.baseboard_fab2(sch_1):page204_i61@mstr_discrete.res~
(chips)',
 P_PATH='@baseboard_fab2_lib.baseboard_fab2(sch_1):page204_i61@mstr_discrete.res~
(chips)',
 PATH='I61',
 DRAWING='@BASEBOARD_FAB2_LIB.BASEBOARD_FAB2(SCH_1):PAGE204',
 WATTAGE='1/16W',
 TOLERANCE='5%',
 MATERIAL='CHIP',
 BOM_COST='PROC_VRD_VCCIN_CPU0',
 NO_XNET_CONNECTION='1',
 PHYS_PAGE='204',
 XY='(-5475,1825)',
 ROT='0',
 VER='1',
 VALUE='0.0',
 PACK_TYPE='0402',
 PART_NUMBER='G21497-005',
 LOCATION='R4E16',
 ROOM='PVCCIN_CPU0_VSENSE_VR',
 CDS_LIB='mstr_discrete',
 CDS_PART_NAME='RES_0402-0.0,5%,1/16W,CHIP,G21A',
 PRIM_FILE='./archive_libs/mstr_discrete/res/chips/chips.prt';

PART_NAME
 R4E17 'RES_0402-0.0,5%,1/16W,CHIP,G21A':
 ROOM='PVCCIN_CPU0_VSENSE_VR',
 NO_XNET_CONNECTION='1';

SECTION_NUMBER 1
 '@BASEBOARD_FAB2_LIB.BASEBOARD_FAB2(SCH_1):PAGE204_I62@MSTR_DISCRETE.RES(CHIPS)':
 C_PATH='@baseboard_fab2_lib.baseboard_fab2(sch_1):page204_i62@mstr_discrete.res~
(chips)',
 P_PATH='@baseboard_fab2_lib.baseboard_fab2(sch_1):page204_i62@mstr_discrete.res~
(chips)',
 PATH='I62',
 DRAWING='@BASEBOARD_FAB2_LIB.BASEBOARD_FAB2(SCH_1):PAGE204',
 WATTAGE='1/16W',
 TOLERANCE='5%',
 MATERIAL='CHIP',
 BOM_COST='PROC_VRD_VCCIN_CPU0',
 NO_XNET_CONNECTION='1',
 PHYS_PAGE='204',
 XY='(-5450,1375)',
 ROT='0',
 VER='1',
 VALUE='0.0',
 PACK_TYPE='0402',
 PART_NUMBER='G21497-005',
 LOCATION='R4E17',
 ROOM='PVCCIN_CPU0_VSENSE_VR',
 CDS_LIB='mstr_discrete',
 CDS_PART_NAME='RES_0402-0.0,5%,1/16W,CHIP,G21A',
 PRIM_FILE='./archive_libs/mstr_discrete/res/chips/chips.prt';

PART_NAME
 R4E18 'RES_0402-100.0,1%,1/16W,CHIP,GA':
 ROOM='PVCCIN_CPU0_VSENSE_VR';

SECTION_NUMBER 1
 '@BASEBOARD_FAB2_LIB.BASEBOARD_FAB2(SCH_1):PAGE204_I64@MSTR_DISCRETE.RES(CHIPS)':
 C_PATH='@baseboard_fab2_lib.baseboard_fab2(sch_1):page204_i64@mstr_discrete.res~
(chips)',
 P_PATH='@baseboard_fab2_lib.baseboard_fab2(sch_1):page204_i64@mstr_discrete.res~
(chips)',
 PATH='I64',
 DRAWING='@BASEBOARD_FAB2_LIB.BASEBOARD_FAB2(SCH_1):PAGE204',
 WATTAGE='1/16W',
 TOLERANCE='1%',
 MATERIAL='CHIP',
 BOM_COST='PROC_VRD_VCCIN_CPU0',
 PHYS_PAGE='204',
 XY='(-5450,975)',
 ROT='0',
 VER='1',
 VALUE='100.0',
 PACK_TYPE='0402',
 PART_NUMBER='G21796-017',
 LOCATION='R4E18',
 ROOM='PVCCIN_CPU0_VSENSE_VR',
 CDS_LIB='mstr_discrete',
 CDS_PART_NAME='RES_0402-100.0,1%,1/16W,CHIP,GA',
 PRIM_FILE='./archive_libs/mstr_discrete/res/chips/chips.prt';

PART_NAME
 R4E19 'RES_0402-68.1K,1%,1/16W,EMPTY,A':;

SECTION_NUMBER 1
 '@BASEBOARD_FAB2_LIB.BASEBOARD_FAB2(SCH_1):PAGE202_I67@MSTR_DISCRETE.RES(CHIPS)':
 C_PATH='@baseboard_fab2_lib.baseboard_fab2(sch_1):page202_i67@mstr_discrete.res~
(chips)',
 P_PATH='@baseboard_fab2_lib.baseboard_fab2(sch_1):page202_i67@mstr_discrete.res~
(chips)',
 PATH='I67',
 DRAWING='@BASEBOARD_FAB2_LIB.BASEBOARD_FAB2(SCH_1):PAGE202',
 WATTAGE='1/16W',
 TOLERANCE='1%',
 MATERIAL='EMPTY',
 PHYS_PAGE='202',
 XY='(-825,1350)',
 ROT='0',
 VER='2',
 VALUE='68.1K',
 PACK_TYPE='0402',
 PART_NUMBER='G21796-187',
 LOCATION='R4E19',
 CDS_LIB='mstr_discrete',
 CDS_PART_NAME='RES_0402-68.1K,1%,1/16W,EMPTY,A',
 PRIM_FILE='./archive_libs/mstr_discrete/res/chips/chips.prt';

PART_NAME
 R4E20 'RES_0402-2.26K,1.0%,1/16W,EMPTA':
 ROOM='PVCCIN_CPU0_VR';

SECTION_NUMBER 1
 '@BASEBOARD_FAB2_LIB.BASEBOARD_FAB2(SCH_1):PAGE201_I116@MSTR_DISCRETE.RES(CHIPS)':
 C_PATH='@baseboard_fab2_lib.baseboard_fab2(sch_1):page201_i116@mstr_discrete.re~
s(chips)',
 P_PATH='@baseboard_fab2_lib.baseboard_fab2(sch_1):page201_i116@mstr_discrete.re~
s(chips)',
 PATH='I116',
 DRAWING='@BASEBOARD_FAB2_LIB.BASEBOARD_FAB2(SCH_1):PAGE201',
 WATTAGE='1/16W',
 TOLERANCE='1.0%',
 SEC_TYPE='0402',
 MATERIAL='EMPTY',
 PHYS_PAGE='201',
 XY='(-1575,4200)',
 ROT='0',
 VER='2',
 VALUE='2.26K',
 PACK_TYPE='0402',
 PART_NUMBER='G21796-311',
 LOCATION='R4E20',
 ROOM='PVCCIN_CPU0_VR',
 SEC='1',
 CDS_LIB='mstr_discrete',
 CDS_PART_NAME='RES_0402-2.26K,1.0%,1/16W,EMPTA',
 PRIM_FILE='./archive_libs/mstr_discrete/res/chips/chips.prt';

PART_NAME
 R4E21 'RES_0402-68.1K,1%,1/16W,EMPTY,A':;

SECTION_NUMBER 1
 '@BASEBOARD_FAB2_LIB.BASEBOARD_FAB2(SCH_1):PAGE214_I127@MSTR_DISCRETE.RES(CHIPS)':
 C_PATH='@baseboard_fab2_lib.baseboard_fab2(sch_1):page214_i127@mstr_discrete.re~
s(chips)',
 P_PATH='@baseboard_fab2_lib.baseboard_fab2(sch_1):page214_i127@mstr_discrete.re~
s(chips)',
 PATH='I127',
 DRAWING='@BASEBOARD_FAB2_LIB.BASEBOARD_FAB2(SCH_1):PAGE214',
 WATTAGE='1/16W',
 TOLERANCE='1%',
 MATERIAL='EMPTY',
 PHYS_PAGE='214',
 XY='(3400,4075)',
 ROT='0',
 VER='2',
 VALUE='68.1K',
 PACK_TYPE='0402',
 PART_NUMBER='G21796-187',
 LOCATION='R4E21',
 CDS_LIB='mstr_discrete',
 CDS_PART_NAME='RES_0402-68.1K,1%,1/16W,EMPTY,A',
 PRIM_FILE='./archive_libs/mstr_discrete/res/chips/chips.prt';

PART_NAME
 R4E22 'RES_0402-68.1K,1%,1/16W,EMPTY,A':;

SECTION_NUMBER 1
 '@BASEBOARD_FAB2_LIB.BASEBOARD_FAB2(SCH_1):PAGE202_I65@MSTR_DISCRETE.RES(CHIPS)':
 C_PATH='@baseboard_fab2_lib.baseboard_fab2(sch_1):page202_i65@mstr_discrete.res~
(chips)',
 P_PATH='@baseboard_fab2_lib.baseboard_fab2(sch_1):page202_i65@mstr_discrete.res~
(chips)',
 PATH='I65',
 DRAWING='@BASEBOARD_FAB2_LIB.BASEBOARD_FAB2(SCH_1):PAGE202',
 WATTAGE='1/16W',
 TOLERANCE='1%',
 SEC_TYPE='0402',
 MATERIAL='EMPTY',
 PHYS_PAGE='202',
 XY='(-750,3900)',
 ROT='0',
 VER='2',
 VALUE='68.1K',
 PACK_TYPE='0402',
 PART_NUMBER='G21796-187',
 LOCATION='R4E22',
 SEC='1',
 CDS_LIB='mstr_discrete',
 CDS_PART_NAME='RES_0402-68.1K,1%,1/16W,EMPTY,A',
 PRIM_FILE='./archive_libs/mstr_discrete/res/chips/chips.prt';

PART_NAME
 R4F2 'RES_1206-0.002,1%,1W,CHIP,G521A':
 ROOM='PVDDQ_ABC_PWR_VR';

SECTION_NUMBER 1
 '@BASEBOARD_FAB2_LIB.BASEBOARD_FAB2(SCH_1):PAGE197_I14@MSTR_DISCRETE.RES(CHIPS)':
 C_PATH='@baseboard_fab2_lib.baseboard_fab2(sch_1):page197_i14@mstr_discrete.res~
(chips)',
 P_PATH='@baseboard_fab2_lib.baseboard_fab2(sch_1):page197_i14@mstr_discrete.res~
(chips)',
 PATH='I14',
 DRAWING='@BASEBOARD_FAB2_LIB.BASEBOARD_FAB2(SCH_1):PAGE197',
 NEW_VALUE='0.004 OHM',
 CONFIG='064.R0045.0711',
 WATTAGE='1W',
 TOLERANCE='1%',
 SEC_TYPE='1206',
 MATERIAL='CHIP',
 BOM_COST='PVDDQ_ABC_VR',
 PHYS_PAGE='197',
 XY='(-4275,4800)',
 ROT='0',
 VER='1',
 VALUE='0.002',
 PACK_TYPE='1206',
 PART_NUMBER='G52199-004',
 LOCATION='R4F2',
 ROOM='PVDDQ_ABC_PWR_VR',
 SEC='1',
 CDS_LIB='mstr_discrete',
 CDS_PART_NAME='RES_1206-0.002,1%,1W,CHIP,G521A',
 PRIM_FILE='./archive_libs/mstr_discrete/res/chips/chips.prt';

PART_NAME
 R4F3 'RES_0402-2,1.0%,1/16W,CHIP,G21A':
 ROOM='PROC';

SECTION_NUMBER 1
 '@BASEBOARD_FAB2_LIB.BASEBOARD_FAB2(SCH_1):PAGE98_I5@MSTR_DISCRETE.RES(CHIPS)':
 C_PATH='@baseboard_fab2_lib.baseboard_fab2(sch_1):page98_i5@mstr_discrete.res(c~
hips)',
 P_PATH='@baseboard_fab2_lib.baseboard_fab2(sch_1):page98_i5@mstr_discrete.res(c~
hips)',
 PATH='I5',
 DRAWING='@BASEBOARD_FAB2_LIB.BASEBOARD_FAB2(SCH_1):PAGE98',
 WATTAGE='1/16W',
 TOLERANCE='1.0%',
 SEC_TYPE='0402',
 MATERIAL='CHIP',
 BOM_COST='PROC_SOCKET',
 PHYS_PAGE='98',
 XY='(-2025,4025)',
 ROT='0',
 VER='1',
 VALUE='2',
 PACK_TYPE='0402',
 PART_NUMBER='G21796-274',
 LOCATION='R4F3',
 ROOM='PROC',
 SEC='1',
 CDS_LIB='mstr_discrete',
 CDS_PART_NAME='RES_0402-2,1.0%,1/16W,CHIP,G21A',
 PRIM_FILE='./archive_libs/mstr_discrete/res/chips/chips.prt';

PART_NAME
 R4F4 'RES_0402-1.00K,1%,1/16W,CHIP,GA':
 ROOM='MEM';

SECTION_NUMBER 1
 '@BASEBOARD_FAB2_LIB.BASEBOARD_FAB2(SCH_1):PAGE98_I36@MSTR_DISCRETE.RES(CHIPS)':
 C_PATH='@baseboard_fab2_lib.baseboard_fab2(sch_1):page98_i36@mstr_discrete.res(~
chips)',
 P_PATH='@baseboard_fab2_lib.baseboard_fab2(sch_1):page98_i36@mstr_discrete.res(~
chips)',
 PATH='I36',
 DRAWING='@BASEBOARD_FAB2_LIB.BASEBOARD_FAB2(SCH_1):PAGE98',
 WATTAGE='1/16W',
 TOLERANCE='1%',
 SEC_TYPE='0402',
 MATERIAL='CHIP',
 BOM_COST='SM_CONTROLLER',
 PHYS_PAGE='98',
 XY='(-1800,4350)',
 ROT='2',
 VER='2',
 VALUE='1.00K',
 PACK_TYPE='0402',
 PART_NUMBER='G21796-026',
 LOCATION='R4F4',
 ROOM='MEM',
 SEC='1',
 CDS_LIB='mstr_discrete',
 CDS_PART_NAME='RES_0402-1.00K,1%,1/16W,CHIP,GA',
 PRIM_FILE='./archive_libs/mstr_discrete/res/chips/chips.prt';

PART_NAME
 R4F5 'RES_0402-1.00K,1%,1/16W,CHIP,GA':
 ROOM='PROC';

SECTION_NUMBER 1
 '@BASEBOARD_FAB2_LIB.BASEBOARD_FAB2(SCH_1):PAGE98_I4@MSTR_DISCRETE.RES(CHIPS)':
 C_PATH='@baseboard_fab2_lib.baseboard_fab2(sch_1):page98_i4@mstr_discrete.res(c~
hips)',
 P_PATH='@baseboard_fab2_lib.baseboard_fab2(sch_1):page98_i4@mstr_discrete.res(c~
hips)',
 PATH='I4',
 DRAWING='@BASEBOARD_FAB2_LIB.BASEBOARD_FAB2(SCH_1):PAGE98',
 WATTAGE='1/16W',
 TOLERANCE='1%',
 SEC_TYPE='0402',
 MATERIAL='CHIP',
 BOM_COST='PROC_SOCKET',
 PHYS_PAGE='98',
 XY='(-1725,3700)',
 ROT='2',
 VER='2',
 VALUE='1.00K',
 PACK_TYPE='0402',
 PART_NUMBER='G21796-026',
 LOCATION='R4F5',
 ROOM='PROC',
 SEC='1',
 CDS_LIB='mstr_discrete',
 CDS_PART_NAME='RES_0402-1.00K,1%,1/16W,CHIP,GA',
 PRIM_FILE='./archive_libs/mstr_discrete/res/chips/chips.prt';

PART_NAME
 R4F6 'RES_0402-2.2,5%,1/16W,EMPTY,G2A':
 ROOM='PVPP_KLM_VR',
 REUSE_ID='29';

SECTION_NUMBER 1
 '@BASEBOARD_FAB2_LIB.BASEBOARD_FAB2(SCH_1):PAGE233_I208@MSTR_DISCRETE.RES(CHIPS)':
 C_PATH='@baseboard_fab2_lib.baseboard_fab2(sch_1):page233_i208@mstr_discrete.re~
s(chips)',
 P_PATH='@baseboard_fab2_lib.baseboard_fab2(sch_1):page233_i208@mstr_discrete.re~
s(chips)',
 PATH='I208',
 DRAWING='@BASEBOARD_FAB2_LIB.BASEBOARD_FAB2(SCH_1):PAGE233',
 WATTAGE='1/16W',
 TOLERANCE='5%',
 MATERIAL='EMPTY',
 BOM_COST='PVPP_KLM_VR',
 PHYS_PAGE='233',
 REUSE_ID='29',
 XY='(-2450,3100)',
 ROT='0',
 VER='2',
 VALUE='2.2',
 PACK_TYPE='0402',
 PART_NUMBER='G21497-016',
 LOCATION='R4F6',
 ROOM='PVPP_KLM_VR',
 CDS_LIB='mstr_discrete',
 CDS_PART_NAME='RES_0402-2.2,5%,1/16W,EMPTY,G2A',
 PRIM_FILE='./archive_libs/mstr_discrete/res/chips/chips.prt';

PART_NAME
 R4G1 'RES_0402-2,1.0%,1/16W,CHIP,G21A':
 ROOM='PROC';

SECTION_NUMBER 1
 '@BASEBOARD_FAB2_LIB.BASEBOARD_FAB2(SCH_1):PAGE98_I42@MSTR_DISCRETE.RES(CHIPS)':
 C_PATH='@baseboard_fab2_lib.baseboard_fab2(sch_1):page98_i42@mstr_discrete.res(~
chips)',
 P_PATH='@baseboard_fab2_lib.baseboard_fab2(sch_1):page98_i42@mstr_discrete.res(~
chips)',
 PATH='I42',
 DRAWING='@BASEBOARD_FAB2_LIB.BASEBOARD_FAB2(SCH_1):PAGE98',
 WATTAGE='1/16W',
 TOLERANCE='1.0%',
 SEC_TYPE='0402',
 MATERIAL='CHIP',
 BOM_COST='PROC_SOCKET',
 PHYS_PAGE='98',
 XY='(25,4025)',
 ROT='0',
 VER='1',
 VALUE='2',
 PACK_TYPE='0402',
 PART_NUMBER='G21796-274',
 LOCATION='R4G1',
 ROOM='PROC',
 SEC='1',
 CDS_LIB='mstr_discrete',
 CDS_PART_NAME='RES_0402-2,1.0%,1/16W,CHIP,G21A',
 PRIM_FILE='./archive_libs/mstr_discrete/res/chips/chips.prt';

PART_NAME
 R4G2 'RES_0402-1.00K,1%,1/16W,CHIP,GA':
 ROOM='MEM';

SECTION_NUMBER 1
 '@BASEBOARD_FAB2_LIB.BASEBOARD_FAB2(SCH_1):PAGE98_I38@MSTR_DISCRETE.RES(CHIPS)':
 C_PATH='@baseboard_fab2_lib.baseboard_fab2(sch_1):page98_i38@mstr_discrete.res(~
chips)',
 P_PATH='@baseboard_fab2_lib.baseboard_fab2(sch_1):page98_i38@mstr_discrete.res(~
chips)',
 PATH='I38',
 DRAWING='@BASEBOARD_FAB2_LIB.BASEBOARD_FAB2(SCH_1):PAGE98',
 WATTAGE='1/16W',
 TOLERANCE='1%',
 SEC_TYPE='0402',
 MATERIAL='CHIP',
 BOM_COST='SM_CONTROLLER',
 PHYS_PAGE='98',
 XY='(250,4350)',
 ROT='2',
 VER='2',
 VALUE='1.00K',
 PACK_TYPE='0402',
 PART_NUMBER='G21796-026',
 LOCATION='R4G2',
 ROOM='MEM',
 SEC='1',
 CDS_LIB='mstr_discrete',
 CDS_PART_NAME='RES_0402-1.00K,1%,1/16W,CHIP,GA',
 PRIM_FILE='./archive_libs/mstr_discrete/res/chips/chips.prt';

PART_NAME
 R4G3 'RES_0402-1.00K,1%,1/16W,CHIP,GA':
 ROOM='PROC';

SECTION_NUMBER 1
 '@BASEBOARD_FAB2_LIB.BASEBOARD_FAB2(SCH_1):PAGE98_I40@MSTR_DISCRETE.RES(CHIPS)':
 C_PATH='@baseboard_fab2_lib.baseboard_fab2(sch_1):page98_i40@mstr_discrete.res(~
chips)',
 P_PATH='@baseboard_fab2_lib.baseboard_fab2(sch_1):page98_i40@mstr_discrete.res(~
chips)',
 PATH='I40',
 DRAWING='@BASEBOARD_FAB2_LIB.BASEBOARD_FAB2(SCH_1):PAGE98',
 WATTAGE='1/16W',
 TOLERANCE='1%',
 SEC_TYPE='0402',
 MATERIAL='CHIP',
 BOM_COST='PROC_SOCKET',
 PHYS_PAGE='98',
 XY='(325,3700)',
 ROT='2',
 VER='2',
 VALUE='1.00K',
 PACK_TYPE='0402',
 PART_NUMBER='G21796-026',
 LOCATION='R4G3',
 ROOM='PROC',
 SEC='1',
 CDS_LIB='mstr_discrete',
 CDS_PART_NAME='RES_0402-1.00K,1%,1/16W,CHIP,GA',
 PRIM_FILE='./archive_libs/mstr_discrete/res/chips/chips.prt';

PART_NAME
 R4G4 'RES_0402-0.0,5%,1/16W,CHIP,G21A':
 ROOM='PVCCIN_CPU0_VR';

SECTION_NUMBER 1
 '@BASEBOARD_FAB2_LIB.BASEBOARD_FAB2(SCH_1):PAGE233_I275@MSTR_DISCRETE.RES(CHIPS)':
 C_PATH='@baseboard_fab2_lib.baseboard_fab2(sch_1):page233_i275@mstr_discrete.re~
s(chips)',
 P_PATH='@baseboard_fab2_lib.baseboard_fab2(sch_1):page233_i275@mstr_discrete.re~
s(chips)',
 PATH='I275',
 DRAWING='@BASEBOARD_FAB2_LIB.BASEBOARD_FAB2(SCH_1):PAGE233',
 WATTAGE='1/16W',
 TOLERANCE='5%',
 SEC_TYPE='0402',
 MATERIAL='CHIP',
 PHYS_PAGE='233',
 XY='(-6075,2675)',
 ROT='0',
 VER='1',
 VALUE='0.0',
 PACK_TYPE='0402',
 PART_NUMBER='G21497-005',
 LOCATION='R4G4',
 ROOM='PVCCIN_CPU0_VR',
 SEC='1',
 CDS_LIB='mstr_discrete',
 CDS_PART_NAME='RES_0402-0.0,5%,1/16W,CHIP,G21A',
 PRIM_FILE='./archive_libs/mstr_discrete/res/chips/chips.prt';

PART_NAME
 R4G5 'RES_0402-10.0K,1%,1/16W,CHIP,GA':
 ROOM='PVPP_KLM_VR';

SECTION_NUMBER 1
 '@BASEBOARD_FAB2_LIB.BASEBOARD_FAB2(SCH_1):PAGE233_I182@MSTR_DISCRETE.RES(CHIPS)':
 C_PATH='@baseboard_fab2_lib.baseboard_fab2(sch_1):page233_i182@mstr_discrete.re~
s(chips)',
 P_PATH='@baseboard_fab2_lib.baseboard_fab2(sch_1):page233_i182@mstr_discrete.re~
s(chips)',
 PATH='I182',
 DRAWING='@BASEBOARD_FAB2_LIB.BASEBOARD_FAB2(SCH_1):PAGE233',
 BOM='SYSB_CPLD',
 WATTAGE='1/16W',
 TOLERANCE='1%',
 MATERIAL='CHIP',
 BOM_COST='PVPP_KLM_VR',
 PHYS_PAGE='233',
 XY='(-7100,2200)',
 ROT='0',
 VER='2',
 VALUE='10.0K',
 PACK_TYPE='0402',
 PART_NUMBER='G21796-016',
 LOCATION='R4G5',
 ROOM='PVPP_KLM_VR',
 CDS_LIB='mstr_discrete',
 CDS_PART_NAME='RES_0402-10.0K,1%,1/16W,CHIP,GA',
 PRIM_FILE='./archive_libs/mstr_discrete/res/chips/chips.prt';

PART_NAME
 R4G6 'RES_0603-120.0,1%,1/10W,CHIP,GA':
 ROOM='PVPP_KLM_VR',
 REUSE_ID='34';

SECTION_NUMBER 1
 '@BASEBOARD_FAB2_LIB.BASEBOARD_FAB2(SCH_1):PAGE233_I211@MSTR_DISCRETE.RES(CHIPS)':
 C_PATH='@baseboard_fab2_lib.baseboard_fab2(sch_1):page233_i211@mstr_discrete.re~
s(chips)',
 P_PATH='@baseboard_fab2_lib.baseboard_fab2(sch_1):page233_i211@mstr_discrete.re~
s(chips)',
 PATH='I211',
 DRAWING='@BASEBOARD_FAB2_LIB.BASEBOARD_FAB2(SCH_1):PAGE233',
 WATTAGE='1/10W',
 TOLERANCE='1%',
 MATERIAL='CHIP',
 BOM_COST='PVPP_KLM_VR',
 PHYS_PAGE='233',
 REUSE_ID='34',
 XY='(-2000,3525)',
 ROT='0',
 VER='2',
 VALUE='120.0',
 PACK_TYPE='0603',
 PART_NUMBER='G22026-003',
 LOCATION='R4G6',
 ROOM='PVPP_KLM_VR',
 CDS_LIB='mstr_discrete',
 CDS_PART_NAME='RES_0603-120.0,1%,1/10W,CHIP,GA',
 PRIM_FILE='./archive_libs/mstr_discrete/res/chips/chips.prt';

PART_NAME
 R4G7 'RES_0402-20.0K,1%,1/16W,CHIP,GA':
 ROOM='PVPP_KLM_VR',
 REUSE_ID='9';

SECTION_NUMBER 1
 '@BASEBOARD_FAB2_LIB.BASEBOARD_FAB2(SCH_1):PAGE233_I270@MSTR_DISCRETE.RES(CHIPS)':
 C_PATH='@baseboard_fab2_lib.baseboard_fab2(sch_1):page233_i270@mstr_discrete.re~
s(chips)',
 P_PATH='@baseboard_fab2_lib.baseboard_fab2(sch_1):page233_i270@mstr_discrete.re~
s(chips)',
 PATH='I270',
 DRAWING='@BASEBOARD_FAB2_LIB.BASEBOARD_FAB2(SCH_1):PAGE233',
 SPOF='TRUE',
 WATTAGE='1/16W',
 TOLERANCE='1%',
 MATERIAL='CHIP',
 BOM_COST='PVPP_KLM_VR',
 PHYS_PAGE='233',
 REUSE_ID='9',
 XY='(-1275,1800)',
 ROT='0',
 VER='2',
 VALUE='20.0K',
 PACK_TYPE='0402',
 PART_NUMBER='G21796-040',
 LOCATION='R4G7',
 ROOM='PVPP_KLM_VR',
 CDS_LIB='mstr_discrete',
 CDS_PART_NAME='RES_0402-20.0K,1%,1/16W,CHIP,GA',
 PRIM_FILE='./archive_libs/mstr_discrete/res/chips/chips.prt';

PART_NAME
 R4G8 'RES_0402-0.0,5%,1/16W,CHIP,G21A':
 ROOM='PVPP_KLM_VR';

SECTION_NUMBER 1
 '@BASEBOARD_FAB2_LIB.BASEBOARD_FAB2(SCH_1):PAGE233_I271@MSTR_DISCRETE.RES(CHIPS)':
 C_PATH='@baseboard_fab2_lib.baseboard_fab2(sch_1):page233_i271@mstr_discrete.re~
s(chips)',
 P_PATH='@baseboard_fab2_lib.baseboard_fab2(sch_1):page233_i271@mstr_discrete.re~
s(chips)',
 PATH='I271',
 DRAWING='@BASEBOARD_FAB2_LIB.BASEBOARD_FAB2(SCH_1):PAGE233',
 SPOF='TRUE',
 WATTAGE='1/16W',
 TOLERANCE='5%',
 SEC_TYPE='0402',
 MATERIAL='CHIP',
 PHYS_PAGE='233',
 XY='(-1275,2900)',
 ROT='5',
 VER='1',
 VALUE='0.0',
 PACK_TYPE='0402',
 PART_NUMBER='G21497-005',
 LOCATION='R4G8',
 ROOM='PVPP_KLM_VR',
 SEC='1',
 CDS_LIB='mstr_discrete',
 CDS_PART_NAME='RES_0402-0.0,5%,1/16W,CHIP,G21A',
 PRIM_FILE='./archive_libs/mstr_discrete/res/chips/chips.prt';

PART_NAME
 R4G9 'RES_0402-6.19K,1%,1/16W,CHIP,GA':
 ROOM='IO_SLOT';

SECTION_NUMBER 1
 '@BASEBOARD_FAB2_LIB.BASEBOARD_FAB2(SCH_1):PAGE233_I283@MSTR_DISCRETE.RES(CHIPS)':
 C_PATH='@baseboard_fab2_lib.baseboard_fab2(sch_1):page233_i283@mstr_discrete.re~
s(chips)',
 P_PATH='@baseboard_fab2_lib.baseboard_fab2(sch_1):page233_i283@mstr_discrete.re~
s(chips)',
 PATH='I283',
 DRAWING='@BASEBOARD_FAB2_LIB.BASEBOARD_FAB2(SCH_1):PAGE233',
 WATTAGE='1/16W',
 TOLERANCE='1%',
 SEC_TYPE='0402',
 MATERIAL='CHIP',
 BOM_COST='IO_SLOT',
 PHYS_PAGE='233',
 XY='(-1275,1225)',
 ROT='0',
 VER='2',
 VALUE='6.19K',
 PACK_TYPE='0402',
 PART_NUMBER='G21796-161',
 LOCATION='R4G9',
 ROOM='IO_SLOT',
 SEC='1',
 CDS_LIB='mstr_discrete',
 CDS_PART_NAME='RES_0402-6.19K,1%,1/16W,CHIP,GA',
 PRIM_FILE='./archive_libs/mstr_discrete/res/chips/chips.prt';

PART_NAME
 R4G10 'RES_0402-1.0K,0.1%,1/16W,CHIP,A':
 ROOM='PVPP_KLM_VR',
 REUSE_ID='9';

SECTION_NUMBER 1
 '@BASEBOARD_FAB2_LIB.BASEBOARD_FAB2(SCH_1):PAGE233_I266@MSTR_DISCRETE.RES(CHIPS)':
 C_PATH='@baseboard_fab2_lib.baseboard_fab2(sch_1):page233_i266@mstr_discrete.re~
s(chips)',
 P_PATH='@baseboard_fab2_lib.baseboard_fab2(sch_1):page233_i266@mstr_discrete.re~
s(chips)',
 PATH='I266',
 DRAWING='@BASEBOARD_FAB2_LIB.BASEBOARD_FAB2(SCH_1):PAGE233',
 SPOF='TRUE',
 WATTAGE='1/16W',
 TOLERANCE='0.1%',
 SEC_TYPE='0402',
 MATERIAL='CHIP',
 BOM_COST='PVPP_KLM_VR',
 PHYS_PAGE='233',
 REUSE_ID='9',
 XY='(-950,2475)',
 ROT='0',
 VER='2',
 VALUE='1.0K',
 PACK_TYPE='0402',
 PART_NUMBER='G85996-004',
 LOCATION='R4G10',
 ROOM='PVPP_KLM_VR',
 SEC='1',
 CDS_LIB='mstr_discrete',
 CDS_PART_NAME='RES_0402-1.0K,0.1%,1/16W,CHIP,A',
 PRIM_FILE='./archive_libs/mstr_discrete/res/chips/chips.prt';

PART_NAME
 R4G11 'RES_0402-7.87K,1.0%,1/16W,CHIPA':
 ROOM='PVPP_KLM_VR';

SECTION_NUMBER 1
 '@BASEBOARD_FAB2_LIB.BASEBOARD_FAB2(SCH_1):PAGE233_I284@MSTR_DISCRETE.RES(CHIPS)':
 C_PATH='@baseboard_fab2_lib.baseboard_fab2(sch_1):page233_i284@mstr_discrete.re~
s(chips)',
 P_PATH='@baseboard_fab2_lib.baseboard_fab2(sch_1):page233_i284@mstr_discrete.re~
s(chips)',
 PATH='I284',
 DRAWING='@BASEBOARD_FAB2_LIB.BASEBOARD_FAB2(SCH_1):PAGE233',
 NEW_VALUE='3.9K',
 CONFIG='64.39015.6DL',
 WATTAGE='1/16W',
 TOLERANCE='1.0%',
 MATERIAL='CHIP',
 BOM_COST='PVPP_KLM_VR',
 PHYS_PAGE='233',
 XY='(-4675,1500)',
 ROT='2',
 VER='2',
 VALUE='7.87K',
 PACK_TYPE='0402',
 PART_NUMBER='G21796-242',
 LOCATION='R4G11',
 ROOM='PVPP_KLM_VR',
 CDS_LIB='mstr_discrete',
 CDS_PART_NAME='RES_0402-7.87K,1.0%,1/16W,CHIPA',
 PRIM_FILE='./archive_libs/mstr_discrete/res/chips/chips.prt';

PART_NAME
 R4G12 'RES_0402-22.1,1.0%,1/16W,CHIP,A':
 ROOM='PVPP_GHJ_VR';

SECTION_NUMBER 1
 '@BASEBOARD_FAB2_LIB.BASEBOARD_FAB2(SCH_1):PAGE233_I247@MSTR_DISCRETE.RES(CHIPS)':
 C_PATH='@baseboard_fab2_lib.baseboard_fab2(sch_1):page233_i247@mstr_discrete.re~
s(chips)',
 P_PATH='@baseboard_fab2_lib.baseboard_fab2(sch_1):page233_i247@mstr_discrete.re~
s(chips)',
 PATH='I247',
 DRAWING='@BASEBOARD_FAB2_LIB.BASEBOARD_FAB2(SCH_1):PAGE233',
 WATTAGE='1/16W',
 TOLERANCE='1.0%',
 SEC_TYPE='0402',
 MATERIAL='CHIP',
 PHYS_PAGE='233',
 XY='(-3375,825)',
 ROT='0',
 VER='1',
 VALUE='22.1',
 PACK_TYPE='0402',
 PART_NUMBER='G21796-250',
 LOCATION='R4G12',
 ROOM='PVPP_GHJ_VR',
 SEC='1',
 CDS_LIB='mstr_discrete',
 CDS_PART_NAME='RES_0402-22.1,1.0%,1/16W,CHIP,A',
 PRIM_FILE='./archive_libs/mstr_discrete/res/chips/chips.prt';

PART_NAME
 R4G13 'RES_0402-7.87K,1.0%,1/16W,CHIPA':
 ROOM='PVPP_KLM_VR',
 REUSE_ID='13';

SECTION_NUMBER 1
 '@BASEBOARD_FAB2_LIB.BASEBOARD_FAB2(SCH_1):PAGE233_I272@MSTR_DISCRETE.RES(CHIPS)':
 C_PATH='@baseboard_fab2_lib.baseboard_fab2(sch_1):page233_i272@mstr_discrete.re~
s(chips)',
 P_PATH='@baseboard_fab2_lib.baseboard_fab2(sch_1):page233_i272@mstr_discrete.re~
s(chips)',
 PATH='I272',
 DRAWING='@BASEBOARD_FAB2_LIB.BASEBOARD_FAB2(SCH_1):PAGE233',
 WATTAGE='1/16W',
 TOLERANCE='1.0%',
 SEC_TYPE='0402',
 MATERIAL='CHIP',
 BOM_COST='PVPP_KLM_VR',
 PHYS_PAGE='233',
 REUSE_ID='13',
 XY='(-2000,2300)',
 ROT='0',
 VER='1',
 VALUE='7.87K',
 PACK_TYPE='0402',
 PART_NUMBER='G21796-242',
 LOCATION='R4G13',
 ROOM='PVPP_KLM_VR',
 SEC='1',
 CDS_LIB='mstr_discrete',
 CDS_PART_NAME='RES_0402-7.87K,1.0%,1/16W,CHIPA',
 PRIM_FILE='./archive_libs/mstr_discrete/res/chips/chips.prt';

PART_NAME
 R4G14 'RES_0402-1.00K,1%,1/16W,CHIP,GA':
 ROOM='PVPP_KLM_VR',
 REUSE_ID='21';

SECTION_NUMBER 1
 '@BASEBOARD_FAB2_LIB.BASEBOARD_FAB2(SCH_1):PAGE233_I185@MSTR_DISCRETE.RES(CHIPS)':
 C_PATH='@baseboard_fab2_lib.baseboard_fab2(sch_1):page233_i185@mstr_discrete.re~
s(chips)',
 P_PATH='@baseboard_fab2_lib.baseboard_fab2(sch_1):page233_i185@mstr_discrete.re~
s(chips)',
 PATH='I185',
 DRAWING='@BASEBOARD_FAB2_LIB.BASEBOARD_FAB2(SCH_1):PAGE233',
 WATTAGE='1/16W',
 TOLERANCE='1%',
 SEC_TYPE='0402',
 MATERIAL='CHIP',
 BOM_COST='PVPP_KLM_VR',
 PHYS_PAGE='233',
 REUSE_ID='21',
 XY='(-4150,1100)',
 ROT='0',
 VER='2',
 VALUE='1.00K',
 PACK_TYPE='0402',
 PART_NUMBER='G21796-026',
 LOCATION='R4G14',
 ROOM='PVPP_KLM_VR',
 SEC='1',
 CDS_LIB='mstr_discrete',
 CDS_PART_NAME='RES_0402-1.00K,1%,1/16W,CHIP,GA',
 PRIM_FILE='./archive_libs/mstr_discrete/res/chips/chips.prt';

PART_NAME
 R4G15 'RES_0402-33.2,1%,1/16W,CHIP,G2A':;

SECTION_NUMBER 1
 '@BASEBOARD_FAB2_LIB.BASEBOARD_FAB2(SCH_1):PAGE229_I32@MSTR_DISCRETE.RES(CHIPS)':
 C_PATH='@baseboard_fab2_lib.baseboard_fab2(sch_1):page229_i32@mstr_discrete.res~
(chips)',
 P_PATH='@baseboard_fab2_lib.baseboard_fab2(sch_1):page229_i32@mstr_discrete.res~
(chips)',
 PATH='I32',
 DRAWING='@BASEBOARD_FAB2_LIB.BASEBOARD_FAB2(SCH_1):PAGE229',
 WATTAGE='1/16W',
 TOLERANCE='1%',
 SEC_TYPE='0402',
 MATERIAL='CHIP',
 PHYS_PAGE='229',
 XY='(4250,1650)',
 ROT='0',
 VER='1',
 VALUE='33.2',
 PACK_TYPE='0402',
 PART_NUMBER='G21796-074',
 LOCATION='R4G15',
 SEC='1',
 CDS_LIB='mstr_discrete',
 CDS_PART_NAME='RES_0402-33.2,1%,1/16W,CHIP,G2A',
 PRIM_FILE='./archive_libs/mstr_discrete/res/chips/chips.prt';

PART_NAME
 R4G16 'RES_0402-0.0,5%,1/16W,CHIP,G21A':
 ROOM='VTT_GHJ_PWR_VR';

SECTION_NUMBER 1
 '@BASEBOARD_FAB2_LIB.BASEBOARD_FAB2(SCH_1):PAGE229_I4@MSTR_DISCRETE.RES(CHIPS)':
 C_PATH='@baseboard_fab2_lib.baseboard_fab2(sch_1):page229_i4@mstr_discrete.res(~
chips)',
 P_PATH='@baseboard_fab2_lib.baseboard_fab2(sch_1):page229_i4@mstr_discrete.res(~
chips)',
 PATH='I4',
 DRAWING='@BASEBOARD_FAB2_LIB.BASEBOARD_FAB2(SCH_1):PAGE229',
 WATTAGE='1/16W',
 TOLERANCE='5%',
 SEC_TYPE='0402',
 MATERIAL='CHIP',
 BOM_COST='MEM_VRD_VTT_GHJ',
 PHYS_PAGE='229',
 XY='(-650,-25)',
 ROT='0',
 VER='1',
 VALUE='0.0',
 PACK_TYPE='0402',
 PART_NUMBER='G21497-005',
 LOCATION='R4G16',
 ROOM='VTT_GHJ_PWR_VR',
 SEC='1',
 CDS_LIB='mstr_discrete',
 CDS_PART_NAME='RES_0402-0.0,5%,1/16W,CHIP,G21A',
 PRIM_FILE='./archive_libs/mstr_discrete/res/chips/chips.prt';

PART_NAME
 R4G17 'RES_0402-10.0K,1%,1/16W,CHIP,GA':
 ROOM='VTT_GHJ_PWR_VR';

SECTION_NUMBER 1
 '@BASEBOARD_FAB2_LIB.BASEBOARD_FAB2(SCH_1):PAGE229_I24@MSTR_DISCRETE.RES(CHIPS)':
 C_PATH='@baseboard_fab2_lib.baseboard_fab2(sch_1):page229_i24@mstr_discrete.res~
(chips)',
 P_PATH='@baseboard_fab2_lib.baseboard_fab2(sch_1):page229_i24@mstr_discrete.res~
(chips)',
 PATH='I24',
 DRAWING='@BASEBOARD_FAB2_LIB.BASEBOARD_FAB2(SCH_1):PAGE229',
 WATTAGE='1/16W',
 TOLERANCE='1%',
 SEC_TYPE='0402',
 MATERIAL='CHIP',
 BOM_COST='MEM_VRD_VTT_GHJ',
 PHYS_PAGE='229',
 XY='(3325,1850)',
 ROT='0',
 VER='2',
 VALUE='10.0K',
 PACK_TYPE='0402',
 PART_NUMBER='G21796-016',
 LOCATION='R4G17',
 ROOM='VTT_GHJ_PWR_VR',
 SEC='1',
 CDS_LIB='mstr_discrete',
 CDS_PART_NAME='RES_0402-10.0K,1%,1/16W,CHIP,GA',
 PRIM_FILE='./archive_libs/mstr_discrete/res/chips/chips.prt';

PART_NAME
 R4G18 'RES_0402-10.0K,1%,1/16W,CHIP,GA':
 ROOM='VTT_ABC_PWR_VR';

SECTION_NUMBER 1
 '@BASEBOARD_FAB2_LIB.BASEBOARD_FAB2(SCH_1):PAGE221_I25@MSTR_DISCRETE.RES(CHIPS)':
 C_PATH='@baseboard_fab2_lib.baseboard_fab2(sch_1):page221_i25@mstr_discrete.res~
(chips)',
 P_PATH='@baseboard_fab2_lib.baseboard_fab2(sch_1):page221_i25@mstr_discrete.res~
(chips)',
 PATH='I25',
 DRAWING='@BASEBOARD_FAB2_LIB.BASEBOARD_FAB2(SCH_1):PAGE221',
 WATTAGE='1/16W',
 TOLERANCE='1%',
 SEC_TYPE='0402',
 MATERIAL='CHIP',
 BOM_COST='MEM_VRD_VTT_ABC',
 PHYS_PAGE='221',
 XY='(3225,2000)',
 ROT='0',
 VER='2',
 VALUE='10.0K',
 PACK_TYPE='0402',
 PART_NUMBER='G21796-016',
 LOCATION='R4G18',
 ROOM='VTT_ABC_PWR_VR',
 SEC='1',
 CDS_LIB='mstr_discrete',
 CDS_PART_NAME='RES_0402-10.0K,1%,1/16W,CHIP,GA',
 PRIM_FILE='./archive_libs/mstr_discrete/res/chips/chips.prt';

PART_NAME
 R4G19 'RES_0402-33.2,1%,1/16W,CHIP,G2A':;

SECTION_NUMBER 1
 '@BASEBOARD_FAB2_LIB.BASEBOARD_FAB2(SCH_1):PAGE221_I33@MSTR_DISCRETE.RES(CHIPS)':
 C_PATH='@baseboard_fab2_lib.baseboard_fab2(sch_1):page221_i33@mstr_discrete.res~
(chips)',
 P_PATH='@baseboard_fab2_lib.baseboard_fab2(sch_1):page221_i33@mstr_discrete.res~
(chips)',
 PATH='I33',
 DRAWING='@BASEBOARD_FAB2_LIB.BASEBOARD_FAB2(SCH_1):PAGE221',
 WATTAGE='1/16W',
 TOLERANCE='1%',
 SEC_TYPE='0402',
 MATERIAL='CHIP',
 PHYS_PAGE='221',
 XY='(4350,1725)',
 ROT='0',
 VER='1',
 VALUE='33.2',
 PACK_TYPE='0402',
 PART_NUMBER='G21796-074',
 LOCATION='R4G19',
 SEC='1',
 CDS_LIB='mstr_discrete',
 CDS_PART_NAME='RES_0402-33.2,1%,1/16W,CHIP,G2A',
 PRIM_FILE='./archive_libs/mstr_discrete/res/chips/chips.prt';

PART_NAME
 R4G20 'RES_0402-2,1.0%,1/16W,CHIP,G21A':
 ROOM='PROC';

SECTION_NUMBER 1
 '@BASEBOARD_FAB2_LIB.BASEBOARD_FAB2(SCH_1):PAGE98_I50@MSTR_DISCRETE.RES(CHIPS)':
 C_PATH='@baseboard_fab2_lib.baseboard_fab2(sch_1):page98_i50@mstr_discrete.res(~
chips)',
 P_PATH='@baseboard_fab2_lib.baseboard_fab2(sch_1):page98_i50@mstr_discrete.res(~
chips)',
 PATH='I50',
 DRAWING='@BASEBOARD_FAB2_LIB.BASEBOARD_FAB2(SCH_1):PAGE98',
 WATTAGE='1/16W',
 TOLERANCE='1.0%',
 SEC_TYPE='0402',
 MATERIAL='CHIP',
 BOM_COST='PROC_SOCKET',
 PHYS_PAGE='98',
 XY='(2175,4025)',
 ROT='0',
 VER='1',
 VALUE='2',
 PACK_TYPE='0402',
 PART_NUMBER='G21796-274',
 LOCATION='R4G20',
 ROOM='PROC',
 SEC='1',
 CDS_LIB='mstr_discrete',
 CDS_PART_NAME='RES_0402-2,1.0%,1/16W,CHIP,G21A',
 PRIM_FILE='./archive_libs/mstr_discrete/res/chips/chips.prt';

PART_NAME
 R4G21 'RES_0402-1.00K,1%,1/16W,CHIP,GA':
 ROOM='MEM';

SECTION_NUMBER 1
 '@BASEBOARD_FAB2_LIB.BASEBOARD_FAB2(SCH_1):PAGE98_I46@MSTR_DISCRETE.RES(CHIPS)':
 C_PATH='@baseboard_fab2_lib.baseboard_fab2(sch_1):page98_i46@mstr_discrete.res(~
chips)',
 P_PATH='@baseboard_fab2_lib.baseboard_fab2(sch_1):page98_i46@mstr_discrete.res(~
chips)',
 PATH='I46',
 DRAWING='@BASEBOARD_FAB2_LIB.BASEBOARD_FAB2(SCH_1):PAGE98',
 WATTAGE='1/16W',
 TOLERANCE='1%',
 SEC_TYPE='0402',
 MATERIAL='CHIP',
 BOM_COST='SM_CONTROLLER',
 PHYS_PAGE='98',
 XY='(2400,4350)',
 ROT='2',
 VER='2',
 VALUE='1.00K',
 PACK_TYPE='0402',
 PART_NUMBER='G21796-026',
 LOCATION='R4G21',
 ROOM='MEM',
 SEC='1',
 CDS_LIB='mstr_discrete',
 CDS_PART_NAME='RES_0402-1.00K,1%,1/16W,CHIP,GA',
 PRIM_FILE='./archive_libs/mstr_discrete/res/chips/chips.prt';

PART_NAME
 R4G22 'RES_0402-1.00K,1%,1/16W,CHIP,GA':
 ROOM='PROC';

SECTION_NUMBER 1
 '@BASEBOARD_FAB2_LIB.BASEBOARD_FAB2(SCH_1):PAGE98_I48@MSTR_DISCRETE.RES(CHIPS)':
 C_PATH='@baseboard_fab2_lib.baseboard_fab2(sch_1):page98_i48@mstr_discrete.res(~
chips)',
 P_PATH='@baseboard_fab2_lib.baseboard_fab2(sch_1):page98_i48@mstr_discrete.res(~
chips)',
 PATH='I48',
 DRAWING='@BASEBOARD_FAB2_LIB.BASEBOARD_FAB2(SCH_1):PAGE98',
 WATTAGE='1/16W',
 TOLERANCE='1%',
 SEC_TYPE='0402',
 MATERIAL='CHIP',
 BOM_COST='PROC_SOCKET',
 PHYS_PAGE='98',
 XY='(2475,3700)',
 ROT='2',
 VER='2',
 VALUE='1.00K',
 PACK_TYPE='0402',
 PART_NUMBER='G21796-026',
 LOCATION='R4G22',
 ROOM='PROC',
 SEC='1',
 CDS_LIB='mstr_discrete',
 CDS_PART_NAME='RES_0402-1.00K,1%,1/16W,CHIP,GA',
 PRIM_FILE='./archive_libs/mstr_discrete/res/chips/chips.prt';

PART_NAME
 R4G23 'RES_0402-0.0,5%,1/16W,CHIP,G21A':
 ROOM='VTT_ABC_PWR_VR';

SECTION_NUMBER 1
 '@BASEBOARD_FAB2_LIB.BASEBOARD_FAB2(SCH_1):PAGE221_I4@MSTR_DISCRETE.RES(CHIPS)':
 C_PATH='@baseboard_fab2_lib.baseboard_fab2(sch_1):page221_i4@mstr_discrete.res(~
chips)',
 P_PATH='@baseboard_fab2_lib.baseboard_fab2(sch_1):page221_i4@mstr_discrete.res(~
chips)',
 PATH='I4',
 DRAWING='@BASEBOARD_FAB2_LIB.BASEBOARD_FAB2(SCH_1):PAGE221',
 WATTAGE='1/16W',
 TOLERANCE='5%',
 SEC_TYPE='0402',
 MATERIAL='CHIP',
 BOM_COST='MEM_VRD_VTT_ABC',
 PHYS_PAGE='221',
 XY='(-800,50)',
 ROT='0',
 VER='1',
 VALUE='0.0',
 PACK_TYPE='0402',
 PART_NUMBER='G21497-005',
 LOCATION='R4G23',
 ROOM='VTT_ABC_PWR_VR',
 SEC='1',
 CDS_LIB='mstr_discrete',
 CDS_PART_NAME='RES_0402-0.0,5%,1/16W,CHIP,G21A',
 PRIM_FILE='./archive_libs/mstr_discrete/res/chips/chips.prt';

PART_NAME
 R4G24 'RES_0603-0,5.0%,1/10W,CHIP,G22A':
 ROOM='NIC_SPRV';

SECTION_NUMBER 1
 '@BASEBOARD_FAB2_LIB.BASEBOARD_FAB2(SCH_1):PAGE233_I282@MSTR_DISCRETE.RES(CHIPS)':
 C_PATH='@baseboard_fab2_lib.baseboard_fab2(sch_1):page233_i282@mstr_discrete.re~
s(chips)',
 P_PATH='@baseboard_fab2_lib.baseboard_fab2(sch_1):page233_i282@mstr_discrete.re~
s(chips)',
 PATH='I282',
 DRAWING='@BASEBOARD_FAB2_LIB.BASEBOARD_FAB2(SCH_1):PAGE233',
 WATTAGE='1/10W',
 TOLERANCE='5.0%',
 SEC_TYPE='0603',
 MATERIAL='CHIP',
 BOM_COST='NT_GBE_BASE',
 PHYS_PAGE='233',
 XY='(-4075,4050)',
 ROT='0',
 VER='1',
 VALUE='0',
 PACK_TYPE='0603',
 PART_NUMBER='G22178-002',
 LOCATION='R4G24',
 ROOM='NIC_SPRV',
 SEC='1',
 CDS_LIB='mstr_discrete',
 CDS_PART_NAME='RES_0603-0,5.0%,1/10W,CHIP,G22A',
 PRIM_FILE='./archive_libs/mstr_discrete/res/chips/chips.prt';

PART_NAME
 R4G25 'RES_0402-0.0,5%,1/16W,CHIP,G21A':
 ROOM='PVPP_KLM_VR';

SECTION_NUMBER 1
 '@BASEBOARD_FAB2_LIB.BASEBOARD_FAB2(SCH_1):PAGE233_I157@MSTR_DISCRETE.RES(CHIPS)':
 C_PATH='@baseboard_fab2_lib.baseboard_fab2(sch_1):page233_i157@mstr_discrete.re~
s(chips)',
 P_PATH='@baseboard_fab2_lib.baseboard_fab2(sch_1):page233_i157@mstr_discrete.re~
s(chips)',
 PATH='I157',
 DRAWING='@BASEBOARD_FAB2_LIB.BASEBOARD_FAB2(SCH_1):PAGE233',
 WATTAGE='1/16W',
 TOLERANCE='5%',
 MATERIAL='CHIP',
 PHYS_PAGE='233',
 XY='(-1100,550)',
 ROT='0',
 VER='1',
 VALUE='0.0',
 PACK_TYPE='0402',
 PART_NUMBER='G21497-005',
 LOCATION='R4G25',
 ROOM='PVPP_KLM_VR',
 CDS_LIB='mstr_discrete',
 CDS_PART_NAME='RES_0402-0.0,5%,1/16W,CHIP,G21A',
 PRIM_FILE='./archive_libs/mstr_discrete/res/chips/chips.prt';

PART_NAME
 R4L2 'RES_0402-100.0,1%,1/16W,EMPTY,A':
 ROOM='VDDQ_DEF_PWR_VR';

SECTION_NUMBER 1
 '@BASEBOARD_FAB2_LIB.BASEBOARD_FAB2(SCH_1):PAGE220_I74@MSTR_DISCRETE.RES(CHIPS)':
 C_PATH='@baseboard_fab2_lib.baseboard_fab2(sch_1):page220_i74@mstr_discrete.res~
(chips)',
 P_PATH='@baseboard_fab2_lib.baseboard_fab2(sch_1):page220_i74@mstr_discrete.res~
(chips)',
 PATH='I74',
 DRAWING='@BASEBOARD_FAB2_LIB.BASEBOARD_FAB2(SCH_1):PAGE220',
 WATTAGE='1/16W',
 TOLERANCE='1%',
 SEC_TYPE='0402',
 MATERIAL='EMPTY',
 PHYS_PAGE='220',
 XY='(-700,1825)',
 ROT='0',
 VER='2',
 VALUE='100.0',
 PACK_TYPE='0402',
 PART_NUMBER='G21796-017',
 LOCATION='R4L2',
 ROOM='VDDQ_DEF_PWR_VR',
 SEC='1',
 CDS_LIB='mstr_discrete',
 CDS_PART_NAME='RES_0402-100.0,1%,1/16W,EMPTY,A',
 PRIM_FILE='./archive_libs/mstr_discrete/res/chips/chips.prt';

PART_NAME
 R4L4 'RES_0603-120.0,1%,1/10W,CHIP,GA':
 ROOM='VDDQ_DEF_PWR_VR';

SECTION_NUMBER 1
 '@BASEBOARD_FAB2_LIB.BASEBOARD_FAB2(SCH_1):PAGE220_I58@MSTR_DISCRETE.RES(CHIPS)':
 C_PATH='@baseboard_fab2_lib.baseboard_fab2(sch_1):page220_i58@mstr_discrete.res~
(chips)',
 P_PATH='@baseboard_fab2_lib.baseboard_fab2(sch_1):page220_i58@mstr_discrete.res~
(chips)',
 PATH='I58',
 DRAWING='@BASEBOARD_FAB2_LIB.BASEBOARD_FAB2(SCH_1):PAGE220',
 WATTAGE='1/10W',
 TOLERANCE='1%',
 MATERIAL='CHIP',
 BOM_COST='MEM_VRD_PVPP_DEF',
 PHYS_PAGE='220',
 XY='(4100,-100)',
 ROT='0',
 VER='2',
 VALUE='120.0',
 PACK_TYPE='0603',
 PART_NUMBER='G22026-003',
 LOCATION='R4L4',
 ROOM='VDDQ_DEF_PWR_VR',
 CDS_LIB='mstr_discrete',
 CDS_PART_NAME='RES_0603-120.0,1%,1/10W,CHIP,GA',
 PRIM_FILE='./archive_libs/mstr_discrete/res/chips/chips.prt';

PART_NAME
 R4P1 'RES_0402-240,1.0%,1/16W,EMPTY,A':
 ROOM='PROC_SIDEBAND';

SECTION_NUMBER 1
 '@BASEBOARD_FAB2_LIB.BASEBOARD_FAB2(SCH_1):PAGE90_I98@MSTR_DISCRETE.RES(CHIPS)':
 C_PATH='@baseboard_fab2_lib.baseboard_fab2(sch_1):page90_i98@mstr_discrete.res(~
chips)',
 P_PATH='@baseboard_fab2_lib.baseboard_fab2(sch_1):page90_i98@mstr_discrete.res(~
chips)',
 PATH='I98',
 DRAWING='@BASEBOARD_FAB2_LIB.BASEBOARD_FAB2(SCH_1):PAGE90',
 WATTAGE='1/16W',
 TOLERANCE='1.0%',
 SEC_TYPE='0402',
 MATERIAL='EMPTY',
 BOM_COST='PROC',
 PHYS_PAGE='90',
 XY='(-575,3200)',
 ROT='0',
 VER='1',
 VALUE='240',
 PACK_TYPE='0402',
 PART_NUMBER='G21796-294',
 LOCATION='R4P1',
 ROOM='PROC_SIDEBAND',
 SEC='1',
 CDS_LIB='mstr_discrete',
 CDS_PART_NAME='RES_0402-240,1.0%,1/16W,EMPTY,A',
 PRIM_FILE='./archive_libs/mstr_discrete/res/chips/chips.prt';

PART_NAME
 R4P2 'RES_0402-49.9,1%,1/16W,CHIP,G2A':
 ROOM='CPU0';

SECTION_NUMBER 1
 '@BASEBOARD_FAB2_LIB.BASEBOARD_FAB2(SCH_1):PAGE21_I188@MSTR_DISCRETE.RES(CHIPS)':
 C_PATH='@baseboard_fab2_lib.baseboard_fab2(sch_1):page21_i188@mstr_discrete.res~
(chips)',
 P_PATH='@baseboard_fab2_lib.baseboard_fab2(sch_1):page21_i188@mstr_discrete.res~
(chips)',
 PATH='I188',
 DRAWING='@BASEBOARD_FAB2_LIB.BASEBOARD_FAB2(SCH_1):PAGE21',
 WATTAGE='1/16W',
 TOLERANCE='1%',
 SEC_TYPE='0402',
 MATERIAL='CHIP',
 BOM_COST='PROC_SOCKET',
 PHYS_PAGE='21',
 XY='(-7800,2200)',
 ROT='2',
 VER='2',
 VALUE='49.9',
 PACK_TYPE='0402',
 PART_NUMBER='G21796-047',
 LOCATION='R4P2',
 ROOM='CPU0',
 SEC='1',
 CDS_LIB='mstr_discrete',
 CDS_PART_NAME='RES_0402-49.9,1%,1/16W,CHIP,G2A',
 PRIM_FILE='./archive_libs/mstr_discrete/res/chips/chips.prt';

PART_NAME
 R4P3 'RES_0402-49.9,1%,1/16W,CHIP,G2A':
 ROOM='CPU0';

SECTION_NUMBER 1
 '@BASEBOARD_FAB2_LIB.BASEBOARD_FAB2(SCH_1):PAGE21_I186@MSTR_DISCRETE.RES(CHIPS)':
 C_PATH='@baseboard_fab2_lib.baseboard_fab2(sch_1):page21_i186@mstr_discrete.res~
(chips)',
 P_PATH='@baseboard_fab2_lib.baseboard_fab2(sch_1):page21_i186@mstr_discrete.res~
(chips)',
 PATH='I186',
 DRAWING='@BASEBOARD_FAB2_LIB.BASEBOARD_FAB2(SCH_1):PAGE21',
 WATTAGE='1/16W',
 TOLERANCE='1%',
 SEC_TYPE='0402',
 MATERIAL='CHIP',
 BOM_COST='PROC_SOCKET',
 PHYS_PAGE='21',
 XY='(-7575,2100)',
 ROT='2',
 VER='2',
 VALUE='49.9',
 PACK_TYPE='0402',
 PART_NUMBER='G21796-047',
 LOCATION='R4P3',
 ROOM='CPU0',
 SEC='1',
 CDS_LIB='mstr_discrete',
 CDS_PART_NAME='RES_0402-49.9,1%,1/16W,CHIP,G2A',
 PRIM_FILE='./archive_libs/mstr_discrete/res/chips/chips.prt';

PART_NAME
 R4P4 'RES_0402-49.9,1%,1/16W,CHIP,G2A':
 ROOM='CPU0';

SECTION_NUMBER 1
 '@BASEBOARD_FAB2_LIB.BASEBOARD_FAB2(SCH_1):PAGE21_I189@MSTR_DISCRETE.RES(CHIPS)':
 C_PATH='@baseboard_fab2_lib.baseboard_fab2(sch_1):page21_i189@mstr_discrete.res~
(chips)',
 P_PATH='@baseboard_fab2_lib.baseboard_fab2(sch_1):page21_i189@mstr_discrete.res~
(chips)',
 PATH='I189',
 DRAWING='@BASEBOARD_FAB2_LIB.BASEBOARD_FAB2(SCH_1):PAGE21',
 WATTAGE='1/16W',
 TOLERANCE='1%',
 SEC_TYPE='0402',
 MATERIAL='CHIP',
 BOM_COST='PROC_SOCKET',
 PHYS_PAGE='21',
 XY='(-7125,2000)',
 ROT='2',
 VER='2',
 VALUE='49.9',
 PACK_TYPE='0402',
 PART_NUMBER='G21796-047',
 LOCATION='R4P4',
 ROOM='CPU0',
 SEC='1',
 CDS_LIB='mstr_discrete',
 CDS_PART_NAME='RES_0402-49.9,1%,1/16W,CHIP,G2A',
 PRIM_FILE='./archive_libs/mstr_discrete/res/chips/chips.prt';

PART_NAME
 R4P5 'RES_0402-10.0K,1%,1/16W,CHIP,GA':
 ROOM='CPU0';

SECTION_NUMBER 1
 '@BASEBOARD_FAB2_LIB.BASEBOARD_FAB2(SCH_1):PAGE97_I80@MSTR_DISCRETE.RES(CHIPS)':
 C_PATH='@baseboard_fab2_lib.baseboard_fab2(sch_1):page97_i80@mstr_discrete.res(~
chips)',
 P_PATH='@baseboard_fab2_lib.baseboard_fab2(sch_1):page97_i80@mstr_discrete.res(~
chips)',
 PATH='I80',
 DRAWING='@BASEBOARD_FAB2_LIB.BASEBOARD_FAB2(SCH_1):PAGE97',
 WATTAGE='1/16W',
 TOLERANCE='1%',
 SEC_TYPE='0402',
 MATERIAL='CHIP',
 PHYS_PAGE='97',
 XY='(-2375,3175)',
 ROT='0',
 VER='1',
 VALUE='10.0K',
 PACK_TYPE='0402',
 PART_NUMBER='G21796-016',
 LOCATION='R4P5',
 ROOM='CPU0',
 SEC='1',
 CDS_LIB='mstr_discrete',
 CDS_PART_NAME='RES_0402-10.0K,1%,1/16W,CHIP,GA',
 PRIM_FILE='./archive_libs/mstr_discrete/res/chips/chips.prt';

PART_NAME
 R4P6 'RES_0402-240,1.0%,1/16W,EMPTY,A':
 ROOM='PROC_SIDEBAND';

SECTION_NUMBER 1
 '@BASEBOARD_FAB2_LIB.BASEBOARD_FAB2(SCH_1):PAGE90_I68@MSTR_DISCRETE.RES(CHIPS)':
 C_PATH='@baseboard_fab2_lib.baseboard_fab2(sch_1):page90_i68@mstr_discrete.res(~
chips)',
 P_PATH='@baseboard_fab2_lib.baseboard_fab2(sch_1):page90_i68@mstr_discrete.res(~
chips)',
 PATH='I68',
 DRAWING='@BASEBOARD_FAB2_LIB.BASEBOARD_FAB2(SCH_1):PAGE90',
 WATTAGE='1/16W',
 TOLERANCE='1.0%',
 SEC_TYPE='0402',
 MATERIAL='EMPTY',
 BOM_COST='PROC',
 PHYS_PAGE='90',
 XY='(-575,3000)',
 ROT='0',
 VER='1',
 VALUE='240',
 PACK_TYPE='0402',
 PART_NUMBER='G21796-294',
 LOCATION='R4P6',
 ROOM='PROC_SIDEBAND',
 SEC='1',
 CDS_LIB='mstr_discrete',
 CDS_PART_NAME='RES_0402-240,1.0%,1/16W,EMPTY,A',
 PRIM_FILE='./archive_libs/mstr_discrete/res/chips/chips.prt';

PART_NAME
 R4P7 'RES_0402-240,1.0%,1/16W,EMPTY,A':
 ROOM='PROC_SIDEBAND';

SECTION_NUMBER 1
 '@BASEBOARD_FAB2_LIB.BASEBOARD_FAB2(SCH_1):PAGE90_I72@MSTR_DISCRETE.RES(CHIPS)':
 C_PATH='@baseboard_fab2_lib.baseboard_fab2(sch_1):page90_i72@mstr_discrete.res(~
chips)',
 P_PATH='@baseboard_fab2_lib.baseboard_fab2(sch_1):page90_i72@mstr_discrete.res(~
chips)',
 PATH='I72',
 DRAWING='@BASEBOARD_FAB2_LIB.BASEBOARD_FAB2(SCH_1):PAGE90',
 WATTAGE='1/16W',
 TOLERANCE='1.0%',
 SEC_TYPE='0402',
 MATERIAL='EMPTY',
 BOM_COST='PROC',
 PHYS_PAGE='90',
 XY='(-575,2800)',
 ROT='0',
 VER='1',
 VALUE='240',
 PACK_TYPE='0402',
 PART_NUMBER='G21796-294',
 LOCATION='R4P7',
 ROOM='PROC_SIDEBAND',
 SEC='1',
 CDS_LIB='mstr_discrete',
 CDS_PART_NAME='RES_0402-240,1.0%,1/16W,EMPTY,A',
 PRIM_FILE='./archive_libs/mstr_discrete/res/chips/chips.prt';

PART_NAME
 R4P8 'RES_0402-90.9,1%,1/16W,CHIP,G2A':
 ROOM='CPU0';

SECTION_NUMBER 1
 '@BASEBOARD_FAB2_LIB.BASEBOARD_FAB2(SCH_1):PAGE21_I180@MSTR_DISCRETE.RES(CHIPS)':
 C_PATH='@baseboard_fab2_lib.baseboard_fab2(sch_1):page21_i180@mstr_discrete.res~
(chips)',
 P_PATH='@baseboard_fab2_lib.baseboard_fab2(sch_1):page21_i180@mstr_discrete.res~
(chips)',
 PATH='I180',
 DRAWING='@BASEBOARD_FAB2_LIB.BASEBOARD_FAB2(SCH_1):PAGE21',
 WATTAGE='1/16W',
 TOLERANCE='1%',
 SEC_TYPE='0402',
 MATERIAL='CHIP',
 BOM_COST='PROC_SOCKET',
 PHYS_PAGE='21',
 XY='(-7350,2925)',
 ROT='2',
 VER='2',
 VALUE='90.9',
 PACK_TYPE='0402',
 PART_NUMBER='G21796-365',
 LOCATION='R4P8',
 ROOM='CPU0',
 SEC='1',
 CDS_LIB='mstr_discrete',
 CDS_PART_NAME='RES_0402-90.9,1%,1/16W,CHIP,G2A',
 PRIM_FILE='./archive_libs/mstr_discrete/res/chips/chips.prt';

PART_NAME
 R4P10 'RES_0402-90.9,1%,1/16W,CHIP,G2A':
 ROOM='CPU0';

SECTION_NUMBER 1
 '@BASEBOARD_FAB2_LIB.BASEBOARD_FAB2(SCH_1):PAGE21_I181@MSTR_DISCRETE.RES(CHIPS)':
 C_PATH='@baseboard_fab2_lib.baseboard_fab2(sch_1):page21_i181@mstr_discrete.res~
(chips)',
 P_PATH='@baseboard_fab2_lib.baseboard_fab2(sch_1):page21_i181@mstr_discrete.res~
(chips)',
 PATH='I181',
 DRAWING='@BASEBOARD_FAB2_LIB.BASEBOARD_FAB2(SCH_1):PAGE21',
 WATTAGE='1/16W',
 TOLERANCE='1%',
 SEC_TYPE='0402',
 MATERIAL='CHIP',
 BOM_COST='PROC_SOCKET',
 PHYS_PAGE='21',
 XY='(-7575,3000)',
 ROT='2',
 VER='2',
 VALUE='90.9',
 PACK_TYPE='0402',
 PART_NUMBER='G21796-365',
 LOCATION='R4P10',
 ROOM='CPU0',
 SEC='1',
 CDS_LIB='mstr_discrete',
 CDS_PART_NAME='RES_0402-90.9,1%,1/16W,CHIP,G2A',
 PRIM_FILE='./archive_libs/mstr_discrete/res/chips/chips.prt';

PART_NAME
 R4P11 'RES_0402-100.0,1%,1/16W,CHIP,GA':
 ROOM='CPU0';

SECTION_NUMBER 1
 '@BASEBOARD_FAB2_LIB.BASEBOARD_FAB2(SCH_1):PAGE21_I182@MSTR_DISCRETE.RES(CHIPS)':
 C_PATH='@baseboard_fab2_lib.baseboard_fab2(sch_1):page21_i182@mstr_discrete.res~
(chips)',
 P_PATH='@baseboard_fab2_lib.baseboard_fab2(sch_1):page21_i182@mstr_discrete.res~
(chips)',
 PATH='I182',
 DRAWING='@BASEBOARD_FAB2_LIB.BASEBOARD_FAB2(SCH_1):PAGE21',
 WATTAGE='1/16W',
 TOLERANCE='1%',
 SEC_TYPE='0402',
 MATERIAL='CHIP',
 BOM_COST='PROC_SOCKET',
 PHYS_PAGE='21',
 XY='(-7800,3000)',
 ROT='2',
 VER='2',
 VALUE='100.0',
 PACK_TYPE='0402',
 PART_NUMBER='G21796-017',
 LOCATION='R4P11',
 ROOM='CPU0',
 SEC='1',
 CDS_LIB='mstr_discrete',
 CDS_PART_NAME='RES_0402-100.0,1%,1/16W,CHIP,GA',
 PRIM_FILE='./archive_libs/mstr_discrete/res/chips/chips.prt';

PART_NAME
 R4P12 'RES_0402-100.0,1%,1/16W,CHIP,GA':
 ROOM='DEBUG';

SECTION_NUMBER 1
 '@BASEBOARD_FAB2_LIB.BASEBOARD_FAB2(SCH_1):PAGE112_I57@MSTR_DISCRETE.RES(CHIPS)':
 C_PATH='@baseboard_fab2_lib.baseboard_fab2(sch_1):page112_i57@mstr_discrete.res~
(chips)',
 P_PATH='@baseboard_fab2_lib.baseboard_fab2(sch_1):page112_i57@mstr_discrete.res~
(chips)',
 PATH='I57',
 DRAWING='@BASEBOARD_FAB2_LIB.BASEBOARD_FAB2(SCH_1):PAGE112',
 WATTAGE='1/16W',
 TOLERANCE='1%',
 SEC_TYPE='0402',
 MATERIAL='CHIP',
 PHYS_PAGE='112',
 XY='(875,3825)',
 ROT='0',
 VER='2',
 VALUE='100.0',
 PACK_TYPE='0402',
 PART_NUMBER='G21796-017',
 LOCATION='R4P12',
 ROOM='DEBUG',
 SEC='1',
 CDS_LIB='mstr_discrete',
 CDS_PART_NAME='RES_0402-100.0,1%,1/16W,CHIP,GA',
 PRIM_FILE='./archive_libs/mstr_discrete/res/chips/chips.prt';

PART_NAME
 R4P14 'RES_0402-240,1.0%,1/16W,CHIP,GA':
 ROOM='PROC_SIDEBAND';

SECTION_NUMBER 1
 '@BASEBOARD_FAB2_LIB.BASEBOARD_FAB2(SCH_1):PAGE90_I53@MSTR_DISCRETE.RES(CHIPS)':
 C_PATH='@baseboard_fab2_lib.baseboard_fab2(sch_1):page90_i53@mstr_discrete.res(~
chips)',
 P_PATH='@baseboard_fab2_lib.baseboard_fab2(sch_1):page90_i53@mstr_discrete.res(~
chips)',
 PATH='I53',
 DRAWING='@BASEBOARD_FAB2_LIB.BASEBOARD_FAB2(SCH_1):PAGE90',
 WATTAGE='1/16W',
 TOLERANCE='1.0%',
 SEC_TYPE='0402',
 MATERIAL='CHIP',
 BOM_COST='PROC',
 PHYS_PAGE='90',
 XY='(-2475,3400)',
 ROT='0',
 VER='1',
 VALUE='240',
 PACK_TYPE='0402',
 PART_NUMBER='G21796-294',
 LOCATION='R4P14',
 ROOM='PROC_SIDEBAND',
 SEC='1',
 CDS_LIB='mstr_discrete',
 CDS_PART_NAME='RES_0402-240,1.0%,1/16W,CHIP,GA',
 PRIM_FILE='./archive_libs/mstr_discrete/res/chips/chips.prt';

PART_NAME
 R4P15 'RES_0402-100.0,1%,1/16W,CHIP,GA':
 ROOM='DEBUG';

SECTION_NUMBER 1
 '@BASEBOARD_FAB2_LIB.BASEBOARD_FAB2(SCH_1):PAGE112_I53@MSTR_DISCRETE.RES(CHIPS)':
 C_PATH='@baseboard_fab2_lib.baseboard_fab2(sch_1):page112_i53@mstr_discrete.res~
(chips)',
 P_PATH='@baseboard_fab2_lib.baseboard_fab2(sch_1):page112_i53@mstr_discrete.res~
(chips)',
 PATH='I53',
 DRAWING='@BASEBOARD_FAB2_LIB.BASEBOARD_FAB2(SCH_1):PAGE112',
 WATTAGE='1/16W',
 TOLERANCE='1%',
 SEC_TYPE='0402',
 MATERIAL='CHIP',
 PHYS_PAGE='112',
 XY='(1175,3800)',
 ROT='0',
 VER='2',
 VALUE='100.0',
 PACK_TYPE='0402',
 PART_NUMBER='G21796-017',
 LOCATION='R4P15',
 ROOM='DEBUG',
 SEC='1',
 CDS_LIB='mstr_discrete',
 CDS_PART_NAME='RES_0402-100.0,1%,1/16W,CHIP,GA',
 PRIM_FILE='./archive_libs/mstr_discrete/res/chips/chips.prt';

PART_NAME
 R4P17 'RES_0402-150.0,1%,1/16W,CHIP,GA':
 ROOM='PROC_SIDEBAND';

SECTION_NUMBER 1
 '@BASEBOARD_FAB2_LIB.BASEBOARD_FAB2(SCH_1):PAGE152_I58@MSTR_DISCRETE.RES(CHIPS)':
 C_PATH='@baseboard_fab2_lib.baseboard_fab2(sch_1):page152_i58@mstr_discrete.res~
(chips)',
 P_PATH='@baseboard_fab2_lib.baseboard_fab2(sch_1):page152_i58@mstr_discrete.res~
(chips)',
 PATH='I58',
 DRAWING='@BASEBOARD_FAB2_LIB.BASEBOARD_FAB2(SCH_1):PAGE152',
 WATTAGE='1/16W',
 TOLERANCE='1%',
 SEC_TYPE='0402',
 MATERIAL='CHIP',
 BOM_COST='PROC_SIDEBAND',
 PHYS_PAGE='152',
 XY='(-7800,3250)',
 ROT='0',
 VER='2',
 VALUE='150.0',
 PACK_TYPE='0402',
 PART_NUMBER='G21796-009',
 LOCATION='R4P17',
 ROOM='PROC_SIDEBAND',
 SEC='1',
 CDS_LIB='mstr_discrete',
 CDS_PART_NAME='RES_0402-150.0,1%,1/16W,CHIP,GA',
 PRIM_FILE='./archive_libs/mstr_discrete/res/chips/chips.prt';

PART_NAME
 R4P18 'RES_0402-49.9,1%,1/16W,CHIP,G2A':
 ROOM='CPU0';

SECTION_NUMBER 1
 '@BASEBOARD_FAB2_LIB.BASEBOARD_FAB2(SCH_1):PAGE21_I244@MSTR_DISCRETE.RES(CHIPS)':
 C_PATH='@baseboard_fab2_lib.baseboard_fab2(sch_1):page21_i244@mstr_discrete.res~
(chips)',
 P_PATH='@baseboard_fab2_lib.baseboard_fab2(sch_1):page21_i244@mstr_discrete.res~
(chips)',
 PATH='I244',
 DRAWING='@BASEBOARD_FAB2_LIB.BASEBOARD_FAB2(SCH_1):PAGE21',
 WATTAGE='1/16W',
 TOLERANCE='1%',
 SEC_TYPE='0402',
 MATERIAL='CHIP',
 BOM_COST='PROC_SIDEBAND',
 PHYS_PAGE='21',
 XY='(-2075,4250)',
 ROT='0',
 VER='1',
 VALUE='49.9',
 PACK_TYPE='0402',
 PART_NUMBER='G21796-047',
 LOCATION='R4P18',
 ROOM='CPU0',
 SEC='1',
 CDS_LIB='mstr_discrete',
 CDS_PART_NAME='RES_0402-49.9,1%,1/16W,CHIP,G2A',
 PRIM_FILE='./archive_libs/mstr_discrete/res/chips/chips.prt';

PART_NAME
 R4P19 'RES_0402-49.9,1%,1/16W,CHIP,G2A':
 ROOM='CPU0';

SECTION_NUMBER 1
 '@BASEBOARD_FAB2_LIB.BASEBOARD_FAB2(SCH_1):PAGE21_I219@MSTR_DISCRETE.RES(CHIPS)':
 C_PATH='@baseboard_fab2_lib.baseboard_fab2(sch_1):page21_i219@mstr_discrete.res~
(chips)',
 P_PATH='@baseboard_fab2_lib.baseboard_fab2(sch_1):page21_i219@mstr_discrete.res~
(chips)',
 PATH='I219',
 DRAWING='@BASEBOARD_FAB2_LIB.BASEBOARD_FAB2(SCH_1):PAGE21',
 WATTAGE='1/16W',
 TOLERANCE='1%',
 SEC_TYPE='0402',
 MATERIAL='CHIP',
 BOM_COST='PROC_SOCKET',
 PHYS_PAGE='21',
 XY='(-2075,4200)',
 ROT='0',
 VER='1',
 VALUE='49.9',
 PACK_TYPE='0402',
 PART_NUMBER='G21796-047',
 LOCATION='R4P19',
 ROOM='CPU0',
 SEC='1',
 CDS_LIB='mstr_discrete',
 CDS_PART_NAME='RES_0402-49.9,1%,1/16W,CHIP,G2A',
 PRIM_FILE='./archive_libs/mstr_discrete/res/chips/chips.prt';

PART_NAME
 R4P20 'RES_0402-150.0,1%,1/16W,CHIP,GA':
 ROOM='PROC_SIDEBAND';

SECTION_NUMBER 1
 '@BASEBOARD_FAB2_LIB.BASEBOARD_FAB2(SCH_1):PAGE152_I59@MSTR_DISCRETE.RES(CHIPS)':
 C_PATH='@baseboard_fab2_lib.baseboard_fab2(sch_1):page152_i59@mstr_discrete.res~
(chips)',
 P_PATH='@baseboard_fab2_lib.baseboard_fab2(sch_1):page152_i59@mstr_discrete.res~
(chips)',
 PATH='I59',
 DRAWING='@BASEBOARD_FAB2_LIB.BASEBOARD_FAB2(SCH_1):PAGE152',
 WATTAGE='1/16W',
 TOLERANCE='1%',
 SEC_TYPE='0402',
 MATERIAL='CHIP',
 BOM_COST='PROC_SIDEBAND',
 PHYS_PAGE='152',
 XY='(-7900,3250)',
 ROT='2',
 VER='2',
 VALUE='150.0',
 PACK_TYPE='0402',
 PART_NUMBER='G21796-009',
 LOCATION='R4P20',
 ROOM='PROC_SIDEBAND',
 SEC='1',
 CDS_LIB='mstr_discrete',
 CDS_PART_NAME='RES_0402-150.0,1%,1/16W,CHIP,GA',
 PRIM_FILE='./archive_libs/mstr_discrete/res/chips/chips.prt';

PART_NAME
 R4P21 'RES_0402-240,1.0%,1/16W,CHIP,GA':
 ROOM='PROC_SIDEBAND';

SECTION_NUMBER 1
 '@BASEBOARD_FAB2_LIB.BASEBOARD_FAB2(SCH_1):PAGE97_I72@MSTR_DISCRETE.RES(CHIPS)':
 C_PATH='@baseboard_fab2_lib.baseboard_fab2(sch_1):page97_i72@mstr_discrete.res(~
chips)',
 P_PATH='@baseboard_fab2_lib.baseboard_fab2(sch_1):page97_i72@mstr_discrete.res(~
chips)',
 PATH='I72',
 DRAWING='@BASEBOARD_FAB2_LIB.BASEBOARD_FAB2(SCH_1):PAGE97',
 WATTAGE='1/16W',
 TOLERANCE='1.0%',
 SEC_TYPE='0402',
 MATERIAL='CHIP',
 BOM_COST='PROC_SIDEBAND',
 PHYS_PAGE='97',
 XY='(-2625,1425)',
 ROT='0',
 VER='1',
 VALUE='240',
 PACK_TYPE='0402',
 PART_NUMBER='G21796-294',
 LOCATION='R4P21',
 ROOM='PROC_SIDEBAND',
 SEC='1',
 CDS_LIB='mstr_discrete',
 CDS_PART_NAME='RES_0402-240,1.0%,1/16W,CHIP,GA',
 PRIM_FILE='./archive_libs/mstr_discrete/res/chips/chips.prt';

PART_NAME
 R4P23 'RES_0402-150.0,1%,1/16W,CHIP,GA':
 ROOM='DEBUG';

SECTION_NUMBER 1
 '@BASEBOARD_FAB2_LIB.BASEBOARD_FAB2(SCH_1):PAGE112_I58@MSTR_DISCRETE.RES(CHIPS)':
 C_PATH='@baseboard_fab2_lib.baseboard_fab2(sch_1):page112_i58@mstr_discrete.res~
(chips)',
 P_PATH='@baseboard_fab2_lib.baseboard_fab2(sch_1):page112_i58@mstr_discrete.res~
(chips)',
 PATH='I58',
 DRAWING='@BASEBOARD_FAB2_LIB.BASEBOARD_FAB2(SCH_1):PAGE112',
 WATTAGE='1/16W',
 TOLERANCE='1%',
 SEC_TYPE='0402',
 MATERIAL='CHIP',
 PHYS_PAGE='112',
 XY='(575,3800)',
 ROT='0',
 VER='2',
 VALUE='150.0',
 PACK_TYPE='0402',
 PART_NUMBER='G21796-009',
 LOCATION='R4P23',
 ROOM='DEBUG',
 SEC='1',
 CDS_LIB='mstr_discrete',
 CDS_PART_NAME='RES_0402-150.0,1%,1/16W,CHIP,GA',
 PRIM_FILE='./archive_libs/mstr_discrete/res/chips/chips.prt';

PART_NAME
 R4P24 'RES_0402-150.0,1%,1/16W,CHIP,GA':
 ROOM='DEBUG';

SECTION_NUMBER 1
 '@BASEBOARD_FAB2_LIB.BASEBOARD_FAB2(SCH_1):PAGE112_I59@MSTR_DISCRETE.RES(CHIPS)':
 C_PATH='@baseboard_fab2_lib.baseboard_fab2(sch_1):page112_i59@mstr_discrete.res~
(chips)',
 P_PATH='@baseboard_fab2_lib.baseboard_fab2(sch_1):page112_i59@mstr_discrete.res~
(chips)',
 PATH='I59',
 DRAWING='@BASEBOARD_FAB2_LIB.BASEBOARD_FAB2(SCH_1):PAGE112',
 WATTAGE='1/16W',
 TOLERANCE='1%',
 SEC_TYPE='0402',
 MATERIAL='CHIP',
 PHYS_PAGE='112',
 XY='(275,3800)',
 ROT='0',
 VER='2',
 VALUE='150.0',
 PACK_TYPE='0402',
 PART_NUMBER='G21796-009',
 LOCATION='R4P24',
 ROOM='DEBUG',
 SEC='1',
 CDS_LIB='mstr_discrete',
 CDS_PART_NAME='RES_0402-150.0,1%,1/16W,CHIP,GA',
 PRIM_FILE='./archive_libs/mstr_discrete/res/chips/chips.prt';

PART_NAME
 R4R1 'RES_0402-1.00K,1%,1/16W,CHIP,GA':
 ROOM='MIO_CHASSIS';

SECTION_NUMBER 1
 '@BASEBOARD_FAB2_LIB.BASEBOARD_FAB2(SCH_1):PAGE157_I368@MSTR_DISCRETE.RES(CHIPS)':
 C_PATH='@baseboard_fab2_lib.baseboard_fab2(sch_1):page157_i368@mstr_discrete.re~
s(chips)',
 P_PATH='@baseboard_fab2_lib.baseboard_fab2(sch_1):page157_i368@mstr_discrete.re~
s(chips)',
 PATH='I368',
 DRAWING='@BASEBOARD_FAB2_LIB.BASEBOARD_FAB2(SCH_1):PAGE157',
 WATTAGE='1/16W',
 TOLERANCE='1%',
 SEC_TYPE='0402',
 MATERIAL='CHIP',
 BOM_COST='MIO_CHASSIS',
 PHYS_PAGE='157',
 XY='(-6975,775)',
 ROT='0',
 VER='1',
 VALUE='1.00K',
 PACK_TYPE='0402',
 PART_NUMBER='G21796-026',
 LOCATION='R4R1',
 ROOM='MIO_CHASSIS',
 SEC='1',
 CDS_LIB='mstr_discrete',
 CDS_PART_NAME='RES_0402-1.00K,1%,1/16W,CHIP,GA',
 PRIM_FILE='./archive_libs/mstr_discrete/res/chips/chips.prt';

PART_NAME
 R4R2 'RES_0402-150.0,1%,1/16W,CHIP,GA':
 ROOM='PROC_SIDEBAND';

SECTION_NUMBER 1
 '@BASEBOARD_FAB2_LIB.BASEBOARD_FAB2(SCH_1):PAGE92_I101@MSTR_DISCRETE.RES(CHIPS)':
 C_PATH='@baseboard_fab2_lib.baseboard_fab2(sch_1):page92_i101@mstr_discrete.res~
(chips)',
 P_PATH='@baseboard_fab2_lib.baseboard_fab2(sch_1):page92_i101@mstr_discrete.res~
(chips)',
 PATH='I101',
 DRAWING='@BASEBOARD_FAB2_LIB.BASEBOARD_FAB2(SCH_1):PAGE92',
 WATTAGE='1/16W',
 TOLERANCE='1%',
 SEC_TYPE='0402',
 MATERIAL='CHIP',
 BOM_COST='PROC',
 PHYS_PAGE='92',
 XY='(-4450,4600)',
 ROT='2',
 VER='2',
 VALUE='150.0',
 PACK_TYPE='0402',
 PART_NUMBER='G21796-009',
 LOCATION='R4R2',
 ROOM='PROC_SIDEBAND',
 SEC='1',
 CDS_LIB='mstr_discrete',
 CDS_PART_NAME='RES_0402-150.0,1%,1/16W,CHIP,GA',
 PRIM_FILE='./archive_libs/mstr_discrete/res/chips/chips.prt';

PART_NAME
 R4R3 'RES_0402-150.0,1%,1/16W,CHIP,GA':
 ROOM='PROC_SIDEBAND';

SECTION_NUMBER 1
 '@BASEBOARD_FAB2_LIB.BASEBOARD_FAB2(SCH_1):PAGE93_I79@MSTR_DISCRETE.RES(CHIPS)':
 C_PATH='@baseboard_fab2_lib.baseboard_fab2(sch_1):page93_i79@mstr_discrete.res(~
chips)',
 P_PATH='@baseboard_fab2_lib.baseboard_fab2(sch_1):page93_i79@mstr_discrete.res(~
chips)',
 PATH='I79',
 DRAWING='@BASEBOARD_FAB2_LIB.BASEBOARD_FAB2(SCH_1):PAGE93',
 WATTAGE='1/16W',
 TOLERANCE='1%',
 SEC_TYPE='0402',
 MATERIAL='CHIP',
 BOM_COST='PROC_SIDEBAND',
 PHYS_PAGE='93',
 XY='(-2750,2525)',
 ROT='0',
 VER='2',
 VALUE='150.0',
 PACK_TYPE='0402',
 PART_NUMBER='G21796-009',
 LOCATION='R4R3',
 ROOM='PROC_SIDEBAND',
 SEC='1',
 CDS_LIB='mstr_discrete',
 CDS_PART_NAME='RES_0402-150.0,1%,1/16W,CHIP,GA',
 PRIM_FILE='./archive_libs/mstr_discrete/res/chips/chips.prt';

PART_NAME
 R4R4 'RES_0402-150.0,1%,1/16W,CHIP,GA':
 ROOM='PROC_SIDEBAND';

SECTION_NUMBER 1
 '@BASEBOARD_FAB2_LIB.BASEBOARD_FAB2(SCH_1):PAGE97_I42@MSTR_DISCRETE.RES(CHIPS)':
 C_PATH='@baseboard_fab2_lib.baseboard_fab2(sch_1):page97_i42@mstr_discrete.res(~
chips)',
 P_PATH='@baseboard_fab2_lib.baseboard_fab2(sch_1):page97_i42@mstr_discrete.res(~
chips)',
 PATH='I42',
 DRAWING='@BASEBOARD_FAB2_LIB.BASEBOARD_FAB2(SCH_1):PAGE97',
 WATTAGE='1/16W',
 TOLERANCE='1%',
 MATERIAL='CHIP',
 PHYS_PAGE='97',
 XY='(-2700,4525)',
 ROT='0',
 VER='2',
 VALUE='150.0',
 PACK_TYPE='0402',
 PART_NUMBER='G21796-009',
 LOCATION='R4R4',
 ROOM='PROC_SIDEBAND',
 CDS_LIB='mstr_discrete',
 CDS_PART_NAME='RES_0402-150.0,1%,1/16W,CHIP,GA',
 PRIM_FILE='./archive_libs/mstr_discrete/res/chips/chips.prt';

PART_NAME
 R4R5 'RES_0402-4.75K,1%,1/16W,CHIP,GA':
 ROOM='CPU0';

SECTION_NUMBER 1
 '@BASEBOARD_FAB2_LIB.BASEBOARD_FAB2(SCH_1):PAGE21_I258@MSTR_DISCRETE.RES(CHIPS)':
 C_PATH='@baseboard_fab2_lib.baseboard_fab2(sch_1):page21_i258@mstr_discrete.res~
(chips)',
 P_PATH='@baseboard_fab2_lib.baseboard_fab2(sch_1):page21_i258@mstr_discrete.res~
(chips)',
 PATH='I258',
 DRAWING='@BASEBOARD_FAB2_LIB.BASEBOARD_FAB2(SCH_1):PAGE21',
 WATTAGE='1/16W',
 TOLERANCE='1%',
 SEC_TYPE='0402',
 MATERIAL='CHIP',
 PHYS_PAGE='21',
 XY='(-1075,1450)',
 ROT='0',
 VER='2',
 VALUE='4.75K',
 PACK_TYPE='0402',
 PART_NUMBER='G21796-072',
 LOCATION='R4R5',
 ROOM='CPU0',
 SEC='1',
 CDS_LIB='mstr_discrete',
 CDS_PART_NAME='RES_0402-4.75K,1%,1/16W,CHIP,GA',
 PRIM_FILE='./archive_libs/mstr_discrete/res/chips/chips.prt';

PART_NAME
 R4R6 'RES_0402-1.00K,1%,1/16W,CHIP,GA':
 GROUP='MCP',
 ROOM='PROC_SIDEBAND';

SECTION_NUMBER 1
 '@BASEBOARD_FAB2_LIB.BASEBOARD_FAB2(SCH_1):PAGE113_I270@MSTR_DISCRETE.RES(CHIPS)':
 C_PATH='@baseboard_fab2_lib.baseboard_fab2(sch_1):page113_i270@mstr_discrete.re~
s(chips)',
 P_PATH='@baseboard_fab2_lib.baseboard_fab2(sch_1):page113_i270@mstr_discrete.re~
s(chips)',
 PATH='I270',
 DRAWING='@BASEBOARD_FAB2_LIB.BASEBOARD_FAB2(SCH_1):PAGE113',
 WATTAGE='1/16W',
 TOLERANCE='1%',
 SEC_TYPE='0402',
 MATERIAL='CHIP',
 PHYS_PAGE='113',
 XY='(2450,3200)',
 ROT='0',
 VER='2',
 VALUE='1.00K',
 PACK_TYPE='0402',
 PART_NUMBER='G21796-026',
 LOCATION='R4R6',
 ROOM='PROC_SIDEBAND',
 GROUP='MCP',
 SEC='1',
 CDS_LIB='mstr_discrete',
 CDS_PART_NAME='RES_0402-1.00K,1%,1/16W,CHIP,GA',
 PRIM_FILE='./archive_libs/mstr_discrete/res/chips/chips.prt';

PART_NAME
 R4T1 'RES_0402-0.0,5%,1/16W,CHIP,G21A':
 ROOM='NV_DIMM';

SECTION_NUMBER 1
 '@BASEBOARD_FAB2_LIB.BASEBOARD_FAB2(SCH_1):PAGE89_I2@MSTR_DISCRETE.RES(CHIPS)':
 C_PATH='@baseboard_fab2_lib.baseboard_fab2(sch_1):page89_i2@mstr_discrete.res(c~
hips)',
 P_PATH='@baseboard_fab2_lib.baseboard_fab2(sch_1):page89_i2@mstr_discrete.res(c~
hips)',
 PATH='I2',
 DRAWING='@BASEBOARD_FAB2_LIB.BASEBOARD_FAB2(SCH_1):PAGE89',
 WATTAGE='1/16W',
 TOLERANCE='5%',
 SEC_TYPE='0402',
 MATERIAL='CHIP',
 BOM_COST='MEM_NV',
 PHYS_PAGE='89',
 XY='(-2250,2725)',
 ROT='0',
 VER='1',
 VALUE='0.0',
 PACK_TYPE='0402',
 PART_NUMBER='G21497-005',
 LOCATION='R4T1',
 ROOM='NV_DIMM',
 SEC='1',
 CDS_LIB='mstr_discrete',
 CDS_PART_NAME='RES_0402-0.0,5%,1/16W,CHIP,G21A',
 PRIM_FILE='./archive_libs/mstr_discrete/res/chips/chips.prt';

PART_NAME
 R4T2 'RES_0402-0.0,5%,1/16W,EMPTY,G2A':
 ROOM='NV_DIMM';

SECTION_NUMBER 1
 '@BASEBOARD_FAB2_LIB.BASEBOARD_FAB2(SCH_1):PAGE89_I1@MSTR_DISCRETE.RES(CHIPS)':
 C_PATH='@baseboard_fab2_lib.baseboard_fab2(sch_1):page89_i1@mstr_discrete.res(c~
hips)',
 P_PATH='@baseboard_fab2_lib.baseboard_fab2(sch_1):page89_i1@mstr_discrete.res(c~
hips)',
 PATH='I1',
 DRAWING='@BASEBOARD_FAB2_LIB.BASEBOARD_FAB2(SCH_1):PAGE89',
 WATTAGE='1/16W',
 TOLERANCE='5%',
 SEC_TYPE='0402',
 MATERIAL='EMPTY',
 BOM_COST='MEM_NV',
 PHYS_PAGE='89',
 XY='(-2250,3025)',
 ROT='0',
 VER='1',
 VALUE='0.0',
 PACK_TYPE='0402',
 PART_NUMBER='G21497-005',
 LOCATION='R4T2',
 ROOM='NV_DIMM',
 SEC='1',
 CDS_LIB='mstr_discrete',
 CDS_PART_NAME='RES_0402-0.0,5%,1/16W,EMPTY,G2A',
 PRIM_FILE='./archive_libs/mstr_discrete/res/chips/chips.prt';

PART_NAME
 R4T3 'RES_0402-10.0,1%,1/16W,CHIP,G2A':
 ROOM='MEM';

SECTION_NUMBER 1
 '@BASEBOARD_FAB2_LIB.BASEBOARD_FAB2(SCH_1):PAGE99_I83@MSTR_DISCRETE.RES(CHIPS)':
 C_PATH='@baseboard_fab2_lib.baseboard_fab2(sch_1):page99_i83@mstr_discrete.res(~
chips)',
 P_PATH='@baseboard_fab2_lib.baseboard_fab2(sch_1):page99_i83@mstr_discrete.res(~
chips)',
 PATH='I83',
 DRAWING='@BASEBOARD_FAB2_LIB.BASEBOARD_FAB2(SCH_1):PAGE99',
 WATTAGE='1/16W',
 TOLERANCE='1%',
 MATERIAL='CHIP',
 BOM_COST='SM_CONTROLLER',
 PHYS_PAGE='99',
 XY='(-1500,4350)',
 ROT='0',
 VER='1',
 VALUE='10.0',
 PACK_TYPE='0402',
 PART_NUMBER='G21796-066',
 LOCATION='R4T3',
 ROOM='MEM',
 CDS_LIB='mstr_discrete',
 CDS_PART_NAME='RES_0402-10.0,1%,1/16W,CHIP,G2A',
 PRIM_FILE='./archive_libs/mstr_discrete/res/chips/chips.prt';

PART_NAME
 R4T4 'RES_0402-10.0,1%,1/16W,CHIP,G2A':
 ROOM='MEM';

SECTION_NUMBER 1
 '@BASEBOARD_FAB2_LIB.BASEBOARD_FAB2(SCH_1):PAGE99_I20@MSTR_DISCRETE.RES(CHIPS)':
 C_PATH='@baseboard_fab2_lib.baseboard_fab2(sch_1):page99_i20@mstr_discrete.res(~
chips)',
 P_PATH='@baseboard_fab2_lib.baseboard_fab2(sch_1):page99_i20@mstr_discrete.res(~
chips)',
 PATH='I20',
 DRAWING='@BASEBOARD_FAB2_LIB.BASEBOARD_FAB2(SCH_1):PAGE99',
 WATTAGE='1/16W',
 TOLERANCE='1%',
 MATERIAL='CHIP',
 BOM_COST='SM_CONTROLLER',
 PHYS_PAGE='99',
 XY='(-1075,4300)',
 ROT='0',
 VER='1',
 VALUE='10.0',
 PACK_TYPE='0402',
 PART_NUMBER='G21796-066',
 LOCATION='R4T4',
 ROOM='MEM',
 CDS_LIB='mstr_discrete',
 CDS_PART_NAME='RES_0402-10.0,1%,1/16W,CHIP,G2A',
 PRIM_FILE='./archive_libs/mstr_discrete/res/chips/chips.prt';

PART_NAME
 R4T5 'RES_0402-240,1.0%,1/16W,CHIP,GA':
 ROOM='MEM',
 SIGNAL_MODEL='DEFAULT_RESISTOR_750OHM_2_1';

SECTION_NUMBER 1
 '@BASEBOARD_FAB2_LIB.BASEBOARD_FAB2(SCH_1):PAGE99_I19@MSTR_DISCRETE.RES(CHIPS)':
 C_PATH='@baseboard_fab2_lib.baseboard_fab2(sch_1):page99_i19@mstr_discrete.res(~
chips)',
 P_PATH='@baseboard_fab2_lib.baseboard_fab2(sch_1):page99_i19@mstr_discrete.res(~
chips)',
 PATH='I19',
 DRAWING='@BASEBOARD_FAB2_LIB.BASEBOARD_FAB2(SCH_1):PAGE99',
 CD_SEC='1',
 WATTAGE='1/16W',
 TOLERANCE='1.0%',
 MATERIAL='CHIP',
 BOM_COST='SM_CONTROLLER',
 PHYS_PAGE='99',
 XY='(-1025,4650)',
 ROT='2',
 VER='2',
 VALUE='240',
 PACK_TYPE='0402',
 PART_NUMBER='G21796-294',
 LOCATION='R4T5',
 SIGNAL_MODEL='DEFAULT_RESISTOR_750OHM_2_1',
 ROOM='MEM',
 CDS_LIB='mstr_discrete',
 CDS_PART_NAME='RES_0402-240,1.0%,1/16W,CHIP,GA',
 PRIM_FILE='./archive_libs/mstr_discrete/res/chips/chips.prt';

PART_NAME
 R4T6 'RES_0402-240,1.0%,1/16W,CHIP,GA':
 ROOM='MEM',
 SIGNAL_MODEL='DEFAULT_RESISTOR_750OHM_2_1';

SECTION_NUMBER 1
 '@BASEBOARD_FAB2_LIB.BASEBOARD_FAB2(SCH_1):PAGE99_I17@MSTR_DISCRETE.RES(CHIPS)':
 C_PATH='@baseboard_fab2_lib.baseboard_fab2(sch_1):page99_i17@mstr_discrete.res(~
chips)',
 P_PATH='@baseboard_fab2_lib.baseboard_fab2(sch_1):page99_i17@mstr_discrete.res(~
chips)',
 PATH='I17',
 DRAWING='@BASEBOARD_FAB2_LIB.BASEBOARD_FAB2(SCH_1):PAGE99',
 CD_SEC='1',
 WATTAGE='1/16W',
 TOLERANCE='1.0%',
 MATERIAL='CHIP',
 BOM_COST='SM_CONTROLLER',
 PHYS_PAGE='99',
 XY='(-650,4650)',
 ROT='2',
 VER='2',
 VALUE='240',
 PACK_TYPE='0402',
 PART_NUMBER='G21796-294',
 LOCATION='R4T6',
 SIGNAL_MODEL='DEFAULT_RESISTOR_750OHM_2_1',
 ROOM='MEM',
 CDS_LIB='mstr_discrete',
 CDS_PART_NAME='RES_0402-240,1.0%,1/16W,CHIP,GA',
 PRIM_FILE='./archive_libs/mstr_discrete/res/chips/chips.prt';

PART_NAME
 R4T7 'RES_0402-665,1.0%,1/16W,CHIP,GA':
 ROOM='MEM';

SECTION_NUMBER 1
 '@BASEBOARD_FAB2_LIB.BASEBOARD_FAB2(SCH_1):PAGE99_I13@MSTR_DISCRETE.RES(CHIPS)':
 C_PATH='@baseboard_fab2_lib.baseboard_fab2(sch_1):page99_i13@mstr_discrete.res(~
chips)',
 P_PATH='@baseboard_fab2_lib.baseboard_fab2(sch_1):page99_i13@mstr_discrete.res(~
chips)',
 PATH='I13',
 DRAWING='@BASEBOARD_FAB2_LIB.BASEBOARD_FAB2(SCH_1):PAGE99',
 WATTAGE='1/16W',
 TOLERANCE='1.0%',
 SEC_TYPE='0402',
 MATERIAL='CHIP',
 BOM_COST='SM_CONTROLLER',
 PHYS_PAGE='99',
 XY='(875,4650)',
 ROT='0',
 VER='2',
 VALUE='665',
 PACK_TYPE='0402',
 PART_NUMBER='G21796-235',
 LOCATION='R4T7',
 ROOM='MEM',
 SEC='1',
 CDS_LIB='mstr_discrete',
 CDS_PART_NAME='RES_0402-665,1.0%,1/16W,CHIP,GA',
 PRIM_FILE='./archive_libs/mstr_discrete/res/chips/chips.prt';

PART_NAME
 R4T8 'RES_0402-665,1.0%,1/16W,CHIP,GA':
 ROOM='MEM';

SECTION_NUMBER 1
 '@BASEBOARD_FAB2_LIB.BASEBOARD_FAB2(SCH_1):PAGE99_I11@MSTR_DISCRETE.RES(CHIPS)':
 C_PATH='@baseboard_fab2_lib.baseboard_fab2(sch_1):page99_i11@mstr_discrete.res(~
chips)',
 P_PATH='@baseboard_fab2_lib.baseboard_fab2(sch_1):page99_i11@mstr_discrete.res(~
chips)',
 PATH='I11',
 DRAWING='@BASEBOARD_FAB2_LIB.BASEBOARD_FAB2(SCH_1):PAGE99',
 WATTAGE='1/16W',
 TOLERANCE='1.0%',
 SEC_TYPE='0402',
 MATERIAL='CHIP',
 BOM_COST='SM_CONTROLLER',
 PHYS_PAGE='99',
 XY='(1225,4650)',
 ROT='0',
 VER='2',
 VALUE='665',
 PACK_TYPE='0402',
 PART_NUMBER='G21796-235',
 LOCATION='R4T8',
 ROOM='MEM',
 SEC='1',
 CDS_LIB='mstr_discrete',
 CDS_PART_NAME='RES_0402-665,1.0%,1/16W,CHIP,GA',
 PRIM_FILE='./archive_libs/mstr_discrete/res/chips/chips.prt';

PART_NAME
 R4T9 'RES_0402-20.0,1%,1/16W,CHIP,G2A':
 ROOM='MEM';

SECTION_NUMBER 1
 '@BASEBOARD_FAB2_LIB.BASEBOARD_FAB2(SCH_1):PAGE99_I9@MSTR_DISCRETE.RES(CHIPS)':
 C_PATH='@baseboard_fab2_lib.baseboard_fab2(sch_1):page99_i9@mstr_discrete.res(c~
hips)',
 P_PATH='@baseboard_fab2_lib.baseboard_fab2(sch_1):page99_i9@mstr_discrete.res(c~
hips)',
 PATH='I9',
 DRAWING='@BASEBOARD_FAB2_LIB.BASEBOARD_FAB2(SCH_1):PAGE99',
 WATTAGE='1/16W',
 TOLERANCE='1%',
 MATERIAL='CHIP',
 PHYS_PAGE='99',
 XY='(1600,4350)',
 ROT='0',
 VER='1',
 VALUE='20.0',
 PACK_TYPE='0402',
 PART_NUMBER='G21796-173',
 LOCATION='R4T9',
 ROOM='MEM',
 CDS_LIB='mstr_discrete',
 CDS_PART_NAME='RES_0402-20.0,1%,1/16W,CHIP,G2A',
 PRIM_FILE='./archive_libs/mstr_discrete/res/chips/chips.prt';

PART_NAME
 R4T10 'RES_0402-20.0,1%,1/16W,CHIP,G2A':
 ROOM='MEM';

SECTION_NUMBER 1
 '@BASEBOARD_FAB2_LIB.BASEBOARD_FAB2(SCH_1):PAGE99_I10@MSTR_DISCRETE.RES(CHIPS)':
 C_PATH='@baseboard_fab2_lib.baseboard_fab2(sch_1):page99_i10@mstr_discrete.res(~
chips)',
 P_PATH='@baseboard_fab2_lib.baseboard_fab2(sch_1):page99_i10@mstr_discrete.res(~
chips)',
 PATH='I10',
 DRAWING='@BASEBOARD_FAB2_LIB.BASEBOARD_FAB2(SCH_1):PAGE99',
 WATTAGE='1/16W',
 TOLERANCE='1%',
 MATERIAL='CHIP',
 PHYS_PAGE='99',
 XY='(1600,4300)',
 ROT='0',
 VER='1',
 VALUE='20.0',
 PACK_TYPE='0402',
 PART_NUMBER='G21796-173',
 LOCATION='R4T10',
 ROOM='MEM',
 CDS_LIB='mstr_discrete',
 CDS_PART_NAME='RES_0402-20.0,1%,1/16W,CHIP,G2A',
 PRIM_FILE='./archive_libs/mstr_discrete/res/chips/chips.prt';

PART_NAME
 R4U1 'RES_0402-4.75K,1%,1/16W,CHIP,GA':
 ROOM='PROC_SIDEBAND';

SECTION_NUMBER 1
 '@BASEBOARD_FAB2_LIB.BASEBOARD_FAB2(SCH_1):PAGE94_I91@MSTR_DISCRETE.RES(CHIPS)':
 C_PATH='@baseboard_fab2_lib.baseboard_fab2(sch_1):page94_i91@mstr_discrete.res(~
chips)',
 P_PATH='@baseboard_fab2_lib.baseboard_fab2(sch_1):page94_i91@mstr_discrete.res(~
chips)',
 PATH='I91',
 DRAWING='@BASEBOARD_FAB2_LIB.BASEBOARD_FAB2(SCH_1):PAGE94',
 WATTAGE='1/16W',
 TOLERANCE='1%',
 SEC_TYPE='0402',
 MATERIAL='CHIP',
 BOM_COST='PROC_SIDEBAND',
 PHYS_PAGE='94',
 XY='(1400,4450)',
 ROT='2',
 VER='2',
 VALUE='4.75K',
 PACK_TYPE='0402',
 PART_NUMBER='G21796-072',
 LOCATION='R4U1',
 ROOM='PROC_SIDEBAND',
 SEC='1',
 CDS_LIB='mstr_discrete',
 CDS_PART_NAME='RES_0402-4.75K,1%,1/16W,CHIP,GA',
 PRIM_FILE='./archive_libs/mstr_discrete/res/chips/chips.prt';

PART_NAME
 R4U2 'RES_0402-2.21K,1%,1/16W,CHIP,GA':
 ROOM='PROC_SIDEBAND';

SECTION_NUMBER 1
 '@BASEBOARD_FAB2_LIB.BASEBOARD_FAB2(SCH_1):PAGE94_I100@MSTR_DISCRETE.RES(CHIPS)':
 C_PATH='@baseboard_fab2_lib.baseboard_fab2(sch_1):page94_i100@mstr_discrete.res~
(chips)',
 P_PATH='@baseboard_fab2_lib.baseboard_fab2(sch_1):page94_i100@mstr_discrete.res~
(chips)',
 PATH='I100',
 DRAWING='@BASEBOARD_FAB2_LIB.BASEBOARD_FAB2(SCH_1):PAGE94',
 WATTAGE='1/16W',
 TOLERANCE='1%',
 SEC_TYPE='0402',
 MATERIAL='CHIP',
 BOM_COST='PROC_SIDEBAND',
 PHYS_PAGE='94',
 XY='(-300,3650)',
 ROT='2',
 VER='2',
 VALUE='2.21K',
 PACK_TYPE='0402',
 PART_NUMBER='G21796-112',
 LOCATION='R4U2',
 ROOM='PROC_SIDEBAND',
 SEC='1',
 CDS_LIB='mstr_discrete',
 CDS_PART_NAME='RES_0402-2.21K,1%,1/16W,CHIP,GA',
 PRIM_FILE='./archive_libs/mstr_discrete/res/chips/chips.prt';

PART_NAME
 R4U3 'RES_0402-4.75K,1%,1/16W,CHIP,GA':
 ROOM='PROC_SIDEBAND';

SECTION_NUMBER 1
 '@BASEBOARD_FAB2_LIB.BASEBOARD_FAB2(SCH_1):PAGE94_I94@MSTR_DISCRETE.RES(CHIPS)':
 C_PATH='@baseboard_fab2_lib.baseboard_fab2(sch_1):page94_i94@mstr_discrete.res(~
chips)',
 P_PATH='@baseboard_fab2_lib.baseboard_fab2(sch_1):page94_i94@mstr_discrete.res(~
chips)',
 PATH='I94',
 DRAWING='@BASEBOARD_FAB2_LIB.BASEBOARD_FAB2(SCH_1):PAGE94',
 WATTAGE='1/16W',
 TOLERANCE='1%',
 SEC_TYPE='0402',
 MATERIAL='CHIP',
 BOM_COST='PROC_SIDEBAND',
 PHYS_PAGE='94',
 XY='(175,4075)',
 ROT='2',
 VER='2',
 VALUE='4.75K',
 PACK_TYPE='0402',
 PART_NUMBER='G21796-072',
 LOCATION='R4U3',
 ROOM='PROC_SIDEBAND',
 SEC='1',
 CDS_LIB='mstr_discrete',
 CDS_PART_NAME='RES_0402-4.75K,1%,1/16W,CHIP,GA',
 PRIM_FILE='./archive_libs/mstr_discrete/res/chips/chips.prt';

PART_NAME
 R4U4 'RES_0402-33.0K,5%,1/16W,CHIP,GA':;

SECTION_NUMBER 1
 '@BASEBOARD_FAB2_LIB.BASEBOARD_FAB2(SCH_1):PAGE94_I104@MSTR_DISCRETE.RES(CHIPS)':
 C_PATH='@baseboard_fab2_lib.baseboard_fab2(sch_1):page94_i104@mstr_discrete.res~
(chips)',
 P_PATH='@baseboard_fab2_lib.baseboard_fab2(sch_1):page94_i104@mstr_discrete.res~
(chips)',
 PATH='I104',
 DRAWING='@BASEBOARD_FAB2_LIB.BASEBOARD_FAB2(SCH_1):PAGE94',
 WATTAGE='1/16W',
 TOLERANCE='5%',
 SEC_TYPE='0402',
 MATERIAL='CHIP',
 PHYS_PAGE='94',
 XY='(750,3575)',
 ROT='0',
 VER='2',
 VALUE='33.0K',
 PACK_TYPE='0402',
 PART_NUMBER='G21497-023',
 LOCATION='R4U4',
 SEC='1',
 CDS_LIB='mstr_discrete',
 CDS_PART_NAME='RES_0402-33.0K,5%,1/16W,CHIP,GA',
 PRIM_FILE='./archive_libs/mstr_discrete/res/chips/chips.prt';

PART_NAME
 R4U6 'RES_0402-100.0,1%,1/16W,EMPTY,A':
 ROOM='VDDQ_ABC_PWR_VR';

SECTION_NUMBER 1
 '@BASEBOARD_FAB2_LIB.BASEBOARD_FAB2(SCH_1):PAGE217_I74@MSTR_DISCRETE.RES(CHIPS)':
 C_PATH='@baseboard_fab2_lib.baseboard_fab2(sch_1):page217_i74@mstr_discrete.res~
(chips)',
 P_PATH='@baseboard_fab2_lib.baseboard_fab2(sch_1):page217_i74@mstr_discrete.res~
(chips)',
 PATH='I74',
 DRAWING='@BASEBOARD_FAB2_LIB.BASEBOARD_FAB2(SCH_1):PAGE217',
 WATTAGE='1/16W',
 TOLERANCE='1%',
 SEC_TYPE='0402',
 MATERIAL='EMPTY',
 PHYS_PAGE='217',
 XY='(-250,1700)',
 ROT='0',
 VER='2',
 VALUE='100.0',
 PACK_TYPE='0402',
 PART_NUMBER='G21796-017',
 LOCATION='R4U6',
 ROOM='VDDQ_ABC_PWR_VR',
 SEC='1',
 CDS_LIB='mstr_discrete',
 CDS_PART_NAME='RES_0402-100.0,1%,1/16W,EMPTY,A',
 PRIM_FILE='./archive_libs/mstr_discrete/res/chips/chips.prt';

PART_NAME
 R4W1 'RES_0402-4.75K,1%,1/16W,CHIP,GA':
 ROOM='CPLD';

SECTION_NUMBER 1
 '@BASEBOARD_FAB2_LIB.BASEBOARD_FAB2(SCH_1):PAGE191_I195@MSTR_DISCRETE.RES(CHIPS)':
 C_PATH='@baseboard_fab2_lib.baseboard_fab2(sch_1):page191_i195@mstr_discrete.re~
s(chips)',
 P_PATH='@baseboard_fab2_lib.baseboard_fab2(sch_1):page191_i195@mstr_discrete.re~
s(chips)',
 PATH='I195',
 DRAWING='@BASEBOARD_FAB2_LIB.BASEBOARD_FAB2(SCH_1):PAGE191',
 WATTAGE='1/16W',
 TOLERANCE='1%',
 SEC_TYPE='0402',
 MATERIAL='CHIP',
 PHYS_PAGE='191',
 XY='(-1700,2200)',
 ROT='0',
 VER='2',
 VALUE='4.75K',
 PACK_TYPE='0402',
 PART_NUMBER='G21796-072',
 LOCATION='R4W1',
 ROOM='CPLD',
 SEC='1',
 CDS_LIB='mstr_discrete',
 CDS_PART_NAME='RES_0402-4.75K,1%,1/16W,CHIP,GA',
 PRIM_FILE='./archive_libs/mstr_discrete/res/chips/chips.prt';

PART_NAME
 R4W2 'RES_0402-1.00K,1%,1/16W,CHIP,GA':
 ROOM='PROC_SIDEBAND';

SECTION_NUMBER 1
 '@BASEBOARD_FAB2_LIB.BASEBOARD_FAB2(SCH_1):PAGE102_I103@MSTR_DISCRETE.RES(CHIPS)':
 C_PATH='@baseboard_fab2_lib.baseboard_fab2(sch_1):page102_i103@mstr_discrete.re~
s(chips)',
 P_PATH='@baseboard_fab2_lib.baseboard_fab2(sch_1):page102_i103@mstr_discrete.re~
s(chips)',
 PATH='I103',
 DRAWING='@BASEBOARD_FAB2_LIB.BASEBOARD_FAB2(SCH_1):PAGE102',
 WATTAGE='1/16W',
 TOLERANCE='1%',
 SEC_TYPE='0402',
 MATERIAL='CHIP',
 PHYS_PAGE='102',
 XY='(2450,4900)',
 ROT='0',
 VER='2',
 VALUE='1.00K',
 PACK_TYPE='0402',
 PART_NUMBER='G21796-026',
 LOCATION='R4W2',
 ROOM='PROC_SIDEBAND',
 SEC='1',
 CDS_LIB='mstr_discrete',
 CDS_PART_NAME='RES_0402-1.00K,1%,1/16W,CHIP,GA',
 PRIM_FILE='./archive_libs/mstr_discrete/res/chips/chips.prt';

PART_NAME
 R4W3 'RES_0402-3.3K,5%,1/16W,CHIP,G2A':;

SECTION_NUMBER 1
 '@BASEBOARD_FAB2_LIB.BASEBOARD_FAB2(SCH_1):PAGE102_I105@MSTR_DISCRETE.RES(CHIPS)':
 C_PATH='@baseboard_fab2_lib.baseboard_fab2(sch_1):page102_i105@mstr_discrete.re~
s(chips)',
 P_PATH='@baseboard_fab2_lib.baseboard_fab2(sch_1):page102_i105@mstr_discrete.re~
s(chips)',
 PATH='I105',
 DRAWING='@BASEBOARD_FAB2_LIB.BASEBOARD_FAB2(SCH_1):PAGE102',
 WATTAGE='1/16W',
 TOLERANCE='5%',
 SEC_TYPE='0402',
 MATERIAL='CHIP',
 PHYS_PAGE='102',
 XY='(3300,4750)',
 ROT='5',
 VER='1',
 VALUE='3.3K',
 PACK_TYPE='0402',
 PART_NUMBER='G21497-013',
 LOCATION='R4W3',
 SEC='1',
 CDS_LIB='mstr_discrete',
 CDS_PART_NAME='RES_0402-3.3K,5%,1/16W,CHIP,G2A',
 PRIM_FILE='./archive_libs/mstr_discrete/res/chips/chips.prt';

PART_NAME
 R4W4 'RES_0402-3.3K,5%,1/16W,CHIP,G2A':;

SECTION_NUMBER 1
 '@BASEBOARD_FAB2_LIB.BASEBOARD_FAB2(SCH_1):PAGE102_I106@MSTR_DISCRETE.RES(CHIPS)':
 C_PATH='@baseboard_fab2_lib.baseboard_fab2(sch_1):page102_i106@mstr_discrete.re~
s(chips)',
 P_PATH='@baseboard_fab2_lib.baseboard_fab2(sch_1):page102_i106@mstr_discrete.re~
s(chips)',
 PATH='I106',
 DRAWING='@BASEBOARD_FAB2_LIB.BASEBOARD_FAB2(SCH_1):PAGE102',
 WATTAGE='1/16W',
 TOLERANCE='5%',
 SEC_TYPE='0402',
 MATERIAL='CHIP',
 PHYS_PAGE='102',
 XY='(3650,4750)',
 ROT='5',
 VER='1',
 VALUE='3.3K',
 PACK_TYPE='0402',
 PART_NUMBER='G21497-013',
 LOCATION='R4W4',
 SEC='1',
 CDS_LIB='mstr_discrete',
 CDS_PART_NAME='RES_0402-3.3K,5%,1/16W,CHIP,G2A',
 PRIM_FILE='./archive_libs/mstr_discrete/res/chips/chips.prt';

PART_NAME
 R4W5 'RES_0402-0.0,5%,1/16W,EMPTY,G2A':
 ROOM='NV_DIMM';

SECTION_NUMBER 1
 '@BASEBOARD_FAB2_LIB.BASEBOARD_FAB2(SCH_1):PAGE102_I114@MSTR_DISCRETE.RES(CHIPS)':
 C_PATH='@baseboard_fab2_lib.baseboard_fab2(sch_1):page102_i114@mstr_discrete.re~
s(chips)',
 P_PATH='@baseboard_fab2_lib.baseboard_fab2(sch_1):page102_i114@mstr_discrete.re~
s(chips)',
 PATH='I114',
 DRAWING='@BASEBOARD_FAB2_LIB.BASEBOARD_FAB2(SCH_1):PAGE102',
 WATTAGE='1/16W',
 TOLERANCE='5%',
 SEC_TYPE='0402',
 MATERIAL='EMPTY',
 BOM_COST='MEM_NV',
 PHYS_PAGE='102',
 XY='(-1650,2000)',
 ROT='1',
 VER='1',
 VALUE='0.0',
 PACK_TYPE='0402',
 PART_NUMBER='G21497-005',
 LOCATION='R4W5',
 ROOM='NV_DIMM',
 SEC='1',
 CDS_LIB='mstr_discrete',
 CDS_PART_NAME='RES_0402-0.0,5%,1/16W,EMPTY,G2A',
 PRIM_FILE='./archive_libs/mstr_discrete/res/chips/chips.prt';

PART_NAME
 R4W6 'RES_0402-4.75K,1%,1/16W,CHIP,GA':
 ROOM='DB1200ZL';

SECTION_NUMBER 1
 '@BASEBOARD_FAB2_LIB.BASEBOARD_FAB2(SCH_1):PAGE102_I109@MSTR_DISCRETE.RES(CHIPS)':
 C_PATH='@baseboard_fab2_lib.baseboard_fab2(sch_1):page102_i109@mstr_discrete.re~
s(chips)',
 P_PATH='@baseboard_fab2_lib.baseboard_fab2(sch_1):page102_i109@mstr_discrete.re~
s(chips)',
 PATH='I109',
 DRAWING='@BASEBOARD_FAB2_LIB.BASEBOARD_FAB2(SCH_1):PAGE102',
 WATTAGE='1/16W',
 TOLERANCE='1%',
 SEC_TYPE='0402',
 MATERIAL='CHIP',
 BOM_COST='SYS_CLOCK',
 PHYS_PAGE='102',
 XY='(-2400,2350)',
 ROT='0',
 VER='2',
 VALUE='4.75K',
 PACK_TYPE='0402',
 PART_NUMBER='G21796-072',
 LOCATION='R4W6',
 ROOM='DB1200ZL',
 SEC='1',
 CDS_LIB='mstr_discrete',
 CDS_PART_NAME='RES_0402-4.75K,1%,1/16W,CHIP,GA',
 PRIM_FILE='./archive_libs/mstr_discrete/res/chips/chips.prt';

PART_NAME
 R5D1 'RES_0402-90.9,1%,1/16W,CHIP,G2A':
 ROOM='CPU0';

SECTION_NUMBER 1
 '@BASEBOARD_FAB2_LIB.BASEBOARD_FAB2(SCH_1):PAGE21_I177@MSTR_DISCRETE.RES(CHIPS)':
 C_PATH='@baseboard_fab2_lib.baseboard_fab2(sch_1):page21_i177@mstr_discrete.res~
(chips)',
 P_PATH='@baseboard_fab2_lib.baseboard_fab2(sch_1):page21_i177@mstr_discrete.res~
(chips)',
 PATH='I177',
 DRAWING='@BASEBOARD_FAB2_LIB.BASEBOARD_FAB2(SCH_1):PAGE21',
 WATTAGE='1/16W',
 TOLERANCE='1%',
 SEC_TYPE='0402',
 MATERIAL='CHIP',
 BOM_COST='PROC_SOCKET',
 PHYS_PAGE='21',
 XY='(-6625,2875)',
 ROT='2',
 VER='2',
 VALUE='90.9',
 PACK_TYPE='0402',
 PART_NUMBER='G21796-365',
 LOCATION='R5D1',
 ROOM='CPU0',
 SEC='1',
 CDS_LIB='mstr_discrete',
 CDS_PART_NAME='RES_0402-90.9,1%,1/16W,CHIP,G2A',
 PRIM_FILE='./archive_libs/mstr_discrete/res/chips/chips.prt';

PART_NAME
 R5D2 'RES_0402-90.9,1%,1/16W,CHIP,G2A':
 ROOM='CPU0';

SECTION_NUMBER 1
 '@BASEBOARD_FAB2_LIB.BASEBOARD_FAB2(SCH_1):PAGE21_I178@MSTR_DISCRETE.RES(CHIPS)':
 C_PATH='@baseboard_fab2_lib.baseboard_fab2(sch_1):page21_i178@mstr_discrete.res~
(chips)',
 P_PATH='@baseboard_fab2_lib.baseboard_fab2(sch_1):page21_i178@mstr_discrete.res~
(chips)',
 PATH='I178',
 DRAWING='@BASEBOARD_FAB2_LIB.BASEBOARD_FAB2(SCH_1):PAGE21',
 WATTAGE='1/16W',
 TOLERANCE='1%',
 SEC_TYPE='0402',
 MATERIAL='CHIP',
 BOM_COST='PROC_SOCKET',
 PHYS_PAGE='21',
 XY='(-6875,2925)',
 ROT='2',
 VER='2',
 VALUE='90.9',
 PACK_TYPE='0402',
 PART_NUMBER='G21796-365',
 LOCATION='R5D2',
 ROOM='CPU0',
 SEC='1',
 CDS_LIB='mstr_discrete',
 CDS_PART_NAME='RES_0402-90.9,1%,1/16W,CHIP,G2A',
 PRIM_FILE='./archive_libs/mstr_discrete/res/chips/chips.prt';

PART_NAME
 R5D3 'RES_0402-240,1.0%,1/16W,CHIP,GA':
 ROOM='PROC_SIDEBAND';

SECTION_NUMBER 1
 '@BASEBOARD_FAB2_LIB.BASEBOARD_FAB2(SCH_1):PAGE90_I29@MSTR_DISCRETE.RES(CHIPS)':
 C_PATH='@baseboard_fab2_lib.baseboard_fab2(sch_1):page90_i29@mstr_discrete.res(~
chips)',
 P_PATH='@baseboard_fab2_lib.baseboard_fab2(sch_1):page90_i29@mstr_discrete.res(~
chips)',
 PATH='I29',
 DRAWING='@BASEBOARD_FAB2_LIB.BASEBOARD_FAB2(SCH_1):PAGE90',
 WATTAGE='1/16W',
 TOLERANCE='1.0%',
 SEC_TYPE='0402',
 MATERIAL='CHIP',
 BOM_COST='PROC',
 PHYS_PAGE='90',
 XY='(-2475,4400)',
 ROT='0',
 VER='1',
 VALUE='240',
 PACK_TYPE='0402',
 PART_NUMBER='G21796-294',
 LOCATION='R5D3',
 ROOM='PROC_SIDEBAND',
 SEC='1',
 CDS_LIB='mstr_discrete',
 CDS_PART_NAME='RES_0402-240,1.0%,1/16W,CHIP,GA',
 PRIM_FILE='./archive_libs/mstr_discrete/res/chips/chips.prt';

PART_NAME
 R5D4 'RES_0402-240,1.0%,1/16W,CHIP,GA':
 ROOM='PROC_SIDEBAND';

SECTION_NUMBER 1
 '@BASEBOARD_FAB2_LIB.BASEBOARD_FAB2(SCH_1):PAGE90_I96@MSTR_DISCRETE.RES(CHIPS)':
 C_PATH='@baseboard_fab2_lib.baseboard_fab2(sch_1):page90_i96@mstr_discrete.res(~
chips)',
 P_PATH='@baseboard_fab2_lib.baseboard_fab2(sch_1):page90_i96@mstr_discrete.res(~
chips)',
 PATH='I96',
 DRAWING='@BASEBOARD_FAB2_LIB.BASEBOARD_FAB2(SCH_1):PAGE90',
 WATTAGE='1/16W',
 TOLERANCE='1.0%',
 SEC_TYPE='0402',
 MATERIAL='CHIP',
 BOM_COST='PROC',
 PHYS_PAGE='90',
 XY='(-2475,4000)',
 ROT='0',
 VER='1',
 VALUE='240',
 PACK_TYPE='0402',
 PART_NUMBER='G21796-294',
 LOCATION='R5D4',
 ROOM='PROC_SIDEBAND',
 SEC='1',
 CDS_LIB='mstr_discrete',
 CDS_PART_NAME='RES_0402-240,1.0%,1/16W,CHIP,GA',
 PRIM_FILE='./archive_libs/mstr_discrete/res/chips/chips.prt';

PART_NAME
 R5D5 'RES_0402-249,0.1%,1/16W,CHIP,GA':
 ROOM='CPU0';

SECTION_NUMBER 1
 '@BASEBOARD_FAB2_LIB.BASEBOARD_FAB2(SCH_1):PAGE37_I303@MSTR_DISCRETE.RES(CHIPS)':
 C_PATH='@baseboard_fab2_lib.baseboard_fab2(sch_1):page37_i303@mstr_discrete.res~
(chips)',
 P_PATH='@baseboard_fab2_lib.baseboard_fab2(sch_1):page37_i303@mstr_discrete.res~
(chips)',
 PATH='I303',
 DRAWING='@BASEBOARD_FAB2_LIB.BASEBOARD_FAB2(SCH_1):PAGE37',
 WATTAGE='1/16W',
 TOLERANCE='0.1%',
 SEC_TYPE='0402',
 MATERIAL='CHIP',
 BOM_COST='PROC_SOCKET',
 PHYS_PAGE='37',
 XY='(-375,750)',
 ROT='0',
 VER='2',
 VALUE='249',
 PACK_TYPE='0402',
 PART_NUMBER='G85996-031',
 LOCATION='R5D5',
 ROOM='CPU0',
 SEC='1',
 CDS_LIB='mstr_discrete',
 CDS_PART_NAME='RES_0402-249,0.1%,1/16W,CHIP,GA',
 PRIM_FILE='./archive_libs/mstr_discrete/res/chips/chips.prt';

PART_NAME
 R5D6 'RES_0402-10.0,1%,1/16W,EMPTY,GA':
 ROOM='CPU0';

SECTION_NUMBER 1
 '@BASEBOARD_FAB2_LIB.BASEBOARD_FAB2(SCH_1):PAGE37_I312@MSTR_DISCRETE.RES(CHIPS)':
 C_PATH='@baseboard_fab2_lib.baseboard_fab2(sch_1):page37_i312@mstr_discrete.res~
(chips)',
 P_PATH='@baseboard_fab2_lib.baseboard_fab2(sch_1):page37_i312@mstr_discrete.res~
(chips)',
 PATH='I312',
 DRAWING='@BASEBOARD_FAB2_LIB.BASEBOARD_FAB2(SCH_1):PAGE37',
 WATTAGE='1/16W',
 TOLERANCE='1%',
 SEC_TYPE='0402',
 MATERIAL='EMPTY',
 PHYS_PAGE='37',
 XY='(-375,1125)',
 ROT='0',
 VER='2',
 VALUE='10.0',
 PACK_TYPE='0402',
 PART_NUMBER='G21796-066',
 LOCATION='R5D6',
 ROOM='CPU0',
 SEC='1',
 CDS_LIB='mstr_discrete',
 CDS_PART_NAME='RES_0402-10.0,1%,1/16W,EMPTY,GA',
 PRIM_FILE='./archive_libs/mstr_discrete/res/chips/chips.prt';

PART_NAME
 R5N1 'RES_0402-10.0K,1%,1/16W,CHIP,GA':
 ROOM='CPU0';

SECTION_NUMBER 1
 '@BASEBOARD_FAB2_LIB.BASEBOARD_FAB2(SCH_1):PAGE21_I238@MSTR_DISCRETE.RES(CHIPS)':
 C_PATH='@baseboard_fab2_lib.baseboard_fab2(sch_1):page21_i238@mstr_discrete.res~
(chips)',
 P_PATH='@baseboard_fab2_lib.baseboard_fab2(sch_1):page21_i238@mstr_discrete.res~
(chips)',
 PATH='I238',
 DRAWING='@BASEBOARD_FAB2_LIB.BASEBOARD_FAB2(SCH_1):PAGE21',
 WATTAGE='1/16W',
 TOLERANCE='1%',
 SEC_TYPE='0402',
 MATERIAL='CHIP',
 BOM_COST='PROC_SIDEBAND',
 PHYS_PAGE='21',
 XY='(-700,2700)',
 ROT='0',
 VER='2',
 VALUE='10.0K',
 PACK_TYPE='0402',
 PART_NUMBER='G21796-016',
 LOCATION='R5N1',
 ROOM='CPU0',
 SEC='1',
 CDS_LIB='mstr_discrete',
 CDS_PART_NAME='RES_0402-10.0K,1%,1/16W,CHIP,GA',
 PRIM_FILE='./archive_libs/mstr_discrete/res/chips/chips.prt';

PART_NAME
 R5N2 'RES_0402-1.8K,1%,1/16W,CHIP,G2A':
 ROOM='CPU0';

SECTION_NUMBER 1
 '@BASEBOARD_FAB2_LIB.BASEBOARD_FAB2(SCH_1):PAGE21_I227@MSTR_DISCRETE.RES(CHIPS)':
 C_PATH='@baseboard_fab2_lib.baseboard_fab2(sch_1):page21_i227@mstr_discrete.res~
(chips)',
 P_PATH='@baseboard_fab2_lib.baseboard_fab2(sch_1):page21_i227@mstr_discrete.res~
(chips)',
 PATH='I227',
 DRAWING='@BASEBOARD_FAB2_LIB.BASEBOARD_FAB2(SCH_1):PAGE21',
 WATTAGE='1/16W',
 TOLERANCE='1%',
 SEC_TYPE='0402',
 MATERIAL='CHIP',
 BOM_COST='PROC_SIDEBAND',
 PHYS_PAGE='21',
 XY='(-1700,2700)',
 ROT='0',
 VER='2',
 VALUE='1.8K',
 PACK_TYPE='0402',
 PART_NUMBER='G21796-336',
 LOCATION='R5N2',
 ROOM='CPU0',
 SEC='1',
 CDS_LIB='mstr_discrete',
 CDS_PART_NAME='RES_0402-1.8K,1%,1/16W,CHIP,G2A',
 PRIM_FILE='./archive_libs/mstr_discrete/res/chips/chips.prt';

PART_NAME
 R5N3 'RES_0402-10.0K,1%,1/16W,CHIP,GA':
 ROOM='CPU0';

SECTION_NUMBER 1
 '@BASEBOARD_FAB2_LIB.BASEBOARD_FAB2(SCH_1):PAGE21_I240@MSTR_DISCRETE.RES(CHIPS)':
 C_PATH='@baseboard_fab2_lib.baseboard_fab2(sch_1):page21_i240@mstr_discrete.res~
(chips)',
 P_PATH='@baseboard_fab2_lib.baseboard_fab2(sch_1):page21_i240@mstr_discrete.res~
(chips)',
 PATH='I240',
 DRAWING='@BASEBOARD_FAB2_LIB.BASEBOARD_FAB2(SCH_1):PAGE21',
 WATTAGE='1/16W',
 TOLERANCE='1%',
 SEC_TYPE='0402',
 MATERIAL='CHIP',
 BOM_COST='PROC_SIDEBAND',
 PHYS_PAGE='21',
 XY='(-1200,2700)',
 ROT='0',
 VER='2',
 VALUE='10.0K',
 PACK_TYPE='0402',
 PART_NUMBER='G21796-016',
 LOCATION='R5N3',
 ROOM='CPU0',
 SEC='1',
 CDS_LIB='mstr_discrete',
 CDS_PART_NAME='RES_0402-10.0K,1%,1/16W,CHIP,GA',
 PRIM_FILE='./archive_libs/mstr_discrete/res/chips/chips.prt';

PART_NAME
 R5N4 'RES_0402-1.8K,1%,1/16W,CHIP,G2A':
 ROOM='CPU0';

SECTION_NUMBER 1
 '@BASEBOARD_FAB2_LIB.BASEBOARD_FAB2(SCH_1):PAGE21_I241@MSTR_DISCRETE.RES(CHIPS)':
 C_PATH='@baseboard_fab2_lib.baseboard_fab2(sch_1):page21_i241@mstr_discrete.res~
(chips)',
 P_PATH='@baseboard_fab2_lib.baseboard_fab2(sch_1):page21_i241@mstr_discrete.res~
(chips)',
 PATH='I241',
 DRAWING='@BASEBOARD_FAB2_LIB.BASEBOARD_FAB2(SCH_1):PAGE21',
 WATTAGE='1/16W',
 TOLERANCE='1%',
 SEC_TYPE='0402',
 MATERIAL='CHIP',
 BOM_COST='PROC_SIDEBAND',
 PHYS_PAGE='21',
 XY='(-1450,2700)',
 ROT='0',
 VER='2',
 VALUE='1.8K',
 PACK_TYPE='0402',
 PART_NUMBER='G21796-336',
 LOCATION='R5N4',
 ROOM='CPU0',
 SEC='1',
 CDS_LIB='mstr_discrete',
 CDS_PART_NAME='RES_0402-1.8K,1%,1/16W,CHIP,G2A',
 PRIM_FILE='./archive_libs/mstr_discrete/res/chips/chips.prt';

PART_NAME
 R5N5 'RES_0402-10.0K,1%,1/16W,CHIP,GA':
 ROOM='CPU0';

SECTION_NUMBER 1
 '@BASEBOARD_FAB2_LIB.BASEBOARD_FAB2(SCH_1):PAGE21_I239@MSTR_DISCRETE.RES(CHIPS)':
 C_PATH='@baseboard_fab2_lib.baseboard_fab2(sch_1):page21_i239@mstr_discrete.res~
(chips)',
 P_PATH='@baseboard_fab2_lib.baseboard_fab2(sch_1):page21_i239@mstr_discrete.res~
(chips)',
 PATH='I239',
 DRAWING='@BASEBOARD_FAB2_LIB.BASEBOARD_FAB2(SCH_1):PAGE21',
 WATTAGE='1/16W',
 TOLERANCE='1%',
 SEC_TYPE='0402',
 MATERIAL='CHIP',
 BOM_COST='PROC_SIDEBAND',
 PHYS_PAGE='21',
 XY='(-950,2700)',
 ROT='0',
 VER='2',
 VALUE='10.0K',
 PACK_TYPE='0402',
 PART_NUMBER='G21796-016',
 LOCATION='R5N5',
 ROOM='CPU0',
 SEC='1',
 CDS_LIB='mstr_discrete',
 CDS_PART_NAME='RES_0402-10.0K,1%,1/16W,CHIP,GA',
 PRIM_FILE='./archive_libs/mstr_discrete/res/chips/chips.prt';

PART_NAME
 R5P1 'RES_0603-100.0K,1%,1/10W,CHIP,A':
 ROOM='CPU0';

SECTION_NUMBER 1
 '@BASEBOARD_FAB2_LIB.BASEBOARD_FAB2(SCH_1):PAGE37_I309@MSTR_DISCRETE.RES(CHIPS)':
 C_PATH='@baseboard_fab2_lib.baseboard_fab2(sch_1):page37_i309@mstr_discrete.res~
(chips)',
 P_PATH='@baseboard_fab2_lib.baseboard_fab2(sch_1):page37_i309@mstr_discrete.res~
(chips)',
 PATH='I309',
 DRAWING='@BASEBOARD_FAB2_LIB.BASEBOARD_FAB2(SCH_1):PAGE37',
 WATTAGE='1/10W',
 TOLERANCE='1%',
 SEC_TYPE='0603',
 MATERIAL='CHIP',
 BOM_COST='PROC_SOCKET',
 PHYS_PAGE='37',
 XY='(-775,1350)',
 ROT='0',
 VER='2',
 VALUE='100.0K',
 PACK_TYPE='0603',
 PART_NUMBER='G22026-050',
 LOCATION='R5P1',
 ROOM='CPU0',
 SEC='1',
 CDS_LIB='mstr_discrete',
 CDS_PART_NAME='RES_0603-100.0K,1%,1/10W,CHIP,A',
 PRIM_FILE='./archive_libs/mstr_discrete/res/chips/chips.prt';

PART_NAME
 R5P2 'RES_0402-49.9,1%,1/16W,CHIP,G2A':
 ROOM='CPU0';

SECTION_NUMBER 1
 '@BASEBOARD_FAB2_LIB.BASEBOARD_FAB2(SCH_1):PAGE90_I79@MSTR_DISCRETE.RES(CHIPS)':
 C_PATH='@baseboard_fab2_lib.baseboard_fab2(sch_1):page90_i79@mstr_discrete.res(~
chips)',
 P_PATH='@baseboard_fab2_lib.baseboard_fab2(sch_1):page90_i79@mstr_discrete.res(~
chips)',
 PATH='I79',
 DRAWING='@BASEBOARD_FAB2_LIB.BASEBOARD_FAB2(SCH_1):PAGE90',
 WATTAGE='1/16W',
 TOLERANCE='1%',
 SEC_TYPE='0402',
 MATERIAL='CHIP',
 PHYS_PAGE='90',
 XY='(-1575,3200)',
 ROT='0',
 VER='1',
 VALUE='49.9',
 PACK_TYPE='0402',
 PART_NUMBER='G21796-047',
 LOCATION='R5P2',
 ROOM='CPU0',
 SEC='1',
 CDS_LIB='mstr_discrete',
 CDS_PART_NAME='RES_0402-49.9,1%,1/16W,CHIP,G2A',
 PRIM_FILE='./archive_libs/mstr_discrete/res/chips/chips.prt';

PART_NAME
 R5P3 'RES_0402-49.9,1%,1/16W,CHIP,G2A':
 ROOM='CPU0';

SECTION_NUMBER 1
 '@BASEBOARD_FAB2_LIB.BASEBOARD_FAB2(SCH_1):PAGE90_I80@MSTR_DISCRETE.RES(CHIPS)':
 C_PATH='@baseboard_fab2_lib.baseboard_fab2(sch_1):page90_i80@mstr_discrete.res(~
chips)',
 P_PATH='@baseboard_fab2_lib.baseboard_fab2(sch_1):page90_i80@mstr_discrete.res(~
chips)',
 PATH='I80',
 DRAWING='@BASEBOARD_FAB2_LIB.BASEBOARD_FAB2(SCH_1):PAGE90',
 WATTAGE='1/16W',
 TOLERANCE='1%',
 SEC_TYPE='0402',
 MATERIAL='CHIP',
 PHYS_PAGE='90',
 XY='(-1575,3075)',
 ROT='0',
 VER='1',
 VALUE='49.9',
 PACK_TYPE='0402',
 PART_NUMBER='G21796-047',
 LOCATION='R5P3',
 ROOM='CPU0',
 SEC='1',
 CDS_LIB='mstr_discrete',
 CDS_PART_NAME='RES_0402-49.9,1%,1/16W,CHIP,G2A',
 PRIM_FILE='./archive_libs/mstr_discrete/res/chips/chips.prt';

PART_NAME
 R5P4 'RES_0402-49.9,1%,1/16W,CHIP,G2A':
 ROOM='CPU0';

SECTION_NUMBER 1
 '@BASEBOARD_FAB2_LIB.BASEBOARD_FAB2(SCH_1):PAGE22_I190@MSTR_DISCRETE.RES(CHIPS)':
 C_PATH='@baseboard_fab2_lib.baseboard_fab2(sch_1):page22_i190@mstr_discrete.res~
(chips)',
 P_PATH='@baseboard_fab2_lib.baseboard_fab2(sch_1):page22_i190@mstr_discrete.res~
(chips)',
 PATH='I190',
 DRAWING='@BASEBOARD_FAB2_LIB.BASEBOARD_FAB2(SCH_1):PAGE22',
 WATTAGE='1/16W',
 TOLERANCE='1%',
 SEC_TYPE='0402',
 MATERIAL='CHIP',
 PHYS_PAGE='22',
 XY='(-575,2775)',
 ROT='0',
 VER='2',
 VALUE='49.9',
 PACK_TYPE='0402',
 PART_NUMBER='G21796-047',
 LOCATION='R5P4',
 ROOM='CPU0',
 SEC='1',
 CDS_LIB='mstr_discrete',
 CDS_PART_NAME='RES_0402-49.9,1%,1/16W,CHIP,G2A',
 PRIM_FILE='./archive_libs/mstr_discrete/res/chips/chips.prt';

PART_NAME
 R5R1 'RES_0402-49.9,1%,1/16W,CHIP,G2A':
 ROOM='CPU0';

SECTION_NUMBER 1
 '@BASEBOARD_FAB2_LIB.BASEBOARD_FAB2(SCH_1):PAGE22_I188@MSTR_DISCRETE.RES(CHIPS)':
 C_PATH='@baseboard_fab2_lib.baseboard_fab2(sch_1):page22_i188@mstr_discrete.res~
(chips)',
 P_PATH='@baseboard_fab2_lib.baseboard_fab2(sch_1):page22_i188@mstr_discrete.res~
(chips)',
 PATH='I188',
 DRAWING='@BASEBOARD_FAB2_LIB.BASEBOARD_FAB2(SCH_1):PAGE22',
 WATTAGE='1/16W',
 TOLERANCE='1%',
 SEC_TYPE='0402',
 MATERIAL='CHIP',
 PHYS_PAGE='22',
 XY='(-300,2775)',
 ROT='0',
 VER='2',
 VALUE='49.9',
 PACK_TYPE='0402',
 PART_NUMBER='G21796-047',
 LOCATION='R5R1',
 ROOM='CPU0',
 SEC='1',
 CDS_LIB='mstr_discrete',
 CDS_PART_NAME='RES_0402-49.9,1%,1/16W,CHIP,G2A',
 PRIM_FILE='./archive_libs/mstr_discrete/res/chips/chips.prt';

PART_NAME
 R5W1 'RES_0402-0.0,5%,1/16W,CHIP,G21A':
 GROUP='MCP';

SECTION_NUMBER 1
 '@BASEBOARD_FAB2_LIB.BASEBOARD_FAB2(SCH_1):PAGE113_I272@MSTR_DISCRETE.RES(CHIPS)':
 C_PATH='@baseboard_fab2_lib.baseboard_fab2(sch_1):page113_i272@mstr_discrete.re~
s(chips)',
 P_PATH='@baseboard_fab2_lib.baseboard_fab2(sch_1):page113_i272@mstr_discrete.re~
s(chips)',
 PATH='I272',
 DRAWING='@BASEBOARD_FAB2_LIB.BASEBOARD_FAB2(SCH_1):PAGE113',
 WATTAGE='1/16W',
 TOLERANCE='5%',
 SEC_TYPE='0402',
 MATERIAL='CHIP',
 PHYS_PAGE='113',
 XY='(1600,3750)',
 ROT='0',
 VER='1',
 VALUE='0.0',
 PACK_TYPE='0402',
 PART_NUMBER='G21497-005',
 LOCATION='R5W1',
 GROUP='MCP',
 SEC='1',
 CDS_LIB='mstr_discrete',
 CDS_PART_NAME='RES_0402-0.0,5%,1/16W,CHIP,G21A',
 PRIM_FILE='./archive_libs/mstr_discrete/res/chips/chips.prt';

PART_NAME
 R5W2 'RES_0402-0.0,5%,1/16W,CHIP,G21A':
 GROUP='MCP';

SECTION_NUMBER 1
 '@BASEBOARD_FAB2_LIB.BASEBOARD_FAB2(SCH_1):PAGE113_I273@MSTR_DISCRETE.RES(CHIPS)':
 C_PATH='@baseboard_fab2_lib.baseboard_fab2(sch_1):page113_i273@mstr_discrete.re~
s(chips)',
 P_PATH='@baseboard_fab2_lib.baseboard_fab2(sch_1):page113_i273@mstr_discrete.re~
s(chips)',
 PATH='I273',
 DRAWING='@BASEBOARD_FAB2_LIB.BASEBOARD_FAB2(SCH_1):PAGE113',
 WATTAGE='1/16W',
 TOLERANCE='5%',
 MATERIAL='CHIP',
 PHYS_PAGE='113',
 XY='(1600,2375)',
 ROT='0',
 VER='1',
 VALUE='0.0',
 PACK_TYPE='0402',
 PART_NUMBER='G21497-005',
 LOCATION='R5W2',
 GROUP='MCP',
 CDS_LIB='mstr_discrete',
 CDS_PART_NAME='RES_0402-0.0,5%,1/16W,CHIP,G21A',
 PRIM_FILE='./archive_libs/mstr_discrete/res/chips/chips.prt';

PART_NAME
 R6B1 'RES_0402-49.9,1%,1/16W,CHIP,G2A':
 ROOM='CPU0';

SECTION_NUMBER 1
 '@BASEBOARD_FAB2_LIB.BASEBOARD_FAB2(SCH_1):PAGE21_I161@MSTR_DISCRETE.RES(CHIPS)':
 C_PATH='@baseboard_fab2_lib.baseboard_fab2(sch_1):page21_i161@mstr_discrete.res~
(chips)',
 P_PATH='@baseboard_fab2_lib.baseboard_fab2(sch_1):page21_i161@mstr_discrete.res~
(chips)',
 PATH='I161',
 DRAWING='@BASEBOARD_FAB2_LIB.BASEBOARD_FAB2(SCH_1):PAGE21',
 WATTAGE='1/16W',
 TOLERANCE='1%',
 SEC_TYPE='0402',
 MATERIAL='CHIP',
 BOM_COST='PROC_SIDEBAND',
 PHYS_PAGE='21',
 XY='(-750,4300)',
 ROT='0',
 VER='2',
 VALUE='49.9',
 PACK_TYPE='0402',
 PART_NUMBER='G21796-047',
 LOCATION='R6B1',
 ROOM='CPU0',
 SEC='1',
 CDS_LIB='mstr_discrete',
 CDS_PART_NAME='RES_0402-49.9,1%,1/16W,CHIP,G2A',
 PRIM_FILE='./archive_libs/mstr_discrete/res/chips/chips.prt';

PART_NAME
 R6B2 'RES_0402-100.0,1%,1/16W,CHIP,GA':
 ROOM='CPU0';

SECTION_NUMBER 1
 '@BASEBOARD_FAB2_LIB.BASEBOARD_FAB2(SCH_1):PAGE21_I159@MSTR_DISCRETE.RES(CHIPS)':
 C_PATH='@baseboard_fab2_lib.baseboard_fab2(sch_1):page21_i159@mstr_discrete.res~
(chips)',
 P_PATH='@baseboard_fab2_lib.baseboard_fab2(sch_1):page21_i159@mstr_discrete.res~
(chips)',
 PATH='I159',
 DRAWING='@BASEBOARD_FAB2_LIB.BASEBOARD_FAB2(SCH_1):PAGE21',
 WATTAGE='1/16W',
 TOLERANCE='1%',
 SEC_TYPE='0402',
 MATERIAL='CHIP',
 BOM_COST='PROC_SIDEBAND',
 PHYS_PAGE='21',
 XY='(-1000,4300)',
 ROT='0',
 VER='2',
 VALUE='100.0',
 PACK_TYPE='0402',
 PART_NUMBER='G21796-017',
 LOCATION='R6B2',
 ROOM='CPU0',
 SEC='1',
 CDS_LIB='mstr_discrete',
 CDS_PART_NAME='RES_0402-100.0,1%,1/16W,CHIP,GA',
 PRIM_FILE='./archive_libs/mstr_discrete/res/chips/chips.prt';

PART_NAME
 R6B3 'RES_0402-221,1.0%,1/16W,CHIP,GA':
 ROOM='CPU0';

SECTION_NUMBER 1
 '@BASEBOARD_FAB2_LIB.BASEBOARD_FAB2(SCH_1):PAGE21_I152@MSTR_DISCRETE.RES(CHIPS)':
 C_PATH='@baseboard_fab2_lib.baseboard_fab2(sch_1):page21_i152@mstr_discrete.res~
(chips)',
 P_PATH='@baseboard_fab2_lib.baseboard_fab2(sch_1):page21_i152@mstr_discrete.res~
(chips)',
 PATH='I152',
 DRAWING='@BASEBOARD_FAB2_LIB.BASEBOARD_FAB2(SCH_1):PAGE21',
 WATTAGE='1/16W',
 TOLERANCE='1.0%',
 SEC_TYPE='0402',
 MATERIAL='CHIP',
 BOM_COST='PROC_SIDEBAND',
 PHYS_PAGE='21',
 XY='(-2000,3900)',
 ROT='0',
 VER='1',
 VALUE='221',
 PACK_TYPE='0402',
 PART_NUMBER='G21796-271',
 LOCATION='R6B3',
 ROOM='CPU0',
 SEC='1',
 CDS_LIB='mstr_discrete',
 CDS_PART_NAME='RES_0402-221,1.0%,1/16W,CHIP,GA',
 PRIM_FILE='./archive_libs/mstr_discrete/res/chips/chips.prt';

PART_NAME
 R6B4 'RES_0402-0.0,5%,1/16W,CHIP,G21A':
 ROOM='CPU0';

SECTION_NUMBER 1
 '@BASEBOARD_FAB2_LIB.BASEBOARD_FAB2(SCH_1):PAGE21_I154@MSTR_DISCRETE.RES(CHIPS)':
 C_PATH='@baseboard_fab2_lib.baseboard_fab2(sch_1):page21_i154@mstr_discrete.res~
(chips)',
 P_PATH='@baseboard_fab2_lib.baseboard_fab2(sch_1):page21_i154@mstr_discrete.res~
(chips)',
 PATH='I154',
 DRAWING='@BASEBOARD_FAB2_LIB.BASEBOARD_FAB2(SCH_1):PAGE21',
 WATTAGE='1/16W',
 TOLERANCE='5%',
 SEC_TYPE='0402',
 MATERIAL='CHIP',
 BOM_COST='PROC_SIDEBAND',
 PHYS_PAGE='21',
 XY='(-2000,4000)',
 ROT='0',
 VER='1',
 VALUE='0.0',
 PACK_TYPE='0402',
 PART_NUMBER='G21497-005',
 LOCATION='R6B4',
 ROOM='CPU0',
 SEC='1',
 CDS_LIB='mstr_discrete',
 CDS_PART_NAME='RES_0402-0.0,5%,1/16W,CHIP,G21A',
 PRIM_FILE='./archive_libs/mstr_discrete/res/chips/chips.prt';

PART_NAME
 R6B5 'RES_0402-0.0,5%,1/16W,CHIP,G21A':
 ROOM='CPU0';

SECTION_NUMBER 1
 '@BASEBOARD_FAB2_LIB.BASEBOARD_FAB2(SCH_1):PAGE21_I153@MSTR_DISCRETE.RES(CHIPS)':
 C_PATH='@baseboard_fab2_lib.baseboard_fab2(sch_1):page21_i153@mstr_discrete.res~
(chips)',
 P_PATH='@baseboard_fab2_lib.baseboard_fab2(sch_1):page21_i153@mstr_discrete.res~
(chips)',
 PATH='I153',
 DRAWING='@BASEBOARD_FAB2_LIB.BASEBOARD_FAB2(SCH_1):PAGE21',
 WATTAGE='1/16W',
 TOLERANCE='5%',
 SEC_TYPE='0402',
 MATERIAL='CHIP',
 BOM_COST='PROC_SIDEBAND',
 PHYS_PAGE='21',
 XY='(-2000,3950)',
 ROT='0',
 VER='1',
 VALUE='0.0',
 PACK_TYPE='0402',
 PART_NUMBER='G21497-005',
 LOCATION='R6B5',
 ROOM='CPU0',
 SEC='1',
 CDS_LIB='mstr_discrete',
 CDS_PART_NAME='RES_0402-0.0,5%,1/16W,CHIP,G21A',
 PRIM_FILE='./archive_libs/mstr_discrete/res/chips/chips.prt';

PART_NAME
 R6D1 'RES_0402-100.0,1%,1/16W,CHIP,GA':
 ROOM='CPU0';

SECTION_NUMBER 1
 '@BASEBOARD_FAB2_LIB.BASEBOARD_FAB2(SCH_1):PAGE21_I179@MSTR_DISCRETE.RES(CHIPS)':
 C_PATH='@baseboard_fab2_lib.baseboard_fab2(sch_1):page21_i179@mstr_discrete.res~
(chips)',
 P_PATH='@baseboard_fab2_lib.baseboard_fab2(sch_1):page21_i179@mstr_discrete.res~
(chips)',
 PATH='I179',
 DRAWING='@BASEBOARD_FAB2_LIB.BASEBOARD_FAB2(SCH_1):PAGE21',
 WATTAGE='1/16W',
 TOLERANCE='1%',
 SEC_TYPE='0402',
 MATERIAL='CHIP',
 BOM_COST='PROC_SOCKET',
 PHYS_PAGE='21',
 XY='(-7125,2925)',
 ROT='2',
 VER='2',
 VALUE='100.0',
 PACK_TYPE='0402',
 PART_NUMBER='G21796-017',
 LOCATION='R6D1',
 ROOM='CPU0',
 SEC='1',
 CDS_LIB='mstr_discrete',
 CDS_PART_NAME='RES_0402-100.0,1%,1/16W,CHIP,GA',
 PRIM_FILE='./archive_libs/mstr_discrete/res/chips/chips.prt';

PART_NAME
 R6D2 'RES_0402-49.9,1%,1/16W,CHIP,G2A':
 ROOM='CPU0';

SECTION_NUMBER 1
 '@BASEBOARD_FAB2_LIB.BASEBOARD_FAB2(SCH_1):PAGE21_I204@MSTR_DISCRETE.RES(CHIPS)':
 C_PATH='@baseboard_fab2_lib.baseboard_fab2(sch_1):page21_i204@mstr_discrete.res~
(chips)',
 P_PATH='@baseboard_fab2_lib.baseboard_fab2(sch_1):page21_i204@mstr_discrete.res~
(chips)',
 PATH='I204',
 DRAWING='@BASEBOARD_FAB2_LIB.BASEBOARD_FAB2(SCH_1):PAGE21',
 WATTAGE='1/16W',
 TOLERANCE='1%',
 SEC_TYPE='0402',
 MATERIAL='CHIP',
 BOM_COST='PROC_SOCKET',
 PHYS_PAGE='21',
 XY='(-6900,2000)',
 ROT='2',
 VER='2',
 VALUE='49.9',
 PACK_TYPE='0402',
 PART_NUMBER='G21796-047',
 LOCATION='R6D2',
 ROOM='CPU0',
 SEC='1',
 CDS_LIB='mstr_discrete',
 CDS_PART_NAME='RES_0402-49.9,1%,1/16W,CHIP,G2A',
 PRIM_FILE='./archive_libs/mstr_discrete/res/chips/chips.prt';

PART_NAME
 R6D5 'RES_0402-49.9,1%,1/16W,CHIP,G2A':
 ROOM='CPU0';

SECTION_NUMBER 1
 '@BASEBOARD_FAB2_LIB.BASEBOARD_FAB2(SCH_1):PAGE90_I81@MSTR_DISCRETE.RES(CHIPS)':
 C_PATH='@baseboard_fab2_lib.baseboard_fab2(sch_1):page90_i81@mstr_discrete.res(~
chips)',
 P_PATH='@baseboard_fab2_lib.baseboard_fab2(sch_1):page90_i81@mstr_discrete.res(~
chips)',
 PATH='I81',
 DRAWING='@BASEBOARD_FAB2_LIB.BASEBOARD_FAB2(SCH_1):PAGE90',
 WATTAGE='1/16W',
 TOLERANCE='1%',
 SEC_TYPE='0402',
 MATERIAL='CHIP',
 PHYS_PAGE='90',
 XY='(-1575,2925)',
 ROT='0',
 VER='1',
 VALUE='49.9',
 PACK_TYPE='0402',
 PART_NUMBER='G21796-047',
 LOCATION='R6D5',
 ROOM='CPU0',
 SEC='1',
 CDS_LIB='mstr_discrete',
 CDS_PART_NAME='RES_0402-49.9,1%,1/16W,CHIP,G2A',
 PRIM_FILE='./archive_libs/mstr_discrete/res/chips/chips.prt';

PART_NAME
 R6D6 'RES_0402-240,1.0%,1/16W,EMPTY,A':
 ROOM='PROC_SIDEBAND';

SECTION_NUMBER 1
 '@BASEBOARD_FAB2_LIB.BASEBOARD_FAB2(SCH_1):PAGE90_I101@MSTR_DISCRETE.RES(CHIPS)':
 C_PATH='@baseboard_fab2_lib.baseboard_fab2(sch_1):page90_i101@mstr_discrete.res~
(chips)',
 P_PATH='@baseboard_fab2_lib.baseboard_fab2(sch_1):page90_i101@mstr_discrete.res~
(chips)',
 PATH='I101',
 DRAWING='@BASEBOARD_FAB2_LIB.BASEBOARD_FAB2(SCH_1):PAGE90',
 WATTAGE='1/16W',
 TOLERANCE='1.0%',
 SEC_TYPE='0402',
 MATERIAL='EMPTY',
 BOM_COST='PROC',
 PHYS_PAGE='90',
 XY='(-575,3400)',
 ROT='0',
 VER='1',
 VALUE='240',
 PACK_TYPE='0402',
 PART_NUMBER='G21796-294',
 LOCATION='R6D6',
 ROOM='PROC_SIDEBAND',
 SEC='1',
 CDS_LIB='mstr_discrete',
 CDS_PART_NAME='RES_0402-240,1.0%,1/16W,EMPTY,A',
 PRIM_FILE='./archive_libs/mstr_discrete/res/chips/chips.prt';

PART_NAME
 R6D7 'RES_0402-240,1.0%,1/16W,EMPTY,A':
 ROOM='PROC_SIDEBAND';

SECTION_NUMBER 1
 '@BASEBOARD_FAB2_LIB.BASEBOARD_FAB2(SCH_1):PAGE90_I31@MSTR_DISCRETE.RES(CHIPS)':
 C_PATH='@baseboard_fab2_lib.baseboard_fab2(sch_1):page90_i31@mstr_discrete.res(~
chips)',
 P_PATH='@baseboard_fab2_lib.baseboard_fab2(sch_1):page90_i31@mstr_discrete.res(~
chips)',
 PATH='I31',
 DRAWING='@BASEBOARD_FAB2_LIB.BASEBOARD_FAB2(SCH_1):PAGE90',
 WATTAGE='1/16W',
 TOLERANCE='1.0%',
 SEC_TYPE='0402',
 MATERIAL='EMPTY',
 BOM_COST='PROC',
 PHYS_PAGE='90',
 XY='(-2475,4200)',
 ROT='0',
 VER='1',
 VALUE='240',
 PACK_TYPE='0402',
 PART_NUMBER='G21796-294',
 LOCATION='R6D7',
 ROOM='PROC_SIDEBAND',
 SEC='1',
 CDS_LIB='mstr_discrete',
 CDS_PART_NAME='RES_0402-240,1.0%,1/16W,EMPTY,A',
 PRIM_FILE='./archive_libs/mstr_discrete/res/chips/chips.prt';

PART_NAME
 R6D8 'RES_0402-49.9,1%,1/16W,CHIP,G2A':
 ROOM='PROC_RSTS_PGOODS';

SECTION_NUMBER 1
 '@BASEBOARD_FAB2_LIB.BASEBOARD_FAB2(SCH_1):PAGE96_I3@MSTR_DISCRETE.RES(CHIPS)':
 C_PATH='@baseboard_fab2_lib.baseboard_fab2(sch_1):page96_i3@mstr_discrete.res(c~
hips)',
 P_PATH='@baseboard_fab2_lib.baseboard_fab2(sch_1):page96_i3@mstr_discrete.res(c~
hips)',
 PATH='I3',
 DRAWING='@BASEBOARD_FAB2_LIB.BASEBOARD_FAB2(SCH_1):PAGE96',
 WATTAGE='1/16W',
 TOLERANCE='1%',
 SEC_TYPE='0402',
 MATERIAL='CHIP',
 BOM_COST='PROC_SIDEBAND',
 PHYS_PAGE='96',
 XY='(1700,4450)',
 ROT='2',
 VER='2',
 VALUE='49.9',
 PACK_TYPE='0402',
 PART_NUMBER='G21796-047',
 LOCATION='R6D8',
 ROOM='PROC_RSTS_PGOODS',
 SEC='1',
 CDS_LIB='mstr_discrete',
 CDS_PART_NAME='RES_0402-49.9,1%,1/16W,CHIP,G2A',
 PRIM_FILE='./archive_libs/mstr_discrete/res/chips/chips.prt';

PART_NAME
 R6D9 'RES_0402-150.0,1%,1/16W,CHIP,GA':
 ROOM='PROC_SIDEBAND';

SECTION_NUMBER 1
 '@BASEBOARD_FAB2_LIB.BASEBOARD_FAB2(SCH_1):PAGE92_I64@MSTR_DISCRETE.RES(CHIPS)':
 C_PATH='@baseboard_fab2_lib.baseboard_fab2(sch_1):page92_i64@mstr_discrete.res(~
chips)',
 P_PATH='@baseboard_fab2_lib.baseboard_fab2(sch_1):page92_i64@mstr_discrete.res(~
chips)',
 PATH='I64',
 DRAWING='@BASEBOARD_FAB2_LIB.BASEBOARD_FAB2(SCH_1):PAGE92',
 WATTAGE='1/16W',
 TOLERANCE='1%',
 SEC_TYPE='0402',
 MATERIAL='CHIP',
 BOM_COST='PROC_SIDEBAND',
 PHYS_PAGE='92',
 XY='(-4600,1825)',
 ROT='2',
 VER='2',
 VALUE='150.0',
 PACK_TYPE='0402',
 PART_NUMBER='G21796-009',
 LOCATION='R6D9',
 ROOM='PROC_SIDEBAND',
 SEC='1',
 CDS_LIB='mstr_discrete',
 CDS_PART_NAME='RES_0402-150.0,1%,1/16W,CHIP,GA',
 PRIM_FILE='./archive_libs/mstr_discrete/res/chips/chips.prt';

PART_NAME
 R6D10 'RES_0402-240,1.0%,1/16W,EMPTY,A':
 ROOM='PROC_SIDEBAND';

SECTION_NUMBER 1
 '@BASEBOARD_FAB2_LIB.BASEBOARD_FAB2(SCH_1):PAGE90_I49@MSTR_DISCRETE.RES(CHIPS)':
 C_PATH='@baseboard_fab2_lib.baseboard_fab2(sch_1):page90_i49@mstr_discrete.res(~
chips)',
 P_PATH='@baseboard_fab2_lib.baseboard_fab2(sch_1):page90_i49@mstr_discrete.res(~
chips)',
 PATH='I49',
 DRAWING='@BASEBOARD_FAB2_LIB.BASEBOARD_FAB2(SCH_1):PAGE90',
 WATTAGE='1/16W',
 TOLERANCE='1.0%',
 SEC_TYPE='0402',
 MATERIAL='EMPTY',
 BOM_COST='PROC',
 PHYS_PAGE='90',
 XY='(-475,4200)',
 ROT='0',
 VER='1',
 VALUE='240',
 PACK_TYPE='0402',
 PART_NUMBER='G21796-294',
 LOCATION='R6D10',
 ROOM='PROC_SIDEBAND',
 SEC='1',
 CDS_LIB='mstr_discrete',
 CDS_PART_NAME='RES_0402-240,1.0%,1/16W,EMPTY,A',
 PRIM_FILE='./archive_libs/mstr_discrete/res/chips/chips.prt';

PART_NAME
 R6D11 'RES_0402-49.9,1%,1/16W,CHIP,G2A':
 ROOM='CPU0';

SECTION_NUMBER 1
 '@BASEBOARD_FAB2_LIB.BASEBOARD_FAB2(SCH_1):PAGE21_I184@MSTR_DISCRETE.RES(CHIPS)':
 C_PATH='@baseboard_fab2_lib.baseboard_fab2(sch_1):page21_i184@mstr_discrete.res~
(chips)',
 P_PATH='@baseboard_fab2_lib.baseboard_fab2(sch_1):page21_i184@mstr_discrete.res~
(chips)',
 PATH='I184',
 DRAWING='@BASEBOARD_FAB2_LIB.BASEBOARD_FAB2(SCH_1):PAGE21',
 WATTAGE='1/16W',
 TOLERANCE='1%',
 SEC_TYPE='0402',
 MATERIAL='CHIP',
 BOM_COST='PROC_SOCKET',
 PHYS_PAGE='21',
 XY='(-7350,2000)',
 ROT='2',
 VER='2',
 VALUE='49.9',
 PACK_TYPE='0402',
 PART_NUMBER='G21796-047',
 LOCATION='R6D11',
 ROOM='CPU0',
 SEC='1',
 CDS_LIB='mstr_discrete',
 CDS_PART_NAME='RES_0402-49.9,1%,1/16W,CHIP,G2A',
 PRIM_FILE='./archive_libs/mstr_discrete/res/chips/chips.prt';

PART_NAME
 R6D12 'RES_0402-49.9,1%,1/16W,CHIP,G2A':
 ROOM='PROC_RSTS_PGOODS';

SECTION_NUMBER 1
 '@BASEBOARD_FAB2_LIB.BASEBOARD_FAB2(SCH_1):PAGE96_I2@MSTR_DISCRETE.RES(CHIPS)':
 C_PATH='@baseboard_fab2_lib.baseboard_fab2(sch_1):page96_i2@mstr_discrete.res(c~
hips)',
 P_PATH='@baseboard_fab2_lib.baseboard_fab2(sch_1):page96_i2@mstr_discrete.res(c~
hips)',
 PATH='I2',
 DRAWING='@BASEBOARD_FAB2_LIB.BASEBOARD_FAB2(SCH_1):PAGE96',
 WATTAGE='1/16W',
 TOLERANCE='1%',
 SEC_TYPE='0402',
 MATERIAL='CHIP',
 BOM_COST='PROC_SIDEBAND',
 PHYS_PAGE='96',
 XY='(1900,4450)',
 ROT='0',
 VER='2',
 VALUE='49.9',
 PACK_TYPE='0402',
 PART_NUMBER='G21796-047',
 LOCATION='R6D12',
 ROOM='PROC_RSTS_PGOODS',
 SEC='1',
 CDS_LIB='mstr_discrete',
 CDS_PART_NAME='RES_0402-49.9,1%,1/16W,CHIP,G2A',
 PRIM_FILE='./archive_libs/mstr_discrete/res/chips/chips.prt';

PART_NAME
 R6D13 'RES_0402-240,1.0%,1/16W,EMPTY,A':
 ROOM='PROC_SIDEBAND';

SECTION_NUMBER 1
 '@BASEBOARD_FAB2_LIB.BASEBOARD_FAB2(SCH_1):PAGE90_I33@MSTR_DISCRETE.RES(CHIPS)':
 C_PATH='@baseboard_fab2_lib.baseboard_fab2(sch_1):page90_i33@mstr_discrete.res(~
chips)',
 P_PATH='@baseboard_fab2_lib.baseboard_fab2(sch_1):page90_i33@mstr_discrete.res(~
chips)',
 PATH='I33',
 DRAWING='@BASEBOARD_FAB2_LIB.BASEBOARD_FAB2(SCH_1):PAGE90',
 WATTAGE='1/16W',
 TOLERANCE='1.0%',
 SEC_TYPE='0402',
 MATERIAL='EMPTY',
 BOM_COST='PROC',
 PHYS_PAGE='90',
 XY='(-2475,3800)',
 ROT='0',
 VER='1',
 VALUE='240',
 PACK_TYPE='0402',
 PART_NUMBER='G21796-294',
 LOCATION='R6D13',
 ROOM='PROC_SIDEBAND',
 SEC='1',
 CDS_LIB='mstr_discrete',
 CDS_PART_NAME='RES_0402-240,1.0%,1/16W,EMPTY,A',
 PRIM_FILE='./archive_libs/mstr_discrete/res/chips/chips.prt';

PART_NAME
 R6D14 'RES_0402-240,1.0%,1/16W,EMPTY,A':
 ROOM='PROC_SIDEBAND';

SECTION_NUMBER 1
 '@BASEBOARD_FAB2_LIB.BASEBOARD_FAB2(SCH_1):PAGE90_I52@MSTR_DISCRETE.RES(CHIPS)':
 C_PATH='@baseboard_fab2_lib.baseboard_fab2(sch_1):page90_i52@mstr_discrete.res(~
chips)',
 P_PATH='@baseboard_fab2_lib.baseboard_fab2(sch_1):page90_i52@mstr_discrete.res(~
chips)',
 PATH='I52',
 DRAWING='@BASEBOARD_FAB2_LIB.BASEBOARD_FAB2(SCH_1):PAGE90',
 WATTAGE='1/16W',
 TOLERANCE='1.0%',
 SEC_TYPE='0402',
 MATERIAL='EMPTY',
 BOM_COST='PROC',
 PHYS_PAGE='90',
 XY='(-2475,3600)',
 ROT='0',
 VER='1',
 VALUE='240',
 PACK_TYPE='0402',
 PART_NUMBER='G21796-294',
 LOCATION='R6D14',
 ROOM='PROC_SIDEBAND',
 SEC='1',
 CDS_LIB='mstr_discrete',
 CDS_PART_NAME='RES_0402-240,1.0%,1/16W,EMPTY,A',
 PRIM_FILE='./archive_libs/mstr_discrete/res/chips/chips.prt';

PART_NAME
 R6D15 'RES_0402-240,1.0%,1/16W,EMPTY,A':
 ROOM='PROC_SIDEBAND';

SECTION_NUMBER 1
 '@BASEBOARD_FAB2_LIB.BASEBOARD_FAB2(SCH_1):PAGE90_I48@MSTR_DISCRETE.RES(CHIPS)':
 C_PATH='@baseboard_fab2_lib.baseboard_fab2(sch_1):page90_i48@mstr_discrete.res(~
chips)',
 P_PATH='@baseboard_fab2_lib.baseboard_fab2(sch_1):page90_i48@mstr_discrete.res(~
chips)',
 PATH='I48',
 DRAWING='@BASEBOARD_FAB2_LIB.BASEBOARD_FAB2(SCH_1):PAGE90',
 WATTAGE='1/16W',
 TOLERANCE='1.0%',
 SEC_TYPE='0402',
 MATERIAL='EMPTY',
 BOM_COST='PROC',
 PHYS_PAGE='90',
 XY='(-475,4400)',
 ROT='0',
 VER='1',
 VALUE='240',
 PACK_TYPE='0402',
 PART_NUMBER='G21796-294',
 LOCATION='R6D15',
 ROOM='PROC_SIDEBAND',
 SEC='1',
 CDS_LIB='mstr_discrete',
 CDS_PART_NAME='RES_0402-240,1.0%,1/16W,EMPTY,A',
 PRIM_FILE='./archive_libs/mstr_discrete/res/chips/chips.prt';

PART_NAME
 R6D16 'RES_0402-0.0,5%,1/16W,EMPTY,G2A':
 ROOM='BMC_MISC';

SECTION_NUMBER 1
 '@BASEBOARD_FAB2_LIB.BASEBOARD_FAB2(SCH_1):PAGE156_I299@MSTR_DISCRETE.RES(CHIPS)':
 C_PATH='@baseboard_fab2_lib.baseboard_fab2(sch_1):page156_i299@mstr_discrete.re~
s(chips)',
 P_PATH='@baseboard_fab2_lib.baseboard_fab2(sch_1):page156_i299@mstr_discrete.re~
s(chips)',
 PATH='I299',
 DRAWING='@BASEBOARD_FAB2_LIB.BASEBOARD_FAB2(SCH_1):PAGE156',
 WATTAGE='1/16W',
 TOLERANCE='5%',
 SEC_TYPE='0402',
 MATERIAL='EMPTY',
 BOM_COST='SM_CONTROLLER',
 PHYS_PAGE='156',
 XY='(-2900,1825)',
 ROT='0',
 VER='1',
 VALUE='0.0',
 PACK_TYPE='0402',
 PART_NUMBER='G21497-005',
 LOCATION='R6D16',
 ROOM='BMC_MISC',
 SEC='1',
 CDS_LIB='mstr_discrete',
 CDS_PART_NAME='RES_0402-0.0,5%,1/16W,EMPTY,G2A',
 PRIM_FILE='./archive_libs/mstr_discrete/res/chips/chips.prt';

PART_NAME
 R6F1 'RES_0402-49.9,1%,1/16W,CHIP,G2A':
 ROOM='NV_DIMM';

SECTION_NUMBER 1
 '@BASEBOARD_FAB2_LIB.BASEBOARD_FAB2(SCH_1):PAGE89_I4@MSTR_DISCRETE.RES(CHIPS)':
 C_PATH='@baseboard_fab2_lib.baseboard_fab2(sch_1):page89_i4@mstr_discrete.res(c~
hips)',
 P_PATH='@baseboard_fab2_lib.baseboard_fab2(sch_1):page89_i4@mstr_discrete.res(c~
hips)',
 PATH='I4',
 DRAWING='@BASEBOARD_FAB2_LIB.BASEBOARD_FAB2(SCH_1):PAGE89',
 WATTAGE='1/16W',
 TOLERANCE='1%',
 SEC_TYPE='0402',
 MATERIAL='CHIP',
 BOM_COST='MEM_NV',
 PHYS_PAGE='89',
 XY='(350,2825)',
 ROT='0',
 VER='1',
 VALUE='49.9',
 PACK_TYPE='0402',
 PART_NUMBER='G21796-047',
 LOCATION='R6F1',
 ROOM='NV_DIMM',
 SEC='1',
 CDS_LIB='mstr_discrete',
 CDS_PART_NAME='RES_0402-49.9,1%,1/16W,CHIP,G2A',
 PRIM_FILE='./archive_libs/mstr_discrete/res/chips/chips.prt';

PART_NAME
 R6F2 'RES_0402-49.9,1%,1/16W,CHIP,G2A':
 ROOM='NV_DIMM';

SECTION_NUMBER 1
 '@BASEBOARD_FAB2_LIB.BASEBOARD_FAB2(SCH_1):PAGE89_I6@MSTR_DISCRETE.RES(CHIPS)':
 C_PATH='@baseboard_fab2_lib.baseboard_fab2(sch_1):page89_i6@mstr_discrete.res(c~
hips)',
 P_PATH='@baseboard_fab2_lib.baseboard_fab2(sch_1):page89_i6@mstr_discrete.res(c~
hips)',
 PATH='I6',
 DRAWING='@BASEBOARD_FAB2_LIB.BASEBOARD_FAB2(SCH_1):PAGE89',
 WATTAGE='1/16W',
 TOLERANCE='1%',
 SEC_TYPE='0402',
 MATERIAL='CHIP',
 BOM_COST='MEM_NV',
 PHYS_PAGE='89',
 XY='(350,1650)',
 ROT='0',
 VER='1',
 VALUE='49.9',
 PACK_TYPE='0402',
 PART_NUMBER='G21796-047',
 LOCATION='R6F2',
 ROOM='NV_DIMM',
 SEC='1',
 CDS_LIB='mstr_discrete',
 CDS_PART_NAME='RES_0402-49.9,1%,1/16W,CHIP,G2A',
 PRIM_FILE='./archive_libs/mstr_discrete/res/chips/chips.prt';

PART_NAME
 R6F3 'RES_0402-10.0K,1%,1/16W,CHIP,GA':
 ROOM='NV_DIMM';

SECTION_NUMBER 1
 '@BASEBOARD_FAB2_LIB.BASEBOARD_FAB2(SCH_1):PAGE89_I7@MSTR_DISCRETE.RES(CHIPS)':
 C_PATH='@baseboard_fab2_lib.baseboard_fab2(sch_1):page89_i7@mstr_discrete.res(c~
hips)',
 P_PATH='@baseboard_fab2_lib.baseboard_fab2(sch_1):page89_i7@mstr_discrete.res(c~
hips)',
 PATH='I7',
 DRAWING='@BASEBOARD_FAB2_LIB.BASEBOARD_FAB2(SCH_1):PAGE89',
 WATTAGE='1/16W',
 TOLERANCE='1%',
 SEC_TYPE='0402',
 MATERIAL='CHIP',
 BOM_COST='MEM_NV',
 PHYS_PAGE='89',
 XY='(-450,3325)',
 ROT='0',
 VER='2',
 VALUE='10.0K',
 PACK_TYPE='0402',
 PART_NUMBER='G21796-016',
 LOCATION='R6F3',
 ROOM='NV_DIMM',
 SEC='1',
 CDS_LIB='mstr_discrete',
 CDS_PART_NAME='RES_0402-10.0K,1%,1/16W,CHIP,GA',
 PRIM_FILE='./archive_libs/mstr_discrete/res/chips/chips.prt';

PART_NAME
 R6F4 'RES_0402-49.9,1%,1/16W,CHIP,G2A':
 ROOM='NV_DIMM';

SECTION_NUMBER 1
 '@BASEBOARD_FAB2_LIB.BASEBOARD_FAB2(SCH_1):PAGE89_I3@MSTR_DISCRETE.RES(CHIPS)':
 C_PATH='@baseboard_fab2_lib.baseboard_fab2(sch_1):page89_i3@mstr_discrete.res(c~
hips)',
 P_PATH='@baseboard_fab2_lib.baseboard_fab2(sch_1):page89_i3@mstr_discrete.res(c~
hips)',
 PATH='I3',
 DRAWING='@BASEBOARD_FAB2_LIB.BASEBOARD_FAB2(SCH_1):PAGE89',
 WATTAGE='1/16W',
 TOLERANCE='1%',
 SEC_TYPE='0402',
 MATERIAL='CHIP',
 BOM_COST='MEM_NV',
 PHYS_PAGE='89',
 XY='(350,3125)',
 ROT='0',
 VER='1',
 VALUE='49.9',
 PACK_TYPE='0402',
 PART_NUMBER='G21796-047',
 LOCATION='R6F4',
 ROOM='NV_DIMM',
 SEC='1',
 CDS_LIB='mstr_discrete',
 CDS_PART_NAME='RES_0402-49.9,1%,1/16W,CHIP,G2A',
 PRIM_FILE='./archive_libs/mstr_discrete/res/chips/chips.prt';

PART_NAME
 R6F5 'RES_0402-49.9,1%,1/16W,CHIP,G2A':
 ROOM='NV_DIMM';

SECTION_NUMBER 1
 '@BASEBOARD_FAB2_LIB.BASEBOARD_FAB2(SCH_1):PAGE89_I5@MSTR_DISCRETE.RES(CHIPS)':
 C_PATH='@baseboard_fab2_lib.baseboard_fab2(sch_1):page89_i5@mstr_discrete.res(c~
hips)',
 P_PATH='@baseboard_fab2_lib.baseboard_fab2(sch_1):page89_i5@mstr_discrete.res(c~
hips)',
 PATH='I5',
 DRAWING='@BASEBOARD_FAB2_LIB.BASEBOARD_FAB2(SCH_1):PAGE89',
 WATTAGE='1/16W',
 TOLERANCE='1%',
 SEC_TYPE='0402',
 MATERIAL='CHIP',
 BOM_COST='MEM_NV',
 PHYS_PAGE='89',
 XY='(350,1950)',
 ROT='0',
 VER='1',
 VALUE='49.9',
 PACK_TYPE='0402',
 PART_NUMBER='G21796-047',
 LOCATION='R6F5',
 ROOM='NV_DIMM',
 SEC='1',
 CDS_LIB='mstr_discrete',
 CDS_PART_NAME='RES_0402-49.9,1%,1/16W,CHIP,G2A',
 PRIM_FILE='./archive_libs/mstr_discrete/res/chips/chips.prt';

PART_NAME
 R6F6 'RES_0402-0.0,5%,1/16W,EMPTY,G2A':
 ROOM='CLOCK_CPU0_OSC',
 NO_XNET_CONNECTION='1';

SECTION_NUMBER 1
 '@BASEBOARD_FAB2_LIB.BASEBOARD_FAB2(SCH_1):PAGE104_I41@MSTR_DISCRETE.RES(CHIPS)':
 C_PATH='@baseboard_fab2_lib.baseboard_fab2(sch_1):page104_i41@mstr_discrete.res~
(chips)',
 P_PATH='@baseboard_fab2_lib.baseboard_fab2(sch_1):page104_i41@mstr_discrete.res~
(chips)',
 PATH='I41',
 DRAWING='@BASEBOARD_FAB2_LIB.BASEBOARD_FAB2(SCH_1):PAGE104',
 WATTAGE='1/16W',
 TOLERANCE='5%',
 SEC_TYPE='0402',
 MATERIAL='EMPTY',
 NO_XNET_CONNECTION='1',
 PHYS_PAGE='104',
 XY='(525,5025)',
 ROT='0',
 VER='1',
 VALUE='0.0',
 PACK_TYPE='0402',
 PART_NUMBER='G21497-005',
 LOCATION='R6F6',
 ROOM='CLOCK_CPU0_OSC',
 SEC='1',
 CDS_LIB='mstr_discrete',
 CDS_PART_NAME='RES_0402-0.0,5%,1/16W,EMPTY,G2A',
 PRIM_FILE='./archive_libs/mstr_discrete/res/chips/chips.prt';

PART_NAME
 R6F7 'RES_0402-0.0,5%,1/16W,CHIP,G21A':
 ROOM='CLOCK_CPU0_OSC',
 NO_XNET_CONNECTION='1';

SECTION_NUMBER 1
 '@BASEBOARD_FAB2_LIB.BASEBOARD_FAB2(SCH_1):PAGE104_I67@MSTR_DISCRETE.RES(CHIPS)':
 C_PATH='@baseboard_fab2_lib.baseboard_fab2(sch_1):page104_i67@mstr_discrete.res~
(chips)',
 P_PATH='@baseboard_fab2_lib.baseboard_fab2(sch_1):page104_i67@mstr_discrete.res~
(chips)',
 PATH='I67',
 DRAWING='@BASEBOARD_FAB2_LIB.BASEBOARD_FAB2(SCH_1):PAGE104',
 WATTAGE='1/16W',
 TOLERANCE='5%',
 SEC_TYPE='0402',
 MATERIAL='CHIP',
 NO_XNET_CONNECTION='1',
 PHYS_PAGE='104',
 XY='(525,5175)',
 ROT='0',
 VER='1',
 VALUE='0.0',
 PACK_TYPE='0402',
 PART_NUMBER='G21497-005',
 LOCATION='R6F7',
 ROOM='CLOCK_CPU0_OSC',
 SEC='1',
 CDS_LIB='mstr_discrete',
 CDS_PART_NAME='RES_0402-0.0,5%,1/16W,CHIP,G21A',
 PRIM_FILE='./archive_libs/mstr_discrete/res/chips/chips.prt';

PART_NAME
 R6F8 'RES_0402-0.0,5%,1/16W,EMPTY,G2A':
 ROOM='CLOCK_CPU0_OSC',
 NO_XNET_CONNECTION='1';

SECTION_NUMBER 1
 '@BASEBOARD_FAB2_LIB.BASEBOARD_FAB2(SCH_1):PAGE104_I37@MSTR_DISCRETE.RES(CHIPS)':
 C_PATH='@baseboard_fab2_lib.baseboard_fab2(sch_1):page104_i37@mstr_discrete.res~
(chips)',
 P_PATH='@baseboard_fab2_lib.baseboard_fab2(sch_1):page104_i37@mstr_discrete.res~
(chips)',
 PATH='I37',
 DRAWING='@BASEBOARD_FAB2_LIB.BASEBOARD_FAB2(SCH_1):PAGE104',
 WATTAGE='1/16W',
 TOLERANCE='5%',
 SEC_TYPE='0402',
 MATERIAL='EMPTY',
 NO_XNET_CONNECTION='1',
 PHYS_PAGE='104',
 XY='(525,4325)',
 ROT='0',
 VER='1',
 VALUE='0.0',
 PACK_TYPE='0402',
 PART_NUMBER='G21497-005',
 LOCATION='R6F8',
 ROOM='CLOCK_CPU0_OSC',
 SEC='1',
 CDS_LIB='mstr_discrete',
 CDS_PART_NAME='RES_0402-0.0,5%,1/16W,EMPTY,G2A',
 PRIM_FILE='./archive_libs/mstr_discrete/res/chips/chips.prt';

PART_NAME
 R6F9 'RES_0402-0.0,5%,1/16W,CHIP,G21A':
 ROOM='CLOCK_CPU0_OSC',
 NO_XNET_CONNECTION='1';

SECTION_NUMBER 1
 '@BASEBOARD_FAB2_LIB.BASEBOARD_FAB2(SCH_1):PAGE104_I68@MSTR_DISCRETE.RES(CHIPS)':
 C_PATH='@baseboard_fab2_lib.baseboard_fab2(sch_1):page104_i68@mstr_discrete.res~
(chips)',
 P_PATH='@baseboard_fab2_lib.baseboard_fab2(sch_1):page104_i68@mstr_discrete.res~
(chips)',
 PATH='I68',
 DRAWING='@BASEBOARD_FAB2_LIB.BASEBOARD_FAB2(SCH_1):PAGE104',
 WATTAGE='1/16W',
 TOLERANCE='5%',
 SEC_TYPE='0402',
 MATERIAL='CHIP',
 NO_XNET_CONNECTION='1',
 PHYS_PAGE='104',
 XY='(525,4475)',
 ROT='0',
 VER='1',
 VALUE='0.0',
 PACK_TYPE='0402',
 PART_NUMBER='G21497-005',
 LOCATION='R6F9',
 ROOM='CLOCK_CPU0_OSC',
 SEC='1',
 CDS_LIB='mstr_discrete',
 CDS_PART_NAME='RES_0402-0.0,5%,1/16W,CHIP,G21A',
 PRIM_FILE='./archive_libs/mstr_discrete/res/chips/chips.prt';

PART_NAME
 R6F10 'RES_0402-0.0,5%,1/16W,EMPTY,G2A':;

SECTION_NUMBER 1
 '@BASEBOARD_FAB2_LIB.BASEBOARD_FAB2(SCH_1):PAGE104_I78@MSTR_DISCRETE.RES(CHIPS)':
 C_PATH='@baseboard_fab2_lib.baseboard_fab2(sch_1):page104_i78@mstr_discrete.res~
(chips)',
 P_PATH='@baseboard_fab2_lib.baseboard_fab2(sch_1):page104_i78@mstr_discrete.res~
(chips)',
 PATH='I78',
 DRAWING='@BASEBOARD_FAB2_LIB.BASEBOARD_FAB2(SCH_1):PAGE104',
 WATTAGE='1/16W',
 TOLERANCE='5%',
 SEC_TYPE='0402',
 MATERIAL='EMPTY',
 PHYS_PAGE='104',
 XY='(525,4825)',
 ROT='0',
 VER='1',
 VALUE='0.0',
 PACK_TYPE='0402',
 PART_NUMBER='G21497-005',
 LOCATION='R6F10',
 SEC='1',
 CDS_LIB='mstr_discrete',
 CDS_PART_NAME='RES_0402-0.0,5%,1/16W,EMPTY,G2A',
 PRIM_FILE='./archive_libs/mstr_discrete/res/chips/chips.prt';

PART_NAME
 R6F11 'RES_0402-0.0,5%,1/16W,EMPTY,G2A':;

SECTION_NUMBER 1
 '@BASEBOARD_FAB2_LIB.BASEBOARD_FAB2(SCH_1):PAGE104_I79@MSTR_DISCRETE.RES(CHIPS)':
 C_PATH='@baseboard_fab2_lib.baseboard_fab2(sch_1):page104_i79@mstr_discrete.res~
(chips)',
 P_PATH='@baseboard_fab2_lib.baseboard_fab2(sch_1):page104_i79@mstr_discrete.res~
(chips)',
 PATH='I79',
 DRAWING='@BASEBOARD_FAB2_LIB.BASEBOARD_FAB2(SCH_1):PAGE104',
 WATTAGE='1/16W',
 TOLERANCE='5%',
 SEC_TYPE='0402',
 MATERIAL='EMPTY',
 PHYS_PAGE='104',
 XY='(525,4125)',
 ROT='0',
 VER='1',
 VALUE='0.0',
 PACK_TYPE='0402',
 PART_NUMBER='G21497-005',
 LOCATION='R6F11',
 SEC='1',
 CDS_LIB='mstr_discrete',
 CDS_PART_NAME='RES_0402-0.0,5%,1/16W,EMPTY,G2A',
 PRIM_FILE='./archive_libs/mstr_discrete/res/chips/chips.prt';

PART_NAME
 R6L1 'RES_0402-1.00K,1%,1/16W,CHIP,GA':
 ROOM='PROC';

SECTION_NUMBER 1
 '@BASEBOARD_FAB2_LIB.BASEBOARD_FAB2(SCH_1):PAGE98_I64@MSTR_DISCRETE.RES(CHIPS)':
 C_PATH='@baseboard_fab2_lib.baseboard_fab2(sch_1):page98_i64@mstr_discrete.res(~
chips)',
 P_PATH='@baseboard_fab2_lib.baseboard_fab2(sch_1):page98_i64@mstr_discrete.res(~
chips)',
 PATH='I64',
 DRAWING='@BASEBOARD_FAB2_LIB.BASEBOARD_FAB2(SCH_1):PAGE98',
 WATTAGE='1/16W',
 TOLERANCE='1%',
 SEC_TYPE='0402',
 MATERIAL='CHIP',
 BOM_COST='PROC_SOCKET',
 PHYS_PAGE='98',
 XY='(2475,2000)',
 ROT='2',
 VER='2',
 VALUE='1.00K',
 PACK_TYPE='0402',
 PART_NUMBER='G21796-026',
 LOCATION='R6L1',
 ROOM='PROC',
 SEC='1',
 CDS_LIB='mstr_discrete',
 CDS_PART_NAME='RES_0402-1.00K,1%,1/16W,CHIP,GA',
 PRIM_FILE='./archive_libs/mstr_discrete/res/chips/chips.prt';

PART_NAME
 R6L2 'RES_0402-1.00K,1%,1/16W,CHIP,GA':
 ROOM='MEM';

SECTION_NUMBER 1
 '@BASEBOARD_FAB2_LIB.BASEBOARD_FAB2(SCH_1):PAGE98_I62@MSTR_DISCRETE.RES(CHIPS)':
 C_PATH='@baseboard_fab2_lib.baseboard_fab2(sch_1):page98_i62@mstr_discrete.res(~
chips)',
 P_PATH='@baseboard_fab2_lib.baseboard_fab2(sch_1):page98_i62@mstr_discrete.res(~
chips)',
 PATH='I62',
 DRAWING='@BASEBOARD_FAB2_LIB.BASEBOARD_FAB2(SCH_1):PAGE98',
 WATTAGE='1/16W',
 TOLERANCE='1%',
 SEC_TYPE='0402',
 MATERIAL='CHIP',
 BOM_COST='SM_CONTROLLER',
 PHYS_PAGE='98',
 XY='(2400,2650)',
 ROT='2',
 VER='2',
 VALUE='1.00K',
 PACK_TYPE='0402',
 PART_NUMBER='G21796-026',
 LOCATION='R6L2',
 ROOM='MEM',
 SEC='1',
 CDS_LIB='mstr_discrete',
 CDS_PART_NAME='RES_0402-1.00K,1%,1/16W,CHIP,GA',
 PRIM_FILE='./archive_libs/mstr_discrete/res/chips/chips.prt';

PART_NAME
 R6L3 'RES_0402-2,1.0%,1/16W,CHIP,G21A':
 ROOM='PROC';

SECTION_NUMBER 1
 '@BASEBOARD_FAB2_LIB.BASEBOARD_FAB2(SCH_1):PAGE98_I66@MSTR_DISCRETE.RES(CHIPS)':
 C_PATH='@baseboard_fab2_lib.baseboard_fab2(sch_1):page98_i66@mstr_discrete.res(~
chips)',
 P_PATH='@baseboard_fab2_lib.baseboard_fab2(sch_1):page98_i66@mstr_discrete.res(~
chips)',
 PATH='I66',
 DRAWING='@BASEBOARD_FAB2_LIB.BASEBOARD_FAB2(SCH_1):PAGE98',
 WATTAGE='1/16W',
 TOLERANCE='1.0%',
 SEC_TYPE='0402',
 MATERIAL='CHIP',
 BOM_COST='PROC_SOCKET',
 PHYS_PAGE='98',
 XY='(2175,2325)',
 ROT='0',
 VER='1',
 VALUE='2',
 PACK_TYPE='0402',
 PART_NUMBER='G21796-274',
 LOCATION='R6L3',
 ROOM='PROC',
 SEC='1',
 CDS_LIB='mstr_discrete',
 CDS_PART_NAME='RES_0402-2,1.0%,1/16W,CHIP,G21A',
 PRIM_FILE='./archive_libs/mstr_discrete/res/chips/chips.prt';

PART_NAME
 R6L4 'RES_0402-1.0M,1%,1/16W,EMPTY,GA':
 ROOM='VTT_DEF_PWR_VR';

SECTION_NUMBER 1
 '@BASEBOARD_FAB2_LIB.BASEBOARD_FAB2(SCH_1):PAGE222_I5@MSTR_DISCRETE.RES(CHIPS)':
 C_PATH='@baseboard_fab2_lib.baseboard_fab2(sch_1):page222_i5@mstr_discrete.res(~
chips)',
 P_PATH='@baseboard_fab2_lib.baseboard_fab2(sch_1):page222_i5@mstr_discrete.res(~
chips)',
 PATH='I5',
 DRAWING='@BASEBOARD_FAB2_LIB.BASEBOARD_FAB2(SCH_1):PAGE222',
 WATTAGE='1/16W',
 TOLERANCE='1%',
 SEC_TYPE='0402',
 MATERIAL='EMPTY',
 BOM_COST='MEM_VRD_VTT_DEF',
 PHYS_PAGE='222',
 XY='(-1100,200)',
 ROT='2',
 VER='2',
 VALUE='1.0M',
 PACK_TYPE='0402',
 PART_NUMBER='G21796-021',
 LOCATION='R6L4',
 ROOM='VTT_DEF_PWR_VR',
 SEC='1',
 CDS_LIB='mstr_discrete',
 CDS_PART_NAME='RES_0402-1.0M,1%,1/16W,EMPTY,GA',
 PRIM_FILE='./archive_libs/mstr_discrete/res/chips/chips.prt';

PART_NAME
 R6L5 'RES_0402-1.0M,1%,1/16W,EMPTY,GA':
 ROOM='VTT_KLM_PWR_VR';

SECTION_NUMBER 1
 '@BASEBOARD_FAB2_LIB.BASEBOARD_FAB2(SCH_1):PAGE230_I5@MSTR_DISCRETE.RES(CHIPS)':
 C_PATH='@baseboard_fab2_lib.baseboard_fab2(sch_1):page230_i5@mstr_discrete.res(~
chips)',
 P_PATH='@baseboard_fab2_lib.baseboard_fab2(sch_1):page230_i5@mstr_discrete.res(~
chips)',
 PATH='I5',
 DRAWING='@BASEBOARD_FAB2_LIB.BASEBOARD_FAB2(SCH_1):PAGE230',
 WATTAGE='1/16W',
 TOLERANCE='1%',
 SEC_TYPE='0402',
 MATERIAL='EMPTY',
 BOM_COST='MEM_VRD_VTT_KLM',
 PHYS_PAGE='230',
 XY='(-1975,-75)',
 ROT='2',
 VER='2',
 VALUE='1.0M',
 PACK_TYPE='0402',
 PART_NUMBER='G21796-021',
 LOCATION='R6L5',
 ROOM='VTT_KLM_PWR_VR',
 SEC='1',
 CDS_LIB='mstr_discrete',
 CDS_PART_NAME='RES_0402-1.0M,1%,1/16W,EMPTY,GA',
 PRIM_FILE='./archive_libs/mstr_discrete/res/chips/chips.prt';

PART_NAME
 R6L6 'RES_0402-0.0,5%,1/16W,CHIP,G21A':
 ROOM='VTT_KLM_PWR_VR',
 NO_XNET_CONNECTION='1';

SECTION_NUMBER 1
 '@BASEBOARD_FAB2_LIB.BASEBOARD_FAB2(SCH_1):PAGE230_I6@MSTR_DISCRETE.RES(CHIPS)':
 C_PATH='@baseboard_fab2_lib.baseboard_fab2(sch_1):page230_i6@mstr_discrete.res(~
chips)',
 P_PATH='@baseboard_fab2_lib.baseboard_fab2(sch_1):page230_i6@mstr_discrete.res(~
chips)',
 PATH='I6',
 DRAWING='@BASEBOARD_FAB2_LIB.BASEBOARD_FAB2(SCH_1):PAGE230',
 WATTAGE='1/16W',
 TOLERANCE='5%',
 SEC_TYPE='0402',
 MATERIAL='CHIP',
 BOM_COST='MEM_VRD_VTT_KLM',
 NO_XNET_CONNECTION='1',
 PHYS_PAGE='230',
 XY='(-2350,825)',
 ROT='1',
 VER='2',
 VALUE='0.0',
 PACK_TYPE='0402',
 PART_NUMBER='G21497-005',
 LOCATION='R6L6',
 ROOM='VTT_KLM_PWR_VR',
 SEC='1',
 CDS_LIB='mstr_discrete',
 CDS_PART_NAME='RES_0402-0.0,5%,1/16W,CHIP,G21A',
 PRIM_FILE='./archive_libs/mstr_discrete/res/chips/chips.prt';

PART_NAME
 R6L8 'RES_0402-0.0,5%,1/16W,CHIP,G21A':
 ROOM='VTT_KLM_PWR_VR';

SECTION_NUMBER 1
 '@BASEBOARD_FAB2_LIB.BASEBOARD_FAB2(SCH_1):PAGE230_I13@MSTR_DISCRETE.RES(CHIPS)':
 C_PATH='@baseboard_fab2_lib.baseboard_fab2(sch_1):page230_i13@mstr_discrete.res~
(chips)',
 P_PATH='@baseboard_fab2_lib.baseboard_fab2(sch_1):page230_i13@mstr_discrete.res~
(chips)',
 PATH='I13',
 DRAWING='@BASEBOARD_FAB2_LIB.BASEBOARD_FAB2(SCH_1):PAGE230',
 WATTAGE='1/16W',
 TOLERANCE='5%',
 SEC_TYPE='0402',
 MATERIAL='CHIP',
 BOM_COST='MEM_VRD_VTT_KLM',
 PHYS_PAGE='230',
 XY='(-1525,1025)',
 ROT='0',
 VER='1',
 VALUE='0.0',
 PACK_TYPE='0402',
 PART_NUMBER='G21497-005',
 LOCATION='R6L8',
 ROOM='VTT_KLM_PWR_VR',
 SEC='1',
 CDS_LIB='mstr_discrete',
 CDS_PART_NAME='RES_0402-0.0,5%,1/16W,CHIP,G21A',
 PRIM_FILE='./archive_libs/mstr_discrete/res/chips/chips.prt';

PART_NAME
 R6L9 'RES_0402-10.0K,1%,1/16W,CHIP,GA':
 ROOM='VTT_DEF_PWR_VR';

SECTION_NUMBER 1
 '@BASEBOARD_FAB2_LIB.BASEBOARD_FAB2(SCH_1):PAGE222_I23@MSTR_DISCRETE.RES(CHIPS)':
 C_PATH='@baseboard_fab2_lib.baseboard_fab2(sch_1):page222_i23@mstr_discrete.res~
(chips)',
 P_PATH='@baseboard_fab2_lib.baseboard_fab2(sch_1):page222_i23@mstr_discrete.res~
(chips)',
 PATH='I23',
 DRAWING='@BASEBOARD_FAB2_LIB.BASEBOARD_FAB2(SCH_1):PAGE222',
 WATTAGE='1/16W',
 TOLERANCE='1%',
 SEC_TYPE='0402',
 MATERIAL='CHIP',
 BOM_COST='MEM_VRD_VTT_DEF',
 PHYS_PAGE='222',
 XY='(2500,1650)',
 ROT='0',
 VER='2',
 VALUE='10.0K',
 PACK_TYPE='0402',
 PART_NUMBER='G21796-016',
 LOCATION='R6L9',
 ROOM='VTT_DEF_PWR_VR',
 SEC='1',
 CDS_LIB='mstr_discrete',
 CDS_PART_NAME='RES_0402-10.0K,1%,1/16W,CHIP,GA',
 PRIM_FILE='./archive_libs/mstr_discrete/res/chips/chips.prt';

PART_NAME
 R6L10 'RES_0402-0.0,5%,1/16W,CHIP,G21A':
 ROOM='VTT_DEF_PWR_VR',
 NO_XNET_CONNECTION='1';

SECTION_NUMBER 1
 '@BASEBOARD_FAB2_LIB.BASEBOARD_FAB2(SCH_1):PAGE222_I6@MSTR_DISCRETE.RES(CHIPS)':
 C_PATH='@baseboard_fab2_lib.baseboard_fab2(sch_1):page222_i6@mstr_discrete.res(~
chips)',
 P_PATH='@baseboard_fab2_lib.baseboard_fab2(sch_1):page222_i6@mstr_discrete.res(~
chips)',
 PATH='I6',
 DRAWING='@BASEBOARD_FAB2_LIB.BASEBOARD_FAB2(SCH_1):PAGE222',
 WATTAGE='1/16W',
 TOLERANCE='5%',
 SEC_TYPE='0402',
 MATERIAL='CHIP',
 BOM_COST='MEM_VRD_VTT_DEF',
 NO_XNET_CONNECTION='1',
 PHYS_PAGE='222',
 XY='(-1500,1100)',
 ROT='1',
 VER='2',
 VALUE='0.0',
 PACK_TYPE='0402',
 PART_NUMBER='G21497-005',
 LOCATION='R6L10',
 ROOM='VTT_DEF_PWR_VR',
 SEC='1',
 CDS_LIB='mstr_discrete',
 CDS_PART_NAME='RES_0402-0.0,5%,1/16W,CHIP,G21A',
 PRIM_FILE='./archive_libs/mstr_discrete/res/chips/chips.prt';

PART_NAME
 R6L11 'RES_0402-0.0,5%,1/16W,CHIP,G21A':
 ROOM='VTT_DEF_PWR_VR';

SECTION_NUMBER 1
 '@BASEBOARD_FAB2_LIB.BASEBOARD_FAB2(SCH_1):PAGE222_I10@MSTR_DISCRETE.RES(CHIPS)':
 C_PATH='@baseboard_fab2_lib.baseboard_fab2(sch_1):page222_i10@mstr_discrete.res~
(chips)',
 P_PATH='@baseboard_fab2_lib.baseboard_fab2(sch_1):page222_i10@mstr_discrete.res~
(chips)',
 PATH='I10',
 DRAWING='@BASEBOARD_FAB2_LIB.BASEBOARD_FAB2(SCH_1):PAGE222',
 WATTAGE='1/16W',
 TOLERANCE='5%',
 SEC_TYPE='0402',
 MATERIAL='CHIP',
 BOM_COST='MEM_VRD_VTT_DEF',
 PHYS_PAGE='222',
 XY='(-650,1300)',
 ROT='0',
 VER='1',
 VALUE='0.0',
 PACK_TYPE='0402',
 PART_NUMBER='G21497-005',
 LOCATION='R6L11',
 ROOM='VTT_DEF_PWR_VR',
 SEC='1',
 CDS_LIB='mstr_discrete',
 CDS_PART_NAME='RES_0402-0.0,5%,1/16W,CHIP,G21A',
 PRIM_FILE='./archive_libs/mstr_discrete/res/chips/chips.prt';

PART_NAME
 R6L12 'RES_0402-1.00K,1%,1/16W,CHIP,GA':
 ROOM='PROC';

SECTION_NUMBER 1
 '@BASEBOARD_FAB2_LIB.BASEBOARD_FAB2(SCH_1):PAGE98_I56@MSTR_DISCRETE.RES(CHIPS)':
 C_PATH='@baseboard_fab2_lib.baseboard_fab2(sch_1):page98_i56@mstr_discrete.res(~
chips)',
 P_PATH='@baseboard_fab2_lib.baseboard_fab2(sch_1):page98_i56@mstr_discrete.res(~
chips)',
 PATH='I56',
 DRAWING='@BASEBOARD_FAB2_LIB.BASEBOARD_FAB2(SCH_1):PAGE98',
 WATTAGE='1/16W',
 TOLERANCE='1%',
 SEC_TYPE='0402',
 MATERIAL='CHIP',
 BOM_COST='PROC_SOCKET',
 PHYS_PAGE='98',
 XY='(300,2025)',
 ROT='2',
 VER='2',
 VALUE='1.00K',
 PACK_TYPE='0402',
 PART_NUMBER='G21796-026',
 LOCATION='R6L12',
 ROOM='PROC',
 SEC='1',
 CDS_LIB='mstr_discrete',
 CDS_PART_NAME='RES_0402-1.00K,1%,1/16W,CHIP,GA',
 PRIM_FILE='./archive_libs/mstr_discrete/res/chips/chips.prt';

PART_NAME
 R6L13 'RES_0402-1.00K,1%,1/16W,CHIP,GA':
 ROOM='MEM';

SECTION_NUMBER 1
 '@BASEBOARD_FAB2_LIB.BASEBOARD_FAB2(SCH_1):PAGE98_I54@MSTR_DISCRETE.RES(CHIPS)':
 C_PATH='@baseboard_fab2_lib.baseboard_fab2(sch_1):page98_i54@mstr_discrete.res(~
chips)',
 P_PATH='@baseboard_fab2_lib.baseboard_fab2(sch_1):page98_i54@mstr_discrete.res(~
chips)',
 PATH='I54',
 DRAWING='@BASEBOARD_FAB2_LIB.BASEBOARD_FAB2(SCH_1):PAGE98',
 WATTAGE='1/16W',
 TOLERANCE='1%',
 SEC_TYPE='0402',
 MATERIAL='CHIP',
 BOM_COST='SM_CONTROLLER',
 PHYS_PAGE='98',
 XY='(225,2675)',
 ROT='2',
 VER='2',
 VALUE='1.00K',
 PACK_TYPE='0402',
 PART_NUMBER='G21796-026',
 LOCATION='R6L13',
 ROOM='MEM',
 SEC='1',
 CDS_LIB='mstr_discrete',
 CDS_PART_NAME='RES_0402-1.00K,1%,1/16W,CHIP,GA',
 PRIM_FILE='./archive_libs/mstr_discrete/res/chips/chips.prt';

PART_NAME
 R6L14 'RES_0402-2,1.0%,1/16W,CHIP,G21A':
 ROOM='PROC';

SECTION_NUMBER 1
 '@BASEBOARD_FAB2_LIB.BASEBOARD_FAB2(SCH_1):PAGE98_I58@MSTR_DISCRETE.RES(CHIPS)':
 C_PATH='@baseboard_fab2_lib.baseboard_fab2(sch_1):page98_i58@mstr_discrete.res(~
chips)',
 P_PATH='@baseboard_fab2_lib.baseboard_fab2(sch_1):page98_i58@mstr_discrete.res(~
chips)',
 PATH='I58',
 DRAWING='@BASEBOARD_FAB2_LIB.BASEBOARD_FAB2(SCH_1):PAGE98',
 WATTAGE='1/16W',
 TOLERANCE='1.0%',
 SEC_TYPE='0402',
 MATERIAL='CHIP',
 BOM_COST='PROC_SOCKET',
 PHYS_PAGE='98',
 XY='(0,2350)',
 ROT='0',
 VER='1',
 VALUE='2',
 PACK_TYPE='0402',
 PART_NUMBER='G21796-274',
 LOCATION='R6L14',
 ROOM='PROC',
 SEC='1',
 CDS_LIB='mstr_discrete',
 CDS_PART_NAME='RES_0402-2,1.0%,1/16W,CHIP,G21A',
 PRIM_FILE='./archive_libs/mstr_discrete/res/chips/chips.prt';

PART_NAME
 R6L16 'RES_0402-1.00K,1%,1/16W,CHIP,GA':
 ROOM='PROC';

SECTION_NUMBER 1
 '@BASEBOARD_FAB2_LIB.BASEBOARD_FAB2(SCH_1):PAGE98_I12@MSTR_DISCRETE.RES(CHIPS)':
 C_PATH='@baseboard_fab2_lib.baseboard_fab2(sch_1):page98_i12@mstr_discrete.res(~
chips)',
 P_PATH='@baseboard_fab2_lib.baseboard_fab2(sch_1):page98_i12@mstr_discrete.res(~
chips)',
 PATH='I12',
 DRAWING='@BASEBOARD_FAB2_LIB.BASEBOARD_FAB2(SCH_1):PAGE98',
 WATTAGE='1/16W',
 TOLERANCE='1%',
 SEC_TYPE='0402',
 MATERIAL='CHIP',
 BOM_COST='PROC_SOCKET',
 PHYS_PAGE='98',
 XY='(-1725,2025)',
 ROT='2',
 VER='2',
 VALUE='1.00K',
 PACK_TYPE='0402',
 PART_NUMBER='G21796-026',
 LOCATION='R6L16',
 ROOM='PROC',
 SEC='1',
 CDS_LIB='mstr_discrete',
 CDS_PART_NAME='RES_0402-1.00K,1%,1/16W,CHIP,GA',
 PRIM_FILE='./archive_libs/mstr_discrete/res/chips/chips.prt';

PART_NAME
 R6M1 'RES_0402-1.00K,1%,1/16W,CHIP,GA':
 ROOM='MEM';

SECTION_NUMBER 1
 '@BASEBOARD_FAB2_LIB.BASEBOARD_FAB2(SCH_1):PAGE98_I9@MSTR_DISCRETE.RES(CHIPS)':
 C_PATH='@baseboard_fab2_lib.baseboard_fab2(sch_1):page98_i9@mstr_discrete.res(c~
hips)',
 P_PATH='@baseboard_fab2_lib.baseboard_fab2(sch_1):page98_i9@mstr_discrete.res(c~
hips)',
 PATH='I9',
 DRAWING='@BASEBOARD_FAB2_LIB.BASEBOARD_FAB2(SCH_1):PAGE98',
 WATTAGE='1/16W',
 TOLERANCE='1%',
 SEC_TYPE='0402',
 MATERIAL='CHIP',
 BOM_COST='PROC_SOCKET',
 PHYS_PAGE='98',
 XY='(-1800,2675)',
 ROT='2',
 VER='2',
 VALUE='1.00K',
 PACK_TYPE='0402',
 PART_NUMBER='G21796-026',
 LOCATION='R6M1',
 ROOM='MEM',
 SEC='1',
 CDS_LIB='mstr_discrete',
 CDS_PART_NAME='RES_0402-1.00K,1%,1/16W,CHIP,GA',
 PRIM_FILE='./archive_libs/mstr_discrete/res/chips/chips.prt';

PART_NAME
 R6M2 'RES_0402-2,1.0%,1/16W,CHIP,G21A':
 ROOM='PROC';

SECTION_NUMBER 1
 '@BASEBOARD_FAB2_LIB.BASEBOARD_FAB2(SCH_1):PAGE98_I14@MSTR_DISCRETE.RES(CHIPS)':
 C_PATH='@baseboard_fab2_lib.baseboard_fab2(sch_1):page98_i14@mstr_discrete.res(~
chips)',
 P_PATH='@baseboard_fab2_lib.baseboard_fab2(sch_1):page98_i14@mstr_discrete.res(~
chips)',
 PATH='I14',
 DRAWING='@BASEBOARD_FAB2_LIB.BASEBOARD_FAB2(SCH_1):PAGE98',
 WATTAGE='1/16W',
 TOLERANCE='1.0%',
 SEC_TYPE='0402',
 MATERIAL='CHIP',
 BOM_COST='PROC_SOCKET',
 PHYS_PAGE='98',
 XY='(-2025,2350)',
 ROT='0',
 VER='1',
 VALUE='2',
 PACK_TYPE='0402',
 PART_NUMBER='G21796-274',
 LOCATION='R6M2',
 ROOM='PROC',
 SEC='1',
 CDS_LIB='mstr_discrete',
 CDS_PART_NAME='RES_0402-2,1.0%,1/16W,CHIP,G21A',
 PRIM_FILE='./archive_libs/mstr_discrete/res/chips/chips.prt';

PART_NAME
 R6M4 'RES_0402-4.75K,1%,1/16W,CHIP,GA':
 ROOM='PROC_SIDEBAND';

SECTION_NUMBER 1
 '@BASEBOARD_FAB2_LIB.BASEBOARD_FAB2(SCH_1):PAGE94_I82@MSTR_DISCRETE.RES(CHIPS)':
 C_PATH='@baseboard_fab2_lib.baseboard_fab2(sch_1):page94_i82@mstr_discrete.res(~
chips)',
 P_PATH='@baseboard_fab2_lib.baseboard_fab2(sch_1):page94_i82@mstr_discrete.res(~
chips)',
 PATH='I82',
 DRAWING='@BASEBOARD_FAB2_LIB.BASEBOARD_FAB2(SCH_1):PAGE94',
 WATTAGE='1/16W',
 TOLERANCE='1%',
 MATERIAL='CHIP',
 BOM_COST='PROC_SIDEBAND',
 PHYS_PAGE='94',
 XY='(1175,1325)',
 ROT='2',
 VER='2',
 VALUE='4.75K',
 PACK_TYPE='0402',
 PART_NUMBER='G21796-072',
 LOCATION='R6M4',
 ROOM='PROC_SIDEBAND',
 CDS_LIB='mstr_discrete',
 CDS_PART_NAME='RES_0402-4.75K,1%,1/16W,CHIP,GA',
 PRIM_FILE='./archive_libs/mstr_discrete/res/chips/chips.prt';

PART_NAME
 R6M8 'RES_0402-1.00K,1%,1/16W,CHIP,GA':
 GROUP='MCP',
 ROOM='PROC_SIDEBAND';

SECTION_NUMBER 1
 '@BASEBOARD_FAB2_LIB.BASEBOARD_FAB2(SCH_1):PAGE113_I271@MSTR_DISCRETE.RES(CHIPS)':
 C_PATH='@baseboard_fab2_lib.baseboard_fab2(sch_1):page113_i271@mstr_discrete.re~
s(chips)',
 P_PATH='@baseboard_fab2_lib.baseboard_fab2(sch_1):page113_i271@mstr_discrete.re~
s(chips)',
 PATH='I271',
 DRAWING='@BASEBOARD_FAB2_LIB.BASEBOARD_FAB2(SCH_1):PAGE113',
 WATTAGE='1/16W',
 TOLERANCE='1%',
 SEC_TYPE='0402',
 MATERIAL='CHIP',
 PHYS_PAGE='113',
 XY='(2450,1825)',
 ROT='0',
 VER='2',
 VALUE='1.00K',
 PACK_TYPE='0402',
 PART_NUMBER='G21796-026',
 LOCATION='R6M8',
 ROOM='PROC_SIDEBAND',
 GROUP='MCP',
 SEC='1',
 CDS_LIB='mstr_discrete',
 CDS_PART_NAME='RES_0402-1.00K,1%,1/16W,CHIP,GA',
 PRIM_FILE='./archive_libs/mstr_discrete/res/chips/chips.prt';

PART_NAME
 R6M9 'RES_0402-4.75K,1%,1/16W,CHIP,GA':
 ROOM='CPLD';

SECTION_NUMBER 1
 '@BASEBOARD_FAB2_LIB.BASEBOARD_FAB2(SCH_1):PAGE192_I49@MSTR_DISCRETE.RES(CHIPS)':
 C_PATH='@baseboard_fab2_lib.baseboard_fab2(sch_1):page192_i49@mstr_discrete.res~
(chips)',
 P_PATH='@baseboard_fab2_lib.baseboard_fab2(sch_1):page192_i49@mstr_discrete.res~
(chips)',
 PATH='I49',
 DRAWING='@BASEBOARD_FAB2_LIB.BASEBOARD_FAB2(SCH_1):PAGE192',
 WATTAGE='1/16W',
 TOLERANCE='1%',
 SEC_TYPE='0402',
 MATERIAL='CHIP',
 BOM_COST='CPLD',
 PHYS_PAGE='192',
 XY='(-5750,2800)',
 ROT='0',
 VER='2',
 VALUE='4.75K',
 PACK_TYPE='0402',
 PART_NUMBER='G21796-072',
 LOCATION='R6M9',
 ROOM='CPLD',
 SEC='1',
 CDS_LIB='mstr_discrete',
 CDS_PART_NAME='RES_0402-4.75K,1%,1/16W,CHIP,GA',
 PRIM_FILE='./archive_libs/mstr_discrete/res/chips/chips.prt';

PART_NAME
 R6N1 'RES_0402-49.9,1%,1/16W,CHIP,G2A':
 ROOM='CPU0';

SECTION_NUMBER 1
 '@BASEBOARD_FAB2_LIB.BASEBOARD_FAB2(SCH_1):PAGE21_I164@MSTR_DISCRETE.RES(CHIPS)':
 C_PATH='@baseboard_fab2_lib.baseboard_fab2(sch_1):page21_i164@mstr_discrete.res~
(chips)',
 P_PATH='@baseboard_fab2_lib.baseboard_fab2(sch_1):page21_i164@mstr_discrete.res~
(chips)',
 PATH='I164',
 DRAWING='@BASEBOARD_FAB2_LIB.BASEBOARD_FAB2(SCH_1):PAGE21',
 WATTAGE='1/16W',
 TOLERANCE='1%',
 SEC_TYPE='0402',
 MATERIAL='CHIP',
 BOM_COST='PROC_SIDEBAND',
 PHYS_PAGE='21',
 XY='(-750,3500)',
 ROT='0',
 VER='2',
 VALUE='49.9',
 PACK_TYPE='0402',
 PART_NUMBER='G21796-047',
 LOCATION='R6N1',
 ROOM='CPU0',
 SEC='1',
 CDS_LIB='mstr_discrete',
 CDS_PART_NAME='RES_0402-49.9,1%,1/16W,CHIP,G2A',
 PRIM_FILE='./archive_libs/mstr_discrete/res/chips/chips.prt';

PART_NAME
 R6N2 'RES_0402-100.0,1%,1/16W,CHIP,GA':
 ROOM='CPU0';

SECTION_NUMBER 1
 '@BASEBOARD_FAB2_LIB.BASEBOARD_FAB2(SCH_1):PAGE21_I163@MSTR_DISCRETE.RES(CHIPS)':
 C_PATH='@baseboard_fab2_lib.baseboard_fab2(sch_1):page21_i163@mstr_discrete.res~
(chips)',
 P_PATH='@baseboard_fab2_lib.baseboard_fab2(sch_1):page21_i163@mstr_discrete.res~
(chips)',
 PATH='I163',
 DRAWING='@BASEBOARD_FAB2_LIB.BASEBOARD_FAB2(SCH_1):PAGE21',
 WATTAGE='1/16W',
 TOLERANCE='1%',
 SEC_TYPE='0402',
 MATERIAL='CHIP',
 BOM_COST='PROC_SIDEBAND',
 PHYS_PAGE='21',
 XY='(-1000,3500)',
 ROT='0',
 VER='2',
 VALUE='100.0',
 PACK_TYPE='0402',
 PART_NUMBER='G21796-017',
 LOCATION='R6N2',
 ROOM='CPU0',
 SEC='1',
 CDS_LIB='mstr_discrete',
 CDS_PART_NAME='RES_0402-100.0,1%,1/16W,CHIP,GA',
 PRIM_FILE='./archive_libs/mstr_discrete/res/chips/chips.prt';

PART_NAME
 R6N3 'RES_0402-0.0,5%,1/16W,CHIP,G21A':
 ROOM='CPU0';

SECTION_NUMBER 1
 '@BASEBOARD_FAB2_LIB.BASEBOARD_FAB2(SCH_1):PAGE205_I81@MSTR_DISCRETE.RES(CHIPS)':
 C_PATH='@baseboard_fab2_lib.baseboard_fab2(sch_1):page205_i81@mstr_discrete.res~
(chips)',
 P_PATH='@baseboard_fab2_lib.baseboard_fab2(sch_1):page205_i81@mstr_discrete.res~
(chips)',
 PATH='I81',
 DRAWING='@BASEBOARD_FAB2_LIB.BASEBOARD_FAB2(SCH_1):PAGE205',
 WATTAGE='1/16W',
 TOLERANCE='5%',
 SEC_TYPE='0402',
 MATERIAL='CHIP',
 BOM_COST='PROC_SIDEBAND',
 PHYS_PAGE='205',
 XY='(-5850,4725)',
 ROT='0',
 VER='1',
 VALUE='0.0',
 PACK_TYPE='0402',
 PART_NUMBER='G21497-005',
 LOCATION='R6N3',
 ROOM='CPU0',
 SEC='1',
 CDS_LIB='mstr_discrete',
 CDS_PART_NAME='RES_0402-0.0,5%,1/16W,CHIP,G21A',
 PRIM_FILE='./archive_libs/mstr_discrete/res/chips/chips.prt';

PART_NAME
 R6N4 'RES_0402-51.1,1.0%,1/16W,CHIP,A':;

SECTION_NUMBER 1
 '@BASEBOARD_FAB2_LIB.BASEBOARD_FAB2(SCH_1):PAGE205_I45@MSTR_DISCRETE.RES(CHIPS)':
 C_PATH='@baseboard_fab2_lib.baseboard_fab2(sch_1):page205_i45@mstr_discrete.res~
(chips)',
 P_PATH='@baseboard_fab2_lib.baseboard_fab2(sch_1):page205_i45@mstr_discrete.res~
(chips)',
 PATH='I45',
 DRAWING='@BASEBOARD_FAB2_LIB.BASEBOARD_FAB2(SCH_1):PAGE205',
 WATTAGE='1/16W',
 TOLERANCE='1.0%',
 SEC_TYPE='0402',
 MATERIAL='CHIP',
 PHYS_PAGE='205',
 XY='(-275,3075)',
 ROT='0',
 VER='2',
 VALUE='51.1',
 PACK_TYPE='0402',
 PART_NUMBER='G21796-208',
 LOCATION='R6N4',
 SEC='1',
 CDS_LIB='mstr_discrete',
 CDS_PART_NAME='RES_0402-51.1,1.0%,1/16W,CHIP,A',
 PRIM_FILE='./archive_libs/mstr_discrete/res/chips/chips.prt';

PART_NAME
 R6N8 'RES_0402-10.0,1%,1/16W,CHIP,G2A':
 ROOM='CPU1';

SECTION_NUMBER 1
 '@BASEBOARD_FAB2_LIB.BASEBOARD_FAB2(SCH_1):PAGE163_I2@MSTR_DISCRETE.RES(CHIPS)':
 C_PATH='@baseboard_fab2_lib.baseboard_fab2(sch_1):page163_i2@mstr_discrete.res(~
chips)',
 P_PATH='@baseboard_fab2_lib.baseboard_fab2(sch_1):page163_i2@mstr_discrete.res(~
chips)',
 PATH='I2',
 DRAWING='@BASEBOARD_FAB2_LIB.BASEBOARD_FAB2(SCH_1):PAGE163',
 WATTAGE='1/16W',
 TOLERANCE='1%',
 SEC_TYPE='0402',
 MATERIAL='CHIP',
 PHYS_PAGE='163',
 XY='(-3800,3300)',
 ROT='0',
 VER='1',
 VALUE='10.0',
 PACK_TYPE='0402',
 PART_NUMBER='G21796-066',
 LOCATION='R6N8',
 ROOM='CPU1',
 SEC='1',
 CDS_LIB='mstr_discrete',
 CDS_PART_NAME='RES_0402-10.0,1%,1/16W,CHIP,G2A',
 PRIM_FILE='./archive_libs/mstr_discrete/res/chips/chips.prt';

PART_NAME
 R6N9 'RES_0402-10.0,1%,1/16W,CHIP,G2A':
 ROOM='CPU1';

SECTION_NUMBER 1
 '@BASEBOARD_FAB2_LIB.BASEBOARD_FAB2(SCH_1):PAGE163_I3@MSTR_DISCRETE.RES(CHIPS)':
 C_PATH='@baseboard_fab2_lib.baseboard_fab2(sch_1):page163_i3@mstr_discrete.res(~
chips)',
 P_PATH='@baseboard_fab2_lib.baseboard_fab2(sch_1):page163_i3@mstr_discrete.res(~
chips)',
 PATH='I3',
 DRAWING='@BASEBOARD_FAB2_LIB.BASEBOARD_FAB2(SCH_1):PAGE163',
 WATTAGE='1/16W',
 TOLERANCE='1%',
 SEC_TYPE='0402',
 MATERIAL='CHIP',
 PHYS_PAGE='163',
 XY='(-3275,3250)',
 ROT='0',
 VER='1',
 VALUE='10.0',
 PACK_TYPE='0402',
 PART_NUMBER='G21796-066',
 LOCATION='R6N9',
 ROOM='CPU1',
 SEC='1',
 CDS_LIB='mstr_discrete',
 CDS_PART_NAME='RES_0402-10.0,1%,1/16W,CHIP,G2A',
 PRIM_FILE='./archive_libs/mstr_discrete/res/chips/chips.prt';

PART_NAME
 R6N10 'RES_0402-221,1.0%,1/16W,CHIP,GA':
 ROOM='CPU0';

SECTION_NUMBER 1
 '@BASEBOARD_FAB2_LIB.BASEBOARD_FAB2(SCH_1):PAGE21_I149@MSTR_DISCRETE.RES(CHIPS)':
 C_PATH='@baseboard_fab2_lib.baseboard_fab2(sch_1):page21_i149@mstr_discrete.res~
(chips)',
 P_PATH='@baseboard_fab2_lib.baseboard_fab2(sch_1):page21_i149@mstr_discrete.res~
(chips)',
 PATH='I149',
 DRAWING='@BASEBOARD_FAB2_LIB.BASEBOARD_FAB2(SCH_1):PAGE21',
 WATTAGE='1/16W',
 TOLERANCE='1.0%',
 SEC_TYPE='0402',
 MATERIAL='CHIP',
 BOM_COST='PROC_SIDEBAND',
 PHYS_PAGE='21',
 XY='(-2000,3750)',
 ROT='0',
 VER='1',
 VALUE='221',
 PACK_TYPE='0402',
 PART_NUMBER='G21796-271',
 LOCATION='R6N10',
 ROOM='CPU0',
 SEC='1',
 CDS_LIB='mstr_discrete',
 CDS_PART_NAME='RES_0402-221,1.0%,1/16W,CHIP,GA',
 PRIM_FILE='./archive_libs/mstr_discrete/res/chips/chips.prt';

PART_NAME
 R6N11 'RES_0402-0.0,5%,1/16W,CHIP,G21A':
 ROOM='CPU0';

SECTION_NUMBER 1
 '@BASEBOARD_FAB2_LIB.BASEBOARD_FAB2(SCH_1):PAGE21_I151@MSTR_DISCRETE.RES(CHIPS)':
 C_PATH='@baseboard_fab2_lib.baseboard_fab2(sch_1):page21_i151@mstr_discrete.res~
(chips)',
 P_PATH='@baseboard_fab2_lib.baseboard_fab2(sch_1):page21_i151@mstr_discrete.res~
(chips)',
 PATH='I151',
 DRAWING='@BASEBOARD_FAB2_LIB.BASEBOARD_FAB2(SCH_1):PAGE21',
 WATTAGE='1/16W',
 TOLERANCE='5%',
 SEC_TYPE='0402',
 MATERIAL='CHIP',
 BOM_COST='PROC_SIDEBAND',
 PHYS_PAGE='21',
 XY='(-2000,3850)',
 ROT='0',
 VER='1',
 VALUE='0.0',
 PACK_TYPE='0402',
 PART_NUMBER='G21497-005',
 LOCATION='R6N11',
 ROOM='CPU0',
 SEC='1',
 CDS_LIB='mstr_discrete',
 CDS_PART_NAME='RES_0402-0.0,5%,1/16W,CHIP,G21A',
 PRIM_FILE='./archive_libs/mstr_discrete/res/chips/chips.prt';

PART_NAME
 R6N12 'RES_0402-0.0,5%,1/16W,CHIP,G21A':
 ROOM='CPU0';

SECTION_NUMBER 1
 '@BASEBOARD_FAB2_LIB.BASEBOARD_FAB2(SCH_1):PAGE21_I150@MSTR_DISCRETE.RES(CHIPS)':
 C_PATH='@baseboard_fab2_lib.baseboard_fab2(sch_1):page21_i150@mstr_discrete.res~
(chips)',
 P_PATH='@baseboard_fab2_lib.baseboard_fab2(sch_1):page21_i150@mstr_discrete.res~
(chips)',
 PATH='I150',
 DRAWING='@BASEBOARD_FAB2_LIB.BASEBOARD_FAB2(SCH_1):PAGE21',
 WATTAGE='1/16W',
 TOLERANCE='5%',
 SEC_TYPE='0402',
 MATERIAL='CHIP',
 BOM_COST='PROC_SIDEBAND',
 PHYS_PAGE='21',
 XY='(-2000,3800)',
 ROT='0',
 VER='1',
 VALUE='0.0',
 PACK_TYPE='0402',
 PART_NUMBER='G21497-005',
 LOCATION='R6N12',
 ROOM='CPU0',
 SEC='1',
 CDS_LIB='mstr_discrete',
 CDS_PART_NAME='RES_0402-0.0,5%,1/16W,CHIP,G21A',
 PRIM_FILE='./archive_libs/mstr_discrete/res/chips/chips.prt';

PART_NAME
 R6N13 'RES_0402-1.00K,1%,1/16W,CHIP,GA':
 ROOM='CPU0';

SECTION_NUMBER 1
 '@BASEBOARD_FAB2_LIB.BASEBOARD_FAB2(SCH_1):PAGE156_I303@MSTR_DISCRETE.RES(CHIPS)':
 C_PATH='@baseboard_fab2_lib.baseboard_fab2(sch_1):page156_i303@mstr_discrete.re~
s(chips)',
 P_PATH='@baseboard_fab2_lib.baseboard_fab2(sch_1):page156_i303@mstr_discrete.re~
s(chips)',
 PATH='I303',
 DRAWING='@BASEBOARD_FAB2_LIB.BASEBOARD_FAB2(SCH_1):PAGE156',
 WATTAGE='1/16W',
 TOLERANCE='1%',
 SEC_TYPE='0402',
 MATERIAL='CHIP',
 PHYS_PAGE='156',
 XY='(-4000,775)',
 ROT='0',
 VER='1',
 VALUE='1.00K',
 PACK_TYPE='0402',
 PART_NUMBER='G21796-026',
 LOCATION='R6N13',
 ROOM='CPU0',
 SEC='1',
 CDS_LIB='mstr_discrete',
 CDS_PART_NAME='RES_0402-1.00K,1%,1/16W,CHIP,GA',
 PRIM_FILE='./archive_libs/mstr_discrete/res/chips/chips.prt';

PART_NAME
 R6N14 'RES_0402-1.00K,1%,1/16W,CHIP,GA':
 ROOM='CPU0';

SECTION_NUMBER 1
 '@BASEBOARD_FAB2_LIB.BASEBOARD_FAB2(SCH_1):PAGE156_I302@MSTR_DISCRETE.RES(CHIPS)':
 C_PATH='@baseboard_fab2_lib.baseboard_fab2(sch_1):page156_i302@mstr_discrete.re~
s(chips)',
 P_PATH='@baseboard_fab2_lib.baseboard_fab2(sch_1):page156_i302@mstr_discrete.re~
s(chips)',
 PATH='I302',
 DRAWING='@BASEBOARD_FAB2_LIB.BASEBOARD_FAB2(SCH_1):PAGE156',
 WATTAGE='1/16W',
 TOLERANCE='1%',
 SEC_TYPE='0402',
 MATERIAL='CHIP',
 PHYS_PAGE='156',
 XY='(-4000,975)',
 ROT='0',
 VER='1',
 VALUE='1.00K',
 PACK_TYPE='0402',
 PART_NUMBER='G21796-026',
 LOCATION='R6N14',
 ROOM='CPU0',
 SEC='1',
 CDS_LIB='mstr_discrete',
 CDS_PART_NAME='RES_0402-1.00K,1%,1/16W,CHIP,GA',
 PRIM_FILE='./archive_libs/mstr_discrete/res/chips/chips.prt';

PART_NAME
 R6N15 'RES_0402-1.00K,1%,1/16W,CHIP,GA':
 ROOM='CPU0';

SECTION_NUMBER 1
 '@BASEBOARD_FAB2_LIB.BASEBOARD_FAB2(SCH_1):PAGE156_I304@MSTR_DISCRETE.RES(CHIPS)':
 C_PATH='@baseboard_fab2_lib.baseboard_fab2(sch_1):page156_i304@mstr_discrete.re~
s(chips)',
 P_PATH='@baseboard_fab2_lib.baseboard_fab2(sch_1):page156_i304@mstr_discrete.re~
s(chips)',
 PATH='I304',
 DRAWING='@BASEBOARD_FAB2_LIB.BASEBOARD_FAB2(SCH_1):PAGE156',
 WATTAGE='1/16W',
 TOLERANCE='1%',
 SEC_TYPE='0402',
 MATERIAL='CHIP',
 PHYS_PAGE='156',
 XY='(-4000,575)',
 ROT='0',
 VER='1',
 VALUE='1.00K',
 PACK_TYPE='0402',
 PART_NUMBER='G21796-026',
 LOCATION='R6N15',
 ROOM='CPU0',
 SEC='1',
 CDS_LIB='mstr_discrete',
 CDS_PART_NAME='RES_0402-1.00K,1%,1/16W,CHIP,GA',
 PRIM_FILE='./archive_libs/mstr_discrete/res/chips/chips.prt';

PART_NAME
 R6P1 'RES_0402-42.2,1.0%,1/16W,EMPTYA':
 ROOM='DB1200Z';

SECTION_NUMBER 1
 '@BASEBOARD_FAB2_LIB.BASEBOARD_FAB2(SCH_1):PAGE103_I149@MSTR_DISCRETE.RES(CHIPS)':
 C_PATH='@baseboard_fab2_lib.baseboard_fab2(sch_1):page103_i149@mstr_discrete.re~
s(chips)',
 P_PATH='@baseboard_fab2_lib.baseboard_fab2(sch_1):page103_i149@mstr_discrete.re~
s(chips)',
 PATH='I149',
 DRAWING='@BASEBOARD_FAB2_LIB.BASEBOARD_FAB2(SCH_1):PAGE103',
 WATTAGE='1/16W',
 TOLERANCE='1.0%',
 SEC_TYPE='0402',
 MATERIAL='EMPTY',
 BOM_COST='SYS_CLOCK',
 PHYS_PAGE='103',
 XY='(1025,4075)',
 ROT='0',
 VER='1',
 VALUE='42.2',
 PACK_TYPE='0402',
 PART_NUMBER='G21796-259',
 LOCATION='R6P1',
 ROOM='DB1200Z',
 SEC='1',
 CDS_LIB='mstr_discrete',
 CDS_PART_NAME='RES_0402-42.2,1.0%,1/16W,EMPTYA',
 PRIM_FILE='./archive_libs/mstr_discrete/res/chips/chips.prt';

PART_NAME
 R6P2 'RES_0402-42.2,1.0%,1/16W,EMPTYA':
 ROOM='DB1200Z';

SECTION_NUMBER 1
 '@BASEBOARD_FAB2_LIB.BASEBOARD_FAB2(SCH_1):PAGE103_I151@MSTR_DISCRETE.RES(CHIPS)':
 C_PATH='@baseboard_fab2_lib.baseboard_fab2(sch_1):page103_i151@mstr_discrete.re~
s(chips)',
 P_PATH='@baseboard_fab2_lib.baseboard_fab2(sch_1):page103_i151@mstr_discrete.re~
s(chips)',
 PATH='I151',
 DRAWING='@BASEBOARD_FAB2_LIB.BASEBOARD_FAB2(SCH_1):PAGE103',
 WATTAGE='1/16W',
 TOLERANCE='1.0%',
 SEC_TYPE='0402',
 MATERIAL='EMPTY',
 BOM_COST='SYS_CLOCK',
 PHYS_PAGE='103',
 XY='(1050,3750)',
 ROT='0',
 VER='1',
 VALUE='42.2',
 PACK_TYPE='0402',
 PART_NUMBER='G21796-259',
 LOCATION='R6P2',
 ROOM='DB1200Z',
 SEC='1',
 CDS_LIB='mstr_discrete',
 CDS_PART_NAME='RES_0402-42.2,1.0%,1/16W,EMPTYA',
 PRIM_FILE='./archive_libs/mstr_discrete/res/chips/chips.prt';

PART_NAME
 R6P3 'RES_0402-42.2,1.0%,1/16W,EMPTYA':
 ROOM='DB1200Z';

SECTION_NUMBER 1
 '@BASEBOARD_FAB2_LIB.BASEBOARD_FAB2(SCH_1):PAGE103_I145@MSTR_DISCRETE.RES(CHIPS)':
 C_PATH='@baseboard_fab2_lib.baseboard_fab2(sch_1):page103_i145@mstr_discrete.re~
s(chips)',
 P_PATH='@baseboard_fab2_lib.baseboard_fab2(sch_1):page103_i145@mstr_discrete.re~
s(chips)',
 PATH='I145',
 DRAWING='@BASEBOARD_FAB2_LIB.BASEBOARD_FAB2(SCH_1):PAGE103',
 WATTAGE='1/16W',
 TOLERANCE='1.0%',
 SEC_TYPE='0402',
 MATERIAL='EMPTY',
 BOM_COST='SYS_CLOCK',
 PHYS_PAGE='103',
 XY='(1025,4725)',
 ROT='0',
 VER='1',
 VALUE='42.2',
 PACK_TYPE='0402',
 PART_NUMBER='G21796-259',
 LOCATION='R6P3',
 ROOM='DB1200Z',
 SEC='1',
 CDS_LIB='mstr_discrete',
 CDS_PART_NAME='RES_0402-42.2,1.0%,1/16W,EMPTYA',
 PRIM_FILE='./archive_libs/mstr_discrete/res/chips/chips.prt';

PART_NAME
 R6P4 'RES_0402-42.2,1.0%,1/16W,EMPTYA':
 ROOM='DB1200Z';

SECTION_NUMBER 1
 '@BASEBOARD_FAB2_LIB.BASEBOARD_FAB2(SCH_1):PAGE103_I147@MSTR_DISCRETE.RES(CHIPS)':
 C_PATH='@baseboard_fab2_lib.baseboard_fab2(sch_1):page103_i147@mstr_discrete.re~
s(chips)',
 P_PATH='@baseboard_fab2_lib.baseboard_fab2(sch_1):page103_i147@mstr_discrete.re~
s(chips)',
 PATH='I147',
 DRAWING='@BASEBOARD_FAB2_LIB.BASEBOARD_FAB2(SCH_1):PAGE103',
 WATTAGE='1/16W',
 TOLERANCE='1.0%',
 SEC_TYPE='0402',
 MATERIAL='EMPTY',
 BOM_COST='SYS_CLOCK',
 PHYS_PAGE='103',
 XY='(1050,4400)',
 ROT='0',
 VER='1',
 VALUE='42.2',
 PACK_TYPE='0402',
 PART_NUMBER='G21796-259',
 LOCATION='R6P4',
 ROOM='DB1200Z',
 SEC='1',
 CDS_LIB='mstr_discrete',
 CDS_PART_NAME='RES_0402-42.2,1.0%,1/16W,EMPTYA',
 PRIM_FILE='./archive_libs/mstr_discrete/res/chips/chips.prt';

PART_NAME
 R6P5 'RES_0402-42.2,1.0%,1/16W,EMPTYA':
 ROOM='DB1200Z';

SECTION_NUMBER 1
 '@BASEBOARD_FAB2_LIB.BASEBOARD_FAB2(SCH_1):PAGE103_I141@MSTR_DISCRETE.RES(CHIPS)':
 C_PATH='@baseboard_fab2_lib.baseboard_fab2(sch_1):page103_i141@mstr_discrete.re~
s(chips)',
 P_PATH='@baseboard_fab2_lib.baseboard_fab2(sch_1):page103_i141@mstr_discrete.re~
s(chips)',
 PATH='I141',
 DRAWING='@BASEBOARD_FAB2_LIB.BASEBOARD_FAB2(SCH_1):PAGE103',
 WATTAGE='1/16W',
 TOLERANCE='1.0%',
 SEC_TYPE='0402',
 MATERIAL='EMPTY',
 BOM_COST='SYS_CLOCK',
 PHYS_PAGE='103',
 XY='(-3325,1475)',
 ROT='0',
 VER='1',
 VALUE='42.2',
 PACK_TYPE='0402',
 PART_NUMBER='G21796-259',
 LOCATION='R6P5',
 ROOM='DB1200Z',
 SEC='1',
 CDS_LIB='mstr_discrete',
 CDS_PART_NAME='RES_0402-42.2,1.0%,1/16W,EMPTYA',
 PRIM_FILE='./archive_libs/mstr_discrete/res/chips/chips.prt';

PART_NAME
 R6P6 'RES_0402-42.2,1.0%,1/16W,EMPTYA':
 ROOM='DB1200Z';

SECTION_NUMBER 1
 '@BASEBOARD_FAB2_LIB.BASEBOARD_FAB2(SCH_1):PAGE103_I143@MSTR_DISCRETE.RES(CHIPS)':
 C_PATH='@baseboard_fab2_lib.baseboard_fab2(sch_1):page103_i143@mstr_discrete.re~
s(chips)',
 P_PATH='@baseboard_fab2_lib.baseboard_fab2(sch_1):page103_i143@mstr_discrete.re~
s(chips)',
 PATH='I143',
 DRAWING='@BASEBOARD_FAB2_LIB.BASEBOARD_FAB2(SCH_1):PAGE103',
 WATTAGE='1/16W',
 TOLERANCE='1.0%',
 SEC_TYPE='0402',
 MATERIAL='EMPTY',
 BOM_COST='SYS_CLOCK',
 PHYS_PAGE='103',
 XY='(-3325,1150)',
 ROT='0',
 VER='1',
 VALUE='42.2',
 PACK_TYPE='0402',
 PART_NUMBER='G21796-259',
 LOCATION='R6P6',
 ROOM='DB1200Z',
 SEC='1',
 CDS_LIB='mstr_discrete',
 CDS_PART_NAME='RES_0402-42.2,1.0%,1/16W,EMPTYA',
 PRIM_FILE='./archive_libs/mstr_discrete/res/chips/chips.prt';

PART_NAME
 R6P7 'RES_0402-42.2,1.0%,1/16W,EMPTYA':
 ROOM='DB1200Z';

SECTION_NUMBER 1
 '@BASEBOARD_FAB2_LIB.BASEBOARD_FAB2(SCH_1):PAGE103_I137@MSTR_DISCRETE.RES(CHIPS)':
 C_PATH='@baseboard_fab2_lib.baseboard_fab2(sch_1):page103_i137@mstr_discrete.re~
s(chips)',
 P_PATH='@baseboard_fab2_lib.baseboard_fab2(sch_1):page103_i137@mstr_discrete.re~
s(chips)',
 PATH='I137',
 DRAWING='@BASEBOARD_FAB2_LIB.BASEBOARD_FAB2(SCH_1):PAGE103',
 WATTAGE='1/16W',
 TOLERANCE='1.0%',
 SEC_TYPE='0402',
 MATERIAL='EMPTY',
 BOM_COST='SYS_CLOCK',
 PHYS_PAGE='103',
 XY='(-3325,2125)',
 ROT='0',
 VER='1',
 VALUE='42.2',
 PACK_TYPE='0402',
 PART_NUMBER='G21796-259',
 LOCATION='R6P7',
 ROOM='DB1200Z',
 SEC='1',
 CDS_LIB='mstr_discrete',
 CDS_PART_NAME='RES_0402-42.2,1.0%,1/16W,EMPTYA',
 PRIM_FILE='./archive_libs/mstr_discrete/res/chips/chips.prt';

PART_NAME
 R6P8 'RES_0402-42.2,1.0%,1/16W,EMPTYA':
 ROOM='DB1200Z';

SECTION_NUMBER 1
 '@BASEBOARD_FAB2_LIB.BASEBOARD_FAB2(SCH_1):PAGE103_I139@MSTR_DISCRETE.RES(CHIPS)':
 C_PATH='@baseboard_fab2_lib.baseboard_fab2(sch_1):page103_i139@mstr_discrete.re~
s(chips)',
 P_PATH='@baseboard_fab2_lib.baseboard_fab2(sch_1):page103_i139@mstr_discrete.re~
s(chips)',
 PATH='I139',
 DRAWING='@BASEBOARD_FAB2_LIB.BASEBOARD_FAB2(SCH_1):PAGE103',
 WATTAGE='1/16W',
 TOLERANCE='1.0%',
 SEC_TYPE='0402',
 MATERIAL='EMPTY',
 BOM_COST='SYS_CLOCK',
 PHYS_PAGE='103',
 XY='(-3325,1800)',
 ROT='0',
 VER='1',
 VALUE='42.2',
 PACK_TYPE='0402',
 PART_NUMBER='G21796-259',
 LOCATION='R6P8',
 ROOM='DB1200Z',
 SEC='1',
 CDS_LIB='mstr_discrete',
 CDS_PART_NAME='RES_0402-42.2,1.0%,1/16W,EMPTYA',
 PRIM_FILE='./archive_libs/mstr_discrete/res/chips/chips.prt';

PART_NAME
 R6P9 'RES_0402-42.2,1.0%,1/16W,EMPTYA':
 ROOM='DB1200Z';

SECTION_NUMBER 1
 '@BASEBOARD_FAB2_LIB.BASEBOARD_FAB2(SCH_1):PAGE103_I155@MSTR_DISCRETE.RES(CHIPS)':
 C_PATH='@baseboard_fab2_lib.baseboard_fab2(sch_1):page103_i155@mstr_discrete.re~
s(chips)',
 P_PATH='@baseboard_fab2_lib.baseboard_fab2(sch_1):page103_i155@mstr_discrete.re~
s(chips)',
 PATH='I155',
 DRAWING='@BASEBOARD_FAB2_LIB.BASEBOARD_FAB2(SCH_1):PAGE103',
 WATTAGE='1/16W',
 TOLERANCE='1.0%',
 SEC_TYPE='0402',
 MATERIAL='EMPTY',
 BOM_COST='SYS_CLOCK',
 PHYS_PAGE='103',
 XY='(1075,3100)',
 ROT='0',
 VER='1',
 VALUE='42.2',
 PACK_TYPE='0402',
 PART_NUMBER='G21796-259',
 LOCATION='R6P9',
 ROOM='DB1200Z',
 SEC='1',
 CDS_LIB='mstr_discrete',
 CDS_PART_NAME='RES_0402-42.2,1.0%,1/16W,EMPTYA',
 PRIM_FILE='./archive_libs/mstr_discrete/res/chips/chips.prt';

PART_NAME
 R6P10 'RES_0402-0.0,5%,1/16W,CHIP,G21A':
 ROOM='CPU0';

SECTION_NUMBER 1
 '@BASEBOARD_FAB2_LIB.BASEBOARD_FAB2(SCH_1):PAGE203_I129@MSTR_DISCRETE.RES(CHIPS)':
 C_PATH='@baseboard_fab2_lib.baseboard_fab2(sch_1):page203_i129@mstr_discrete.re~
s(chips)',
 P_PATH='@baseboard_fab2_lib.baseboard_fab2(sch_1):page203_i129@mstr_discrete.re~
s(chips)',
 PATH='I129',
 DRAWING='@BASEBOARD_FAB2_LIB.BASEBOARD_FAB2(SCH_1):PAGE203',
 WATTAGE='1/16W',
 TOLERANCE='5%',
 SEC_TYPE='0402',
 MATERIAL='CHIP',
 BOM_COST='PROC_SIDEBAND',
 PHYS_PAGE='203',
 XY='(-5425,2000)',
 ROT='0',
 VER='1',
 VALUE='0.0',
 PACK_TYPE='0402',
 PART_NUMBER='G21497-005',
 LOCATION='R6P10',
 ROOM='CPU0',
 SEC='1',
 CDS_LIB='mstr_discrete',
 CDS_PART_NAME='RES_0402-0.0,5%,1/16W,CHIP,G21A',
 PRIM_FILE='./archive_libs/mstr_discrete/res/chips/chips.prt';

PART_NAME
 R6P11 'RES_0402-42.2,1.0%,1/16W,EMPTYA':
 ROOM='DB1200Z';

SECTION_NUMBER 1
 '@BASEBOARD_FAB2_LIB.BASEBOARD_FAB2(SCH_1):PAGE103_I153@MSTR_DISCRETE.RES(CHIPS)':
 C_PATH='@baseboard_fab2_lib.baseboard_fab2(sch_1):page103_i153@mstr_discrete.re~
s(chips)',
 P_PATH='@baseboard_fab2_lib.baseboard_fab2(sch_1):page103_i153@mstr_discrete.re~
s(chips)',
 PATH='I153',
 DRAWING='@BASEBOARD_FAB2_LIB.BASEBOARD_FAB2(SCH_1):PAGE103',
 WATTAGE='1/16W',
 TOLERANCE='1.0%',
 SEC_TYPE='0402',
 MATERIAL='EMPTY',
 BOM_COST='SYS_CLOCK',
 PHYS_PAGE='103',
 XY='(1050,3425)',
 ROT='0',
 VER='1',
 VALUE='42.2',
 PACK_TYPE='0402',
 PART_NUMBER='G21796-259',
 LOCATION='R6P11',
 ROOM='DB1200Z',
 SEC='1',
 CDS_LIB='mstr_discrete',
 CDS_PART_NAME='RES_0402-42.2,1.0%,1/16W,EMPTYA',
 PRIM_FILE='./archive_libs/mstr_discrete/res/chips/chips.prt';

PART_NAME
 R6P12 'RES_0402-42.2,1.0%,1/16W,EMPTYA':
 ROOM='DB1200Z';

SECTION_NUMBER 1
 '@BASEBOARD_FAB2_LIB.BASEBOARD_FAB2(SCH_1):PAGE103_I159@MSTR_DISCRETE.RES(CHIPS)':
 C_PATH='@baseboard_fab2_lib.baseboard_fab2(sch_1):page103_i159@mstr_discrete.re~
s(chips)',
 P_PATH='@baseboard_fab2_lib.baseboard_fab2(sch_1):page103_i159@mstr_discrete.re~
s(chips)',
 PATH='I159',
 DRAWING='@BASEBOARD_FAB2_LIB.BASEBOARD_FAB2(SCH_1):PAGE103',
 WATTAGE='1/16W',
 TOLERANCE='1.0%',
 SEC_TYPE='0402',
 MATERIAL='EMPTY',
 BOM_COST='SYS_CLOCK',
 PHYS_PAGE='103',
 XY='(1050,2450)',
 ROT='0',
 VER='1',
 VALUE='42.2',
 PACK_TYPE='0402',
 PART_NUMBER='G21796-259',
 LOCATION='R6P12',
 ROOM='DB1200Z',
 SEC='1',
 CDS_LIB='mstr_discrete',
 CDS_PART_NAME='RES_0402-42.2,1.0%,1/16W,EMPTYA',
 PRIM_FILE='./archive_libs/mstr_discrete/res/chips/chips.prt';

PART_NAME
 R6P13 'RES_0402-42.2,1.0%,1/16W,EMPTYA':
 ROOM='DB1200Z';

SECTION_NUMBER 1
 '@BASEBOARD_FAB2_LIB.BASEBOARD_FAB2(SCH_1):PAGE103_I157@MSTR_DISCRETE.RES(CHIPS)':
 C_PATH='@baseboard_fab2_lib.baseboard_fab2(sch_1):page103_i157@mstr_discrete.re~
s(chips)',
 P_PATH='@baseboard_fab2_lib.baseboard_fab2(sch_1):page103_i157@mstr_discrete.re~
s(chips)',
 PATH='I157',
 DRAWING='@BASEBOARD_FAB2_LIB.BASEBOARD_FAB2(SCH_1):PAGE103',
 WATTAGE='1/16W',
 TOLERANCE='1.0%',
 SEC_TYPE='0402',
 MATERIAL='EMPTY',
 BOM_COST='SYS_CLOCK',
 PHYS_PAGE='103',
 XY='(1050,2775)',
 ROT='0',
 VER='1',
 VALUE='42.2',
 PACK_TYPE='0402',
 PART_NUMBER='G21796-259',
 LOCATION='R6P13',
 ROOM='DB1200Z',
 SEC='1',
 CDS_LIB='mstr_discrete',
 CDS_PART_NAME='RES_0402-42.2,1.0%,1/16W,EMPTYA',
 PRIM_FILE='./archive_libs/mstr_discrete/res/chips/chips.prt';

PART_NAME
 R6P15 'RES_0402-42.2,1.0%,1/16W,EMPTYA':
 ROOM='DB1200Z';

SECTION_NUMBER 1
 '@BASEBOARD_FAB2_LIB.BASEBOARD_FAB2(SCH_1):PAGE103_I167@MSTR_DISCRETE.RES(CHIPS)':
 C_PATH='@baseboard_fab2_lib.baseboard_fab2(sch_1):page103_i167@mstr_discrete.re~
s(chips)',
 P_PATH='@baseboard_fab2_lib.baseboard_fab2(sch_1):page103_i167@mstr_discrete.re~
s(chips)',
 PATH='I167',
 DRAWING='@BASEBOARD_FAB2_LIB.BASEBOARD_FAB2(SCH_1):PAGE103',
 WATTAGE='1/16W',
 TOLERANCE='1.0%',
 SEC_TYPE='0402',
 MATERIAL='EMPTY',
 BOM_COST='SYS_CLOCK',
 PHYS_PAGE='103',
 XY='(1050,1150)',
 ROT='0',
 VER='1',
 VALUE='42.2',
 PACK_TYPE='0402',
 PART_NUMBER='G21796-259',
 LOCATION='R6P15',
 ROOM='DB1200Z',
 SEC='1',
 CDS_LIB='mstr_discrete',
 CDS_PART_NAME='RES_0402-42.2,1.0%,1/16W,EMPTYA',
 PRIM_FILE='./archive_libs/mstr_discrete/res/chips/chips.prt';

PART_NAME
 R6P16 'RES_0402-1.00K,1%,1/16W,CHIP,GA':
 ROOM='BMC';

SECTION_NUMBER 1
 '@BASEBOARD_FAB2_LIB.BASEBOARD_FAB2(SCH_1):PAGE201_I132@MSTR_DISCRETE.RES(CHIPS)':
 C_PATH='@baseboard_fab2_lib.baseboard_fab2(sch_1):page201_i132@mstr_discrete.re~
s(chips)',
 P_PATH='@baseboard_fab2_lib.baseboard_fab2(sch_1):page201_i132@mstr_discrete.re~
s(chips)',
 PATH='I132',
 DRAWING='@BASEBOARD_FAB2_LIB.BASEBOARD_FAB2(SCH_1):PAGE201',
 WATTAGE='1/16W',
 TOLERANCE='1%',
 SEC_TYPE='0402',
 MATERIAL='CHIP',
 BOM_COST='SM_CONTROLLER',
 PHYS_PAGE='201',
 XY='(-4775,4350)',
 ROT='0',
 VER='2',
 VALUE='1.00K',
 PACK_TYPE='0402',
 PART_NUMBER='G21796-026',
 LOCATION='R6P16',
 ROOM='BMC',
 SEC='1',
 CDS_LIB='mstr_discrete',
 CDS_PART_NAME='RES_0402-1.00K,1%,1/16W,CHIP,GA',
 PRIM_FILE='./archive_libs/mstr_discrete/res/chips/chips.prt';

PART_NAME
 R6P17 'RES_0402-42.2,1.0%,1/16W,EMPTYA':
 ROOM='DB1200Z';

SECTION_NUMBER 1
 '@BASEBOARD_FAB2_LIB.BASEBOARD_FAB2(SCH_1):PAGE103_I165@MSTR_DISCRETE.RES(CHIPS)':
 C_PATH='@baseboard_fab2_lib.baseboard_fab2(sch_1):page103_i165@mstr_discrete.re~
s(chips)',
 P_PATH='@baseboard_fab2_lib.baseboard_fab2(sch_1):page103_i165@mstr_discrete.re~
s(chips)',
 PATH='I165',
 DRAWING='@BASEBOARD_FAB2_LIB.BASEBOARD_FAB2(SCH_1):PAGE103',
 WATTAGE='1/16W',
 TOLERANCE='1.0%',
 SEC_TYPE='0402',
 MATERIAL='EMPTY',
 BOM_COST='SYS_CLOCK',
 PHYS_PAGE='103',
 XY='(1050,1475)',
 ROT='0',
 VER='1',
 VALUE='42.2',
 PACK_TYPE='0402',
 PART_NUMBER='G21796-259',
 LOCATION='R6P17',
 ROOM='DB1200Z',
 SEC='1',
 CDS_LIB='mstr_discrete',
 CDS_PART_NAME='RES_0402-42.2,1.0%,1/16W,EMPTYA',
 PRIM_FILE='./archive_libs/mstr_discrete/res/chips/chips.prt';

PART_NAME
 R6P18 'RES_0402-0.0,5%,1/16W,CHIP,G21A':
 ROOM='PVCCIN_CPU0_VR';

SECTION_NUMBER 1
 '@BASEBOARD_FAB2_LIB.BASEBOARD_FAB2(SCH_1):PAGE201_I131@MSTR_DISCRETE.RES(CHIPS)':
 C_PATH='@baseboard_fab2_lib.baseboard_fab2(sch_1):page201_i131@mstr_discrete.re~
s(chips)',
 P_PATH='@baseboard_fab2_lib.baseboard_fab2(sch_1):page201_i131@mstr_discrete.re~
s(chips)',
 PATH='I131',
 DRAWING='@BASEBOARD_FAB2_LIB.BASEBOARD_FAB2(SCH_1):PAGE201',
 WATTAGE='1/16W',
 TOLERANCE='5%',
 SEC_TYPE='0402',
 MATERIAL='CHIP',
 PHYS_PAGE='201',
 XY='(-5100,2225)',
 ROT='0',
 VER='1',
 VALUE='0.0',
 PACK_TYPE='0402',
 PART_NUMBER='G21497-005',
 LOCATION='R6P18',
 ROOM='PVCCIN_CPU0_VR',
 SEC='1',
 CDS_LIB='mstr_discrete',
 CDS_PART_NAME='RES_0402-0.0,5%,1/16W,CHIP,G21A',
 PRIM_FILE='./archive_libs/mstr_discrete/res/chips/chips.prt';

PART_NAME
 R6P19 'RES_0402-0.0,5%,1/16W,CHIP,G21A':
 ROOM='CPU0';

SECTION_NUMBER 1
 '@BASEBOARD_FAB2_LIB.BASEBOARD_FAB2(SCH_1):PAGE203_I128@MSTR_DISCRETE.RES(CHIPS)':
 C_PATH='@baseboard_fab2_lib.baseboard_fab2(sch_1):page203_i128@mstr_discrete.re~
s(chips)',
 P_PATH='@baseboard_fab2_lib.baseboard_fab2(sch_1):page203_i128@mstr_discrete.re~
s(chips)',
 PATH='I128',
 DRAWING='@BASEBOARD_FAB2_LIB.BASEBOARD_FAB2(SCH_1):PAGE203',
 WATTAGE='1/16W',
 TOLERANCE='5%',
 SEC_TYPE='0402',
 MATERIAL='CHIP',
 BOM_COST='PROC_SIDEBAND',
 PHYS_PAGE='203',
 XY='(-5325,4750)',
 ROT='0',
 VER='1',
 VALUE='0.0',
 PACK_TYPE='0402',
 PART_NUMBER='G21497-005',
 LOCATION='R6P19',
 ROOM='CPU0',
 SEC='1',
 CDS_LIB='mstr_discrete',
 CDS_PART_NAME='RES_0402-0.0,5%,1/16W,CHIP,G21A',
 PRIM_FILE='./archive_libs/mstr_discrete/res/chips/chips.prt';

PART_NAME
 R6P20 'RES_0402-1.00K,1%,1/16W,CHIP,GA':
 ROOM='DB1200ZL';

SECTION_NUMBER 1
 '@BASEBOARD_FAB2_LIB.BASEBOARD_FAB2(SCH_1):PAGE102_I81@MSTR_DISCRETE.RES(CHIPS)':
 C_PATH='@baseboard_fab2_lib.baseboard_fab2(sch_1):page102_i81@mstr_discrete.res~
(chips)',
 P_PATH='@baseboard_fab2_lib.baseboard_fab2(sch_1):page102_i81@mstr_discrete.res~
(chips)',
 PATH='I81',
 DRAWING='@BASEBOARD_FAB2_LIB.BASEBOARD_FAB2(SCH_1):PAGE102',
 WATTAGE='1/16W',
 TOLERANCE='1%',
 SEC_TYPE='0402',
 MATERIAL='CHIP',
 BOM_COST='SYS_CLOCK',
 PHYS_PAGE='102',
 XY='(-2850,2475)',
 ROT='0',
 VER='2',
 VALUE='1.00K',
 PACK_TYPE='0402',
 PART_NUMBER='G21796-026',
 LOCATION='R6P20',
 ROOM='DB1200ZL',
 SEC='1',
 CDS_LIB='mstr_discrete',
 CDS_PART_NAME='RES_0402-1.00K,1%,1/16W,CHIP,GA',
 PRIM_FILE='./archive_libs/mstr_discrete/res/chips/chips.prt';

PART_NAME
 R6P21 'RES_0402-1.00K,1%,1/16W,CHIP,GA':
 ROOM='DB1200ZL';

SECTION_NUMBER 1
 '@BASEBOARD_FAB2_LIB.BASEBOARD_FAB2(SCH_1):PAGE102_I80@MSTR_DISCRETE.RES(CHIPS)':
 C_PATH='@baseboard_fab2_lib.baseboard_fab2(sch_1):page102_i80@mstr_discrete.res~
(chips)',
 P_PATH='@baseboard_fab2_lib.baseboard_fab2(sch_1):page102_i80@mstr_discrete.res~
(chips)',
 PATH='I80',
 DRAWING='@BASEBOARD_FAB2_LIB.BASEBOARD_FAB2(SCH_1):PAGE102',
 WATTAGE='1/16W',
 TOLERANCE='1%',
 SEC_TYPE='0402',
 MATERIAL='CHIP',
 BOM_COST='SYS_CLOCK',
 PHYS_PAGE='102',
 XY='(-3225,2475)',
 ROT='0',
 VER='2',
 VALUE='1.00K',
 PACK_TYPE='0402',
 PART_NUMBER='G21796-026',
 LOCATION='R6P21',
 ROOM='DB1200ZL',
 SEC='1',
 CDS_LIB='mstr_discrete',
 CDS_PART_NAME='RES_0402-1.00K,1%,1/16W,CHIP,GA',
 PRIM_FILE='./archive_libs/mstr_discrete/res/chips/chips.prt';

PART_NAME
 R6P22 'RES_0402-4.75K,1%,1/16W,EMPTY,A':
 ROOM='DB1200ZL';

SECTION_NUMBER 1
 '@BASEBOARD_FAB2_LIB.BASEBOARD_FAB2(SCH_1):PAGE102_I47@MSTR_DISCRETE.RES(CHIPS)':
 C_PATH='@baseboard_fab2_lib.baseboard_fab2(sch_1):page102_i47@mstr_discrete.res~
(chips)',
 P_PATH='@baseboard_fab2_lib.baseboard_fab2(sch_1):page102_i47@mstr_discrete.res~
(chips)',
 PATH='I47',
 DRAWING='@BASEBOARD_FAB2_LIB.BASEBOARD_FAB2(SCH_1):PAGE102',
 WATTAGE='1/16W',
 TOLERANCE='1%',
 SEC_TYPE='0402',
 MATERIAL='EMPTY',
 BOM_COST='SYS_CLOCK',
 PHYS_PAGE='102',
 XY='(-2925,1025)',
 ROT='2',
 VER='2',
 VALUE='4.75K',
 PACK_TYPE='0402',
 PART_NUMBER='G21796-072',
 LOCATION='R6P22',
 ROOM='DB1200ZL',
 SEC='1',
 CDS_LIB='mstr_discrete',
 CDS_PART_NAME='RES_0402-4.75K,1%,1/16W,EMPTY,A',
 PRIM_FILE='./archive_libs/mstr_discrete/res/chips/chips.prt';

PART_NAME
 R6P23 'RES_0402-4.75K,1%,1/16W,EMPTY,A':
 ROOM='DB1200ZL';

SECTION_NUMBER 1
 '@BASEBOARD_FAB2_LIB.BASEBOARD_FAB2(SCH_1):PAGE102_I46@MSTR_DISCRETE.RES(CHIPS)':
 C_PATH='@baseboard_fab2_lib.baseboard_fab2(sch_1):page102_i46@mstr_discrete.res~
(chips)',
 P_PATH='@baseboard_fab2_lib.baseboard_fab2(sch_1):page102_i46@mstr_discrete.res~
(chips)',
 PATH='I46',
 DRAWING='@BASEBOARD_FAB2_LIB.BASEBOARD_FAB2(SCH_1):PAGE102',
 WATTAGE='1/16W',
 TOLERANCE='1%',
 SEC_TYPE='0402',
 MATERIAL='EMPTY',
 BOM_COST='SYS_CLOCK',
 PHYS_PAGE='102',
 XY='(-2675,1025)',
 ROT='0',
 VER='2',
 VALUE='4.75K',
 PACK_TYPE='0402',
 PART_NUMBER='G21796-072',
 LOCATION='R6P23',
 ROOM='DB1200ZL',
 SEC='1',
 CDS_LIB='mstr_discrete',
 CDS_PART_NAME='RES_0402-4.75K,1%,1/16W,EMPTY,A',
 PRIM_FILE='./archive_libs/mstr_discrete/res/chips/chips.prt';

PART_NAME
 R6P25 'RES_0603-2.2,1.0%,1/10W,CHIP,GA':
 ROOM='DB1200ZL';

SECTION_NUMBER 1
 '@BASEBOARD_FAB2_LIB.BASEBOARD_FAB2(SCH_1):PAGE102_I26@MSTR_DISCRETE.RES(CHIPS)':
 C_PATH='@baseboard_fab2_lib.baseboard_fab2(sch_1):page102_i26@mstr_discrete.res~
(chips)',
 P_PATH='@baseboard_fab2_lib.baseboard_fab2(sch_1):page102_i26@mstr_discrete.res~
(chips)',
 PATH='I26',
 DRAWING='@BASEBOARD_FAB2_LIB.BASEBOARD_FAB2(SCH_1):PAGE102',
 WATTAGE='1/10W',
 TOLERANCE='1.0%',
 SEC_TYPE='0603',
 MATERIAL='CHIP',
 BOM_COST='SYS_CLOCK',
 PHYS_PAGE='102',
 XY='(-2825,3400)',
 ROT='0',
 VER='1',
 VALUE='2.2',
 PACK_TYPE='0603',
 PART_NUMBER='G22026-127',
 LOCATION='R6P25',
 ROOM='DB1200ZL',
 SEC='1',
 CDS_LIB='mstr_discrete',
 CDS_PART_NAME='RES_0603-2.2,1.0%,1/10W,CHIP,GA',
 PRIM_FILE='./archive_libs/mstr_discrete/res/chips/chips.prt';

PART_NAME
 R6P27 'RES_0402-4.02K,1%,1/16W,CHIP,GA':
 ROOM='PVCCIN_CPU0_VR';

SECTION_NUMBER 1
 '@BASEBOARD_FAB2_LIB.BASEBOARD_FAB2(SCH_1):PAGE201_I120@MSTR_DISCRETE.RES(CHIPS)':
 C_PATH='@baseboard_fab2_lib.baseboard_fab2(sch_1):page201_i120@mstr_discrete.re~
s(chips)',
 P_PATH='@baseboard_fab2_lib.baseboard_fab2(sch_1):page201_i120@mstr_discrete.re~
s(chips)',
 PATH='I120',
 DRAWING='@BASEBOARD_FAB2_LIB.BASEBOARD_FAB2(SCH_1):PAGE201',
 WATTAGE='1/16W',
 TOLERANCE='1%',
 SEC_TYPE='0402',
 MATERIAL='CHIP',
 PHYS_PAGE='201',
 XY='(-4400,900)',
 ROT='0',
 VER='2',
 VALUE='4.02K',
 PACK_TYPE='0402',
 PART_NUMBER='G21796-082',
 LOCATION='R6P27',
 ROOM='PVCCIN_CPU0_VR',
 SEC='1',
 CDS_LIB='mstr_discrete',
 CDS_PART_NAME='RES_0402-4.02K,1%,1/16W,CHIP,GA',
 PRIM_FILE='./archive_libs/mstr_discrete/res/chips/chips.prt';

PART_NAME
 R6P28 'RES_0402-4.02K,1%,1/16W,CHIP,GA':
 ROOM='PVCCIN_CPU0_VR';

SECTION_NUMBER 1
 '@BASEBOARD_FAB2_LIB.BASEBOARD_FAB2(SCH_1):PAGE201_I121@MSTR_DISCRETE.RES(CHIPS)':
 C_PATH='@baseboard_fab2_lib.baseboard_fab2(sch_1):page201_i121@mstr_discrete.re~
s(chips)',
 P_PATH='@baseboard_fab2_lib.baseboard_fab2(sch_1):page201_i121@mstr_discrete.re~
s(chips)',
 PATH='I121',
 DRAWING='@BASEBOARD_FAB2_LIB.BASEBOARD_FAB2(SCH_1):PAGE201',
 WATTAGE='1/16W',
 TOLERANCE='1%',
 SEC_TYPE='0402',
 MATERIAL='CHIP',
 PHYS_PAGE='201',
 XY='(-4725,900)',
 ROT='0',
 VER='2',
 VALUE='4.02K',
 PACK_TYPE='0402',
 PART_NUMBER='G21796-082',
 LOCATION='R6P28',
 ROOM='PVCCIN_CPU0_VR',
 SEC='1',
 CDS_LIB='mstr_discrete',
 CDS_PART_NAME='RES_0402-4.02K,1%,1/16W,CHIP,GA',
 PRIM_FILE='./archive_libs/mstr_discrete/res/chips/chips.prt';

PART_NAME
 R6P32 'RES_0402-2.0K,1%,1/16W,EMPTY,GA':
 ROOM='PVCCIN_CPU0_VR';

SECTION_NUMBER 1
 '@BASEBOARD_FAB2_LIB.BASEBOARD_FAB2(SCH_1):PAGE201_I102@MSTR_DISCRETE.RES(CHIPS)':
 C_PATH='@baseboard_fab2_lib.baseboard_fab2(sch_1):page201_i102@mstr_discrete.re~
s(chips)',
 P_PATH='@baseboard_fab2_lib.baseboard_fab2(sch_1):page201_i102@mstr_discrete.re~
s(chips)',
 PATH='I102',
 DRAWING='@BASEBOARD_FAB2_LIB.BASEBOARD_FAB2(SCH_1):PAGE201',
 WATTAGE='1/16W',
 TOLERANCE='1%',
 SEC_TYPE='0402',
 MATERIAL='EMPTY',
 PHYS_PAGE='201',
 XY='(-1100,2000)',
 ROT='0',
 VER='2',
 VALUE='2.0K',
 PACK_TYPE='0402',
 PART_NUMBER='G21796-001',
 LOCATION='R6P32',
 ROOM='PVCCIN_CPU0_VR',
 SEC='1',
 CDS_LIB='mstr_discrete',
 CDS_PART_NAME='RES_0402-2.0K,1%,1/16W,EMPTY,GA',
 PRIM_FILE='./archive_libs/mstr_discrete/res/chips/chips.prt';

PART_NAME
 R6P33 'RES_0402-110,1%,1/16W,EMPTY,G2A':
 ROOM='PVCCIO_CPU1';

SECTION_NUMBER 1
 '@BASEBOARD_FAB2_LIB.BASEBOARD_FAB2(SCH_1):PAGE213_I30@MSTR_DISCRETE.RES(CHIPS)':
 C_PATH='@baseboard_fab2_lib.baseboard_fab2(sch_1):page213_i30@mstr_discrete.res~
(chips)',
 P_PATH='@baseboard_fab2_lib.baseboard_fab2(sch_1):page213_i30@mstr_discrete.res~
(chips)',
 PATH='I30',
 DRAWING='@BASEBOARD_FAB2_LIB.BASEBOARD_FAB2(SCH_1):PAGE213',
 WATTAGE='1/16W',
 TOLERANCE='1%',
 SEC_TYPE='0402',
 MATERIAL='EMPTY',
 PHYS_PAGE='213',
 XY='(-2050,4425)',
 ROT='0',
 VER='2',
 VALUE='110',
 PACK_TYPE='0402',
 PART_NUMBER='G21796-203',
 LOCATION='R6P33',
 ROOM='PVCCIO_CPU1',
 SEC='1',
 CDS_LIB='mstr_discrete',
 CDS_PART_NAME='RES_0402-110,1%,1/16W,EMPTY,G2A',
 PRIM_FILE='./archive_libs/mstr_discrete/res/chips/chips.prt';

PART_NAME
 R6P35 'RES_0402-100.0,1%,1/16W,EMPTY,A':
 ROOM='PVCCIO_CPU1';

SECTION_NUMBER 1
 '@BASEBOARD_FAB2_LIB.BASEBOARD_FAB2(SCH_1):PAGE213_I27@MSTR_DISCRETE.RES(CHIPS)':
 C_PATH='@baseboard_fab2_lib.baseboard_fab2(sch_1):page213_i27@mstr_discrete.res~
(chips)',
 P_PATH='@baseboard_fab2_lib.baseboard_fab2(sch_1):page213_i27@mstr_discrete.res~
(chips)',
 PATH='I27',
 DRAWING='@BASEBOARD_FAB2_LIB.BASEBOARD_FAB2(SCH_1):PAGE213',
 WATTAGE='1/16W',
 TOLERANCE='1%',
 SEC_TYPE='0402',
 MATERIAL='EMPTY',
 PHYS_PAGE='213',
 XY='(-1450,4475)',
 ROT='0',
 VER='2',
 VALUE='100.0',
 PACK_TYPE='0402',
 PART_NUMBER='G21796-017',
 LOCATION='R6P35',
 ROOM='PVCCIO_CPU1',
 SEC='1',
 CDS_LIB='mstr_discrete',
 CDS_PART_NAME='RES_0402-100.0,1%,1/16W,EMPTY,A',
 PRIM_FILE='./archive_libs/mstr_discrete/res/chips/chips.prt';

PART_NAME
 R6P37 'RES_0402-2.0K,1%,1/16W,EMPTY,GA':
 ROOM='PVCCIN_CPU0_VR';

SECTION_NUMBER 1
 '@BASEBOARD_FAB2_LIB.BASEBOARD_FAB2(SCH_1):PAGE201_I103@MSTR_DISCRETE.RES(CHIPS)':
 C_PATH='@baseboard_fab2_lib.baseboard_fab2(sch_1):page201_i103@mstr_discrete.re~
s(chips)',
 P_PATH='@baseboard_fab2_lib.baseboard_fab2(sch_1):page201_i103@mstr_discrete.re~
s(chips)',
 PATH='I103',
 DRAWING='@BASEBOARD_FAB2_LIB.BASEBOARD_FAB2(SCH_1):PAGE201',
 WATTAGE='1/16W',
 TOLERANCE='1%',
 SEC_TYPE='0402',
 MATERIAL='EMPTY',
 PHYS_PAGE='201',
 XY='(-825,2000)',
 ROT='0',
 VER='2',
 VALUE='2.0K',
 PACK_TYPE='0402',
 PART_NUMBER='G21796-001',
 LOCATION='R6P37',
 ROOM='PVCCIN_CPU0_VR',
 SEC='1',
 CDS_LIB='mstr_discrete',
 CDS_PART_NAME='RES_0402-2.0K,1%,1/16W,EMPTY,GA',
 PRIM_FILE='./archive_libs/mstr_discrete/res/chips/chips.prt';

PART_NAME
 R6P39 'RES_0402-4.75K,1%,1/16W,CHIP,GA':
 ROOM='CPU1';

SECTION_NUMBER 1
 '@BASEBOARD_FAB2_LIB.BASEBOARD_FAB2(SCH_1):PAGE55_I181@MSTR_DISCRETE.RES(CHIPS)':
 C_PATH='@baseboard_fab2_lib.baseboard_fab2(sch_1):page55_i181@mstr_discrete.res~
(chips)',
 P_PATH='@baseboard_fab2_lib.baseboard_fab2(sch_1):page55_i181@mstr_discrete.res~
(chips)',
 PATH='I181',
 DRAWING='@BASEBOARD_FAB2_LIB.BASEBOARD_FAB2(SCH_1):PAGE55',
 WATTAGE='1/16W',
 TOLERANCE='1%',
 SEC_TYPE='0402',
 MATERIAL='CHIP',
 PHYS_PAGE='55',
 XY='(13275,1100)',
 ROT='0',
 VER='2',
 VALUE='4.75K',
 PACK_TYPE='0402',
 PART_NUMBER='G21796-072',
 LOCATION='R6P39',
 ROOM='CPU1',
 SEC='1',
 CDS_LIB='mstr_discrete',
 CDS_PART_NAME='RES_0402-4.75K,1%,1/16W,CHIP,GA',
 PRIM_FILE='./archive_libs/mstr_discrete/res/chips/chips.prt';

PART_NAME
 R6P40 'RES_0402-100.0K,1%,1/16W,EMPTYA':
 ROOM='BMC';

SECTION_NUMBER 1
 '@BASEBOARD_FAB2_LIB.BASEBOARD_FAB2(SCH_1):PAGE213_I91@MSTR_DISCRETE.RES(CHIPS)':
 C_PATH='@baseboard_fab2_lib.baseboard_fab2(sch_1):page213_i91@mstr_discrete.res~
(chips)',
 P_PATH='@baseboard_fab2_lib.baseboard_fab2(sch_1):page213_i91@mstr_discrete.res~
(chips)',
 PATH='I91',
 DRAWING='@BASEBOARD_FAB2_LIB.BASEBOARD_FAB2(SCH_1):PAGE213',
 WATTAGE='1/16W',
 TOLERANCE='1%',
 SEC_TYPE='0402',
 MATERIAL='EMPTY',
 BOM_COST='SM_CONTROLLER',
 PHYS_PAGE='213',
 XY='(-1025,4275)',
 ROT='0',
 VER='2',
 VALUE='100.0K',
 PACK_TYPE='0402',
 PART_NUMBER='G21796-010',
 LOCATION='R6P40',
 ROOM='BMC',
 SEC='1',
 CDS_LIB='mstr_discrete',
 CDS_PART_NAME='RES_0402-100.0K,1%,1/16W,EMPTYA',
 PRIM_FILE='./archive_libs/mstr_discrete/res/chips/chips.prt';

PART_NAME
 R6P41 'RES_0402-0.0,5%,1/16W,CHIP,G21A':
 ROOM='PVCCIN_CPU0_VR';

SECTION_NUMBER 1
 '@BASEBOARD_FAB2_LIB.BASEBOARD_FAB2(SCH_1):PAGE213_I90@MSTR_DISCRETE.RES(CHIPS)':
 C_PATH='@baseboard_fab2_lib.baseboard_fab2(sch_1):page213_i90@mstr_discrete.res~
(chips)',
 P_PATH='@baseboard_fab2_lib.baseboard_fab2(sch_1):page213_i90@mstr_discrete.res~
(chips)',
 PATH='I90',
 DRAWING='@BASEBOARD_FAB2_LIB.BASEBOARD_FAB2(SCH_1):PAGE213',
 WATTAGE='1/16W',
 TOLERANCE='5%',
 SEC_TYPE='0402',
 MATERIAL='CHIP',
 PHYS_PAGE='213',
 XY='(-1925,3225)',
 ROT='0',
 VER='1',
 VALUE='0.0',
 PACK_TYPE='0402',
 PART_NUMBER='G21497-005',
 LOCATION='R6P41',
 ROOM='PVCCIN_CPU0_VR',
 SEC='1',
 CDS_LIB='mstr_discrete',
 CDS_PART_NAME='RES_0402-0.0,5%,1/16W,CHIP,G21A',
 PRIM_FILE='./archive_libs/mstr_discrete/res/chips/chips.prt';

PART_NAME
 R6P45 'RES_0402-33.2,1%,1/16W,CHIP,G2A':;

SECTION_NUMBER 1
 '@BASEBOARD_FAB2_LIB.BASEBOARD_FAB2(SCH_1):PAGE201_I128@MSTR_DISCRETE.RES(CHIPS)':
 C_PATH='@baseboard_fab2_lib.baseboard_fab2(sch_1):page201_i128@mstr_discrete.re~
s(chips)',
 P_PATH='@baseboard_fab2_lib.baseboard_fab2(sch_1):page201_i128@mstr_discrete.re~
s(chips)',
 PATH='I128',
 DRAWING='@BASEBOARD_FAB2_LIB.BASEBOARD_FAB2(SCH_1):PAGE201',
 WATTAGE='1/16W',
 TOLERANCE='1%',
 SEC_TYPE='0402',
 MATERIAL='CHIP',
 PHYS_PAGE='201',
 XY='(-2400,2975)',
 ROT='0',
 VER='1',
 VALUE='33.2',
 PACK_TYPE='0402',
 PART_NUMBER='G21796-074',
 LOCATION='R6P45',
 SEC='1',
 CDS_LIB='mstr_discrete',
 CDS_PART_NAME='RES_0402-33.2,1%,1/16W,CHIP,G2A',
 PRIM_FILE='./archive_libs/mstr_discrete/res/chips/chips.prt';

PART_NAME
 R6P46 'RES_0402-100.0,1%,1/16W,CHIP,GA':
 ROOM='DEBUG';

SECTION_NUMBER 1
 '@BASEBOARD_FAB2_LIB.BASEBOARD_FAB2(SCH_1):PAGE112_I49@MSTR_DISCRETE.RES(CHIPS)':
 C_PATH='@baseboard_fab2_lib.baseboard_fab2(sch_1):page112_i49@mstr_discrete.res~
(chips)',
 P_PATH='@baseboard_fab2_lib.baseboard_fab2(sch_1):page112_i49@mstr_discrete.res~
(chips)',
 PATH='I49',
 DRAWING='@BASEBOARD_FAB2_LIB.BASEBOARD_FAB2(SCH_1):PAGE112',
 WATTAGE='1/16W',
 TOLERANCE='1%',
 SEC_TYPE='0402',
 MATERIAL='CHIP',
 PHYS_PAGE='112',
 XY='(2675,2400)',
 ROT='0',
 VER='2',
 VALUE='100.0',
 PACK_TYPE='0402',
 PART_NUMBER='G21796-017',
 LOCATION='R6P46',
 ROOM='DEBUG',
 SEC='1',
 CDS_LIB='mstr_discrete',
 CDS_PART_NAME='RES_0402-100.0,1%,1/16W,CHIP,GA',
 PRIM_FILE='./archive_libs/mstr_discrete/res/chips/chips.prt';

PART_NAME
 R6P47 'RES_0402-0.0,5%,1/16W,CHIP,G21A':
 ROOM='CPU0';

SECTION_NUMBER 1
 '@BASEBOARD_FAB2_LIB.BASEBOARD_FAB2(SCH_1):PAGE204_I103@MSTR_DISCRETE.RES(CHIPS)':
 C_PATH='@baseboard_fab2_lib.baseboard_fab2(sch_1):page204_i103@mstr_discrete.re~
s(chips)',
 P_PATH='@baseboard_fab2_lib.baseboard_fab2(sch_1):page204_i103@mstr_discrete.re~
s(chips)',
 PATH='I103',
 DRAWING='@BASEBOARD_FAB2_LIB.BASEBOARD_FAB2(SCH_1):PAGE204',
 WATTAGE='1/16W',
 TOLERANCE='5%',
 SEC_TYPE='0402',
 MATERIAL='CHIP',
 BOM_COST='PROC_SIDEBAND',
 PHYS_PAGE='204',
 XY='(-5550,4750)',
 ROT='0',
 VER='1',
 VALUE='0.0',
 PACK_TYPE='0402',
 PART_NUMBER='G21497-005',
 LOCATION='R6P47',
 ROOM='CPU0',
 SEC='1',
 CDS_LIB='mstr_discrete',
 CDS_PART_NAME='RES_0402-0.0,5%,1/16W,CHIP,G21A',
 PRIM_FILE='./archive_libs/mstr_discrete/res/chips/chips.prt';

PART_NAME
 R6P48 'RES_0402-1.00K,1%,1/16W,CHIP,GA':
 ROOM='PROC_SIDEBAND';

SECTION_NUMBER 1
 '@BASEBOARD_FAB2_LIB.BASEBOARD_FAB2(SCH_1):PAGE102_I115@MSTR_DISCRETE.RES(CHIPS)':
 C_PATH='@baseboard_fab2_lib.baseboard_fab2(sch_1):page102_i115@mstr_discrete.re~
s(chips)',
 P_PATH='@baseboard_fab2_lib.baseboard_fab2(sch_1):page102_i115@mstr_discrete.re~
s(chips)',
 PATH='I115',
 DRAWING='@BASEBOARD_FAB2_LIB.BASEBOARD_FAB2(SCH_1):PAGE102',
 WATTAGE='1/16W',
 TOLERANCE='1%',
 SEC_TYPE='0402',
 MATERIAL='CHIP',
 PHYS_PAGE='102',
 XY='(-750,1075)',
 ROT='0',
 VER='2',
 VALUE='1.00K',
 PACK_TYPE='0402',
 PART_NUMBER='G21796-026',
 LOCATION='R6P48',
 ROOM='PROC_SIDEBAND',
 SEC='1',
 CDS_LIB='mstr_discrete',
 CDS_PART_NAME='RES_0402-1.00K,1%,1/16W,CHIP,GA',
 PRIM_FILE='./archive_libs/mstr_discrete/res/chips/chips.prt';

PART_NAME
 R6P49 'RES_0402-2.26K,1.0%,1/16W,EMPTA':
 ROOM='PVCCIO_CPU1';

SECTION_NUMBER 1
 '@BASEBOARD_FAB2_LIB.BASEBOARD_FAB2(SCH_1):PAGE213_I14@MSTR_DISCRETE.RES(CHIPS)':
 C_PATH='@baseboard_fab2_lib.baseboard_fab2(sch_1):page213_i14@mstr_discrete.res~
(chips)',
 P_PATH='@baseboard_fab2_lib.baseboard_fab2(sch_1):page213_i14@mstr_discrete.res~
(chips)',
 PATH='I14',
 DRAWING='@BASEBOARD_FAB2_LIB.BASEBOARD_FAB2(SCH_1):PAGE213',
 WATTAGE='1/16W',
 TOLERANCE='1.0%',
 SEC_TYPE='0402',
 MATERIAL='EMPTY',
 PHYS_PAGE='213',
 XY='(1600,4075)',
 ROT='0',
 VER='2',
 VALUE='2.26K',
 PACK_TYPE='0402',
 PART_NUMBER='G21796-311',
 LOCATION='R6P49',
 ROOM='PVCCIO_CPU1',
 SEC='1',
 CDS_LIB='mstr_discrete',
 CDS_PART_NAME='RES_0402-2.26K,1.0%,1/16W,EMPTA',
 PRIM_FILE='./archive_libs/mstr_discrete/res/chips/chips.prt';

PART_NAME
 R6R2 'RES_0402-0.0,5%,1/16W,CHIP,G21A':
 ROOM='CPU0';

SECTION_NUMBER 1
 '@BASEBOARD_FAB2_LIB.BASEBOARD_FAB2(SCH_1):PAGE202_I107@MSTR_DISCRETE.RES(CHIPS)':
 C_PATH='@baseboard_fab2_lib.baseboard_fab2(sch_1):page202_i107@mstr_discrete.re~
s(chips)',
 P_PATH='@baseboard_fab2_lib.baseboard_fab2(sch_1):page202_i107@mstr_discrete.re~
s(chips)',
 PATH='I107',
 DRAWING='@BASEBOARD_FAB2_LIB.BASEBOARD_FAB2(SCH_1):PAGE202',
 WATTAGE='1/16W',
 TOLERANCE='5%',
 SEC_TYPE='0402',
 MATERIAL='CHIP',
 BOM_COST='PROC_SIDEBAND',
 PHYS_PAGE='202',
 XY='(-5550,4625)',
 ROT='0',
 VER='1',
 VALUE='0.0',
 PACK_TYPE='0402',
 PART_NUMBER='G21497-005',
 LOCATION='R6R2',
 ROOM='CPU0',
 SEC='1',
 CDS_LIB='mstr_discrete',
 CDS_PART_NAME='RES_0402-0.0,5%,1/16W,CHIP,G21A',
 PRIM_FILE='./archive_libs/mstr_discrete/res/chips/chips.prt';

PART_NAME
 R6R5 'RES_0402-0.0,5%,1/16W,CHIP,G21A':
 ROOM='CPU0';

SECTION_NUMBER 1
 '@BASEBOARD_FAB2_LIB.BASEBOARD_FAB2(SCH_1):PAGE214_I173@MSTR_DISCRETE.RES(CHIPS)':
 C_PATH='@baseboard_fab2_lib.baseboard_fab2(sch_1):page214_i173@mstr_discrete.re~
s(chips)',
 P_PATH='@baseboard_fab2_lib.baseboard_fab2(sch_1):page214_i173@mstr_discrete.re~
s(chips)',
 PATH='I173',
 DRAWING='@BASEBOARD_FAB2_LIB.BASEBOARD_FAB2(SCH_1):PAGE214',
 WATTAGE='1/16W',
 TOLERANCE='5%',
 SEC_TYPE='0402',
 MATERIAL='CHIP',
 BOM_COST='PROC_SIDEBAND',
 PHYS_PAGE='214',
 XY='(-1575,4750)',
 ROT='0',
 VER='1',
 VALUE='0.0',
 PACK_TYPE='0402',
 PART_NUMBER='G21497-005',
 LOCATION='R6R5',
 ROOM='CPU0',
 SEC='1',
 CDS_LIB='mstr_discrete',
 CDS_PART_NAME='RES_0402-0.0,5%,1/16W,CHIP,G21A',
 PRIM_FILE='./archive_libs/mstr_discrete/res/chips/chips.prt';

PART_NAME
 R6R6 'RES_0402-0.0,5%,1/16W,CHIP,G21A':
 ROOM='CPU0';

SECTION_NUMBER 1
 '@BASEBOARD_FAB2_LIB.BASEBOARD_FAB2(SCH_1):PAGE202_I108@MSTR_DISCRETE.RES(CHIPS)':
 C_PATH='@baseboard_fab2_lib.baseboard_fab2(sch_1):page202_i108@mstr_discrete.re~
s(chips)',
 P_PATH='@baseboard_fab2_lib.baseboard_fab2(sch_1):page202_i108@mstr_discrete.re~
s(chips)',
 PATH='I108',
 DRAWING='@BASEBOARD_FAB2_LIB.BASEBOARD_FAB2(SCH_1):PAGE202',
 WATTAGE='1/16W',
 TOLERANCE='5%',
 SEC_TYPE='0402',
 MATERIAL='CHIP',
 BOM_COST='PROC_SIDEBAND',
 PHYS_PAGE='202',
 XY='(-5625,1975)',
 ROT='0',
 VER='1',
 VALUE='0.0',
 PACK_TYPE='0402',
 PART_NUMBER='G21497-005',
 LOCATION='R6R6',
 ROOM='CPU0',
 SEC='1',
 CDS_LIB='mstr_discrete',
 CDS_PART_NAME='RES_0402-0.0,5%,1/16W,CHIP,G21A',
 PRIM_FILE='./archive_libs/mstr_discrete/res/chips/chips.prt';

PART_NAME
 R6T1 'RES_0402-240,1.0%,1/16W,CHIP,GA':
 ROOM='MEM',
 SIGNAL_MODEL='DEFAULT_RESISTOR_750OHM_2_1';

SECTION_NUMBER 1
 '@BASEBOARD_FAB2_LIB.BASEBOARD_FAB2(SCH_1):PAGE99_I70@MSTR_DISCRETE.RES(CHIPS)':
 C_PATH='@baseboard_fab2_lib.baseboard_fab2(sch_1):page99_i70@mstr_discrete.res(~
chips)',
 P_PATH='@baseboard_fab2_lib.baseboard_fab2(sch_1):page99_i70@mstr_discrete.res(~
chips)',
 PATH='I70',
 DRAWING='@BASEBOARD_FAB2_LIB.BASEBOARD_FAB2(SCH_1):PAGE99',
 CD_SEC='1',
 WATTAGE='1/16W',
 TOLERANCE='1.0%',
 MATERIAL='CHIP',
 BOM_COST='SM_CONTROLLER',
 PHYS_PAGE='99',
 XY='(-700,2450)',
 ROT='2',
 VER='2',
 VALUE='240',
 PACK_TYPE='0402',
 PART_NUMBER='G21796-294',
 LOCATION='R6T1',
 SIGNAL_MODEL='DEFAULT_RESISTOR_750OHM_2_1',
 ROOM='MEM',
 CDS_LIB='mstr_discrete',
 CDS_PART_NAME='RES_0402-240,1.0%,1/16W,CHIP,GA',
 PRIM_FILE='./archive_libs/mstr_discrete/res/chips/chips.prt';

PART_NAME
 R6T2 'RES_0402-240,1.0%,1/16W,CHIP,GA':
 ROOM='MEM',
 SIGNAL_MODEL='DEFAULT_RESISTOR_750OHM_2_1';

SECTION_NUMBER 1
 '@BASEBOARD_FAB2_LIB.BASEBOARD_FAB2(SCH_1):PAGE99_I72@MSTR_DISCRETE.RES(CHIPS)':
 C_PATH='@baseboard_fab2_lib.baseboard_fab2(sch_1):page99_i72@mstr_discrete.res(~
chips)',
 P_PATH='@baseboard_fab2_lib.baseboard_fab2(sch_1):page99_i72@mstr_discrete.res(~
chips)',
 PATH='I72',
 DRAWING='@BASEBOARD_FAB2_LIB.BASEBOARD_FAB2(SCH_1):PAGE99',
 CD_SEC='1',
 WATTAGE='1/16W',
 TOLERANCE='1.0%',
 MATERIAL='CHIP',
 BOM_COST='SM_CONTROLLER',
 PHYS_PAGE='99',
 XY='(-1075,2450)',
 ROT='2',
 VER='2',
 VALUE='240',
 PACK_TYPE='0402',
 PART_NUMBER='G21796-294',
 LOCATION='R6T2',
 SIGNAL_MODEL='DEFAULT_RESISTOR_750OHM_2_1',
 ROOM='MEM',
 CDS_LIB='mstr_discrete',
 CDS_PART_NAME='RES_0402-240,1.0%,1/16W,CHIP,GA',
 PRIM_FILE='./archive_libs/mstr_discrete/res/chips/chips.prt';

PART_NAME
 R6T3 'RES_0402-10.0,1%,1/16W,CHIP,G2A':
 ROOM='MEM';

SECTION_NUMBER 1
 '@BASEBOARD_FAB2_LIB.BASEBOARD_FAB2(SCH_1):PAGE99_I92@MSTR_DISCRETE.RES(CHIPS)':
 C_PATH='@baseboard_fab2_lib.baseboard_fab2(sch_1):page99_i92@mstr_discrete.res(~
chips)',
 P_PATH='@baseboard_fab2_lib.baseboard_fab2(sch_1):page99_i92@mstr_discrete.res(~
chips)',
 PATH='I92',
 DRAWING='@BASEBOARD_FAB2_LIB.BASEBOARD_FAB2(SCH_1):PAGE99',
 WATTAGE='1/16W',
 TOLERANCE='1%',
 MATERIAL='CHIP',
 BOM_COST='SM_CONTROLLER',
 PHYS_PAGE='99',
 XY='(-1475,2150)',
 ROT='0',
 VER='1',
 VALUE='10.0',
 PACK_TYPE='0402',
 PART_NUMBER='G21796-066',
 LOCATION='R6T3',
 ROOM='MEM',
 CDS_LIB='mstr_discrete',
 CDS_PART_NAME='RES_0402-10.0,1%,1/16W,CHIP,G2A',
 PRIM_FILE='./archive_libs/mstr_discrete/res/chips/chips.prt';

PART_NAME
 R6T4 'RES_0402-10.0,1%,1/16W,CHIP,G2A':
 ROOM='MEM';

SECTION_NUMBER 1
 '@BASEBOARD_FAB2_LIB.BASEBOARD_FAB2(SCH_1):PAGE99_I111@MSTR_DISCRETE.RES(CHIPS)':
 C_PATH='@baseboard_fab2_lib.baseboard_fab2(sch_1):page99_i111@mstr_discrete.res~
(chips)',
 P_PATH='@baseboard_fab2_lib.baseboard_fab2(sch_1):page99_i111@mstr_discrete.res~
(chips)',
 PATH='I111',
 DRAWING='@BASEBOARD_FAB2_LIB.BASEBOARD_FAB2(SCH_1):PAGE99',
 WATTAGE='1/16W',
 TOLERANCE='1%',
 MATERIAL='CHIP',
 BOM_COST='SM_CONTROLLER',
 PHYS_PAGE='99',
 XY='(-1100,2100)',
 ROT='0',
 VER='1',
 VALUE='10.0',
 PACK_TYPE='0402',
 PART_NUMBER='G21796-066',
 LOCATION='R6T4',
 ROOM='MEM',
 CDS_LIB='mstr_discrete',
 CDS_PART_NAME='RES_0402-10.0,1%,1/16W,CHIP,G2A',
 PRIM_FILE='./archive_libs/mstr_discrete/res/chips/chips.prt';

PART_NAME
 R6T5 'RES_0402-1.00K,1%,1/16W,CHIP,GA':
 ROOM='DEBUG';

SECTION_NUMBER 1
 '@BASEBOARD_FAB2_LIB.BASEBOARD_FAB2(SCH_1):PAGE112_I62@MSTR_DISCRETE.RES(CHIPS)':
 C_PATH='@baseboard_fab2_lib.baseboard_fab2(sch_1):page112_i62@mstr_discrete.res~
(chips)',
 P_PATH='@baseboard_fab2_lib.baseboard_fab2(sch_1):page112_i62@mstr_discrete.res~
(chips)',
 PATH='I62',
 DRAWING='@BASEBOARD_FAB2_LIB.BASEBOARD_FAB2(SCH_1):PAGE112',
 WATTAGE='1/16W',
 TOLERANCE='1%',
 SEC_TYPE='0402',
 MATERIAL='CHIP',
 BOM_COST='DEBUG',
 PHYS_PAGE='112',
 XY='(500,1100)',
 ROT='0',
 VER='2',
 VALUE='1.00K',
 PACK_TYPE='0402',
 PART_NUMBER='G21796-026',
 LOCATION='R6T5',
 ROOM='DEBUG',
 SEC='1',
 CDS_LIB='mstr_discrete',
 CDS_PART_NAME='RES_0402-1.00K,1%,1/16W,CHIP,GA',
 PRIM_FILE='./archive_libs/mstr_discrete/res/chips/chips.prt';

PART_NAME
 R6T6 'RES_0402-150.0,1%,1/16W,CHIP,GA':
 ROOM='DEBUG';

SECTION_NUMBER 1
 '@BASEBOARD_FAB2_LIB.BASEBOARD_FAB2(SCH_1):PAGE112_I56@MSTR_DISCRETE.RES(CHIPS)':
 C_PATH='@baseboard_fab2_lib.baseboard_fab2(sch_1):page112_i56@mstr_discrete.res~
(chips)',
 P_PATH='@baseboard_fab2_lib.baseboard_fab2(sch_1):page112_i56@mstr_discrete.res~
(chips)',
 PATH='I56',
 DRAWING='@BASEBOARD_FAB2_LIB.BASEBOARD_FAB2(SCH_1):PAGE112',
 WATTAGE='1/16W',
 TOLERANCE='1%',
 SEC_TYPE='0402',
 MATERIAL='CHIP',
 PHYS_PAGE='112',
 XY='(875,2400)',
 ROT='0',
 VER='2',
 VALUE='150.0',
 PACK_TYPE='0402',
 PART_NUMBER='G21796-009',
 LOCATION='R6T6',
 ROOM='DEBUG',
 SEC='1',
 CDS_LIB='mstr_discrete',
 CDS_PART_NAME='RES_0402-150.0,1%,1/16W,CHIP,GA',
 PRIM_FILE='./archive_libs/mstr_discrete/res/chips/chips.prt';

PART_NAME
 R6T7 'RES_0402-150.0,1%,1/16W,CHIP,GA':
 ROOM='DEBUG';

SECTION_NUMBER 1
 '@BASEBOARD_FAB2_LIB.BASEBOARD_FAB2(SCH_1):PAGE112_I55@MSTR_DISCRETE.RES(CHIPS)':
 C_PATH='@baseboard_fab2_lib.baseboard_fab2(sch_1):page112_i55@mstr_discrete.res~
(chips)',
 P_PATH='@baseboard_fab2_lib.baseboard_fab2(sch_1):page112_i55@mstr_discrete.res~
(chips)',
 PATH='I55',
 DRAWING='@BASEBOARD_FAB2_LIB.BASEBOARD_FAB2(SCH_1):PAGE112',
 WATTAGE='1/16W',
 TOLERANCE='1%',
 SEC_TYPE='0402',
 MATERIAL='CHIP',
 PHYS_PAGE='112',
 XY='(1225,2400)',
 ROT='0',
 VER='2',
 VALUE='150.0',
 PACK_TYPE='0402',
 PART_NUMBER='G21796-009',
 LOCATION='R6T7',
 ROOM='DEBUG',
 SEC='1',
 CDS_LIB='mstr_discrete',
 CDS_PART_NAME='RES_0402-150.0,1%,1/16W,CHIP,GA',
 PRIM_FILE='./archive_libs/mstr_discrete/res/chips/chips.prt';

PART_NAME
 R6T8 'RES_0402-100.0,1%,1/16W,CHIP,GA':
 ROOM='DEBUG';

SECTION_NUMBER 1
 '@BASEBOARD_FAB2_LIB.BASEBOARD_FAB2(SCH_1):PAGE112_I121@MSTR_DISCRETE.RES(CHIPS)':
 C_PATH='@baseboard_fab2_lib.baseboard_fab2(sch_1):page112_i121@mstr_discrete.re~
s(chips)',
 P_PATH='@baseboard_fab2_lib.baseboard_fab2(sch_1):page112_i121@mstr_discrete.re~
s(chips)',
 PATH='I121',
 DRAWING='@BASEBOARD_FAB2_LIB.BASEBOARD_FAB2(SCH_1):PAGE112',
 WATTAGE='1/16W',
 TOLERANCE='1%',
 SEC_TYPE='0402',
 MATERIAL='CHIP',
 PHYS_PAGE='112',
 XY='(3175,2400)',
 ROT='0',
 VER='2',
 VALUE='100.0',
 PACK_TYPE='0402',
 PART_NUMBER='G21796-017',
 LOCATION='R6T8',
 ROOM='DEBUG',
 SEC='1',
 CDS_LIB='mstr_discrete',
 CDS_PART_NAME='RES_0402-100.0,1%,1/16W,CHIP,GA',
 PRIM_FILE='./archive_libs/mstr_discrete/res/chips/chips.prt';

PART_NAME
 R6T9 'RES_0402-100.0,1%,1/16W,CHIP,GA':
 ROOM='DEBUG';

SECTION_NUMBER 1
 '@BASEBOARD_FAB2_LIB.BASEBOARD_FAB2(SCH_1):PAGE112_I120@MSTR_DISCRETE.RES(CHIPS)':
 C_PATH='@baseboard_fab2_lib.baseboard_fab2(sch_1):page112_i120@mstr_discrete.re~
s(chips)',
 P_PATH='@baseboard_fab2_lib.baseboard_fab2(sch_1):page112_i120@mstr_discrete.re~
s(chips)',
 PATH='I120',
 DRAWING='@BASEBOARD_FAB2_LIB.BASEBOARD_FAB2(SCH_1):PAGE112',
 WATTAGE='1/16W',
 TOLERANCE='1%',
 SEC_TYPE='0402',
 MATERIAL='CHIP',
 PHYS_PAGE='112',
 XY='(3500,2400)',
 ROT='0',
 VER='2',
 VALUE='100.0',
 PACK_TYPE='0402',
 PART_NUMBER='G21796-017',
 LOCATION='R6T9',
 ROOM='DEBUG',
 SEC='1',
 CDS_LIB='mstr_discrete',
 CDS_PART_NAME='RES_0402-100.0,1%,1/16W,CHIP,GA',
 PRIM_FILE='./archive_libs/mstr_discrete/res/chips/chips.prt';

PART_NAME
 R6U3 'RES_0402-1.0M,1%,1/16W,EMPTY,GA':
 ROOM='VTT_GHJ_PWR_VR';

SECTION_NUMBER 1
 '@BASEBOARD_FAB2_LIB.BASEBOARD_FAB2(SCH_1):PAGE229_I5@MSTR_DISCRETE.RES(CHIPS)':
 C_PATH='@baseboard_fab2_lib.baseboard_fab2(sch_1):page229_i5@mstr_discrete.res(~
chips)',
 P_PATH='@baseboard_fab2_lib.baseboard_fab2(sch_1):page229_i5@mstr_discrete.res(~
chips)',
 PATH='I5',
 DRAWING='@BASEBOARD_FAB2_LIB.BASEBOARD_FAB2(SCH_1):PAGE229',
 WATTAGE='1/16W',
 TOLERANCE='1%',
 SEC_TYPE='0402',
 MATERIAL='EMPTY',
 BOM_COST='MEM_VRD_VTT_GHJ',
 PHYS_PAGE='229',
 XY='(-425,500)',
 ROT='2',
 VER='2',
 VALUE='1.0M',
 PACK_TYPE='0402',
 PART_NUMBER='G21796-021',
 LOCATION='R6U3',
 ROOM='VTT_GHJ_PWR_VR',
 SEC='1',
 CDS_LIB='mstr_discrete',
 CDS_PART_NAME='RES_0402-1.0M,1%,1/16W,EMPTY,GA',
 PRIM_FILE='./archive_libs/mstr_discrete/res/chips/chips.prt';

PART_NAME
 R6U4 'RES_0402-0.0,5%,1/16W,CHIP,G21A':
 ROOM='VTT_ABC_PWR_VR';

SECTION_NUMBER 1
 '@BASEBOARD_FAB2_LIB.BASEBOARD_FAB2(SCH_1):PAGE221_I14@MSTR_DISCRETE.RES(CHIPS)':
 C_PATH='@baseboard_fab2_lib.baseboard_fab2(sch_1):page221_i14@mstr_discrete.res~
(chips)',
 P_PATH='@baseboard_fab2_lib.baseboard_fab2(sch_1):page221_i14@mstr_discrete.res~
(chips)',
 PATH='I14',
 DRAWING='@BASEBOARD_FAB2_LIB.BASEBOARD_FAB2(SCH_1):PAGE221',
 WATTAGE='1/16W',
 TOLERANCE='5%',
 SEC_TYPE='0402',
 MATERIAL='CHIP',
 BOM_COST='MEM_VRD_VTT_ABC',
 PHYS_PAGE='221',
 XY='(-150,1675)',
 ROT='0',
 VER='1',
 VALUE='0.0',
 PACK_TYPE='0402',
 PART_NUMBER='G21497-005',
 LOCATION='R6U4',
 ROOM='VTT_ABC_PWR_VR',
 SEC='1',
 CDS_LIB='mstr_discrete',
 CDS_PART_NAME='RES_0402-0.0,5%,1/16W,CHIP,G21A',
 PRIM_FILE='./archive_libs/mstr_discrete/res/chips/chips.prt';

PART_NAME
 R6U5 'RES_0402-0.0,5%,1/16W,CHIP,G21A':
 ROOM='VTT_ABC_PWR_VR',
 NO_XNET_CONNECTION='1';

SECTION_NUMBER 1
 '@BASEBOARD_FAB2_LIB.BASEBOARD_FAB2(SCH_1):PAGE221_I6@MSTR_DISCRETE.RES(CHIPS)':
 C_PATH='@baseboard_fab2_lib.baseboard_fab2(sch_1):page221_i6@mstr_discrete.res(~
chips)',
 P_PATH='@baseboard_fab2_lib.baseboard_fab2(sch_1):page221_i6@mstr_discrete.res(~
chips)',
 PATH='I6',
 DRAWING='@BASEBOARD_FAB2_LIB.BASEBOARD_FAB2(SCH_1):PAGE221',
 WATTAGE='1/16W',
 TOLERANCE='5%',
 SEC_TYPE='0402',
 MATERIAL='CHIP',
 BOM_COST='MEM_VRD_VTT_ABC',
 NO_XNET_CONNECTION='1',
 PHYS_PAGE='221',
 XY='(-1050,1450)',
 ROT='1',
 VER='2',
 VALUE='0.0',
 PACK_TYPE='0402',
 PART_NUMBER='G21497-005',
 LOCATION='R6U5',
 ROOM='VTT_ABC_PWR_VR',
 SEC='1',
 CDS_LIB='mstr_discrete',
 CDS_PART_NAME='RES_0402-0.0,5%,1/16W,CHIP,G21A',
 PRIM_FILE='./archive_libs/mstr_discrete/res/chips/chips.prt';

PART_NAME
 R6U6 'RES_0402-0.0,5%,1/16W,CHIP,G21A':
 ROOM='VTT_GHJ_PWR_VR',
 NO_XNET_CONNECTION='1';

SECTION_NUMBER 1
 '@BASEBOARD_FAB2_LIB.BASEBOARD_FAB2(SCH_1):PAGE229_I6@MSTR_DISCRETE.RES(CHIPS)':
 C_PATH='@baseboard_fab2_lib.baseboard_fab2(sch_1):page229_i6@mstr_discrete.res(~
chips)',
 P_PATH='@baseboard_fab2_lib.baseboard_fab2(sch_1):page229_i6@mstr_discrete.res(~
chips)',
 PATH='I6',
 DRAWING='@BASEBOARD_FAB2_LIB.BASEBOARD_FAB2(SCH_1):PAGE229',
 WATTAGE='1/16W',
 TOLERANCE='5%',
 SEC_TYPE='0402',
 MATERIAL='CHIP',
 BOM_COST='MEM_VRD_VTT_GHJ',
 NO_XNET_CONNECTION='1',
 PHYS_PAGE='229',
 XY='(-850,1400)',
 ROT='1',
 VER='2',
 VALUE='0.0',
 PACK_TYPE='0402',
 PART_NUMBER='G21497-005',
 LOCATION='R6U6',
 ROOM='VTT_GHJ_PWR_VR',
 SEC='1',
 CDS_LIB='mstr_discrete',
 CDS_PART_NAME='RES_0402-0.0,5%,1/16W,CHIP,G21A',
 PRIM_FILE='./archive_libs/mstr_discrete/res/chips/chips.prt';

PART_NAME
 R6U7 'RES_0402-0.0,5%,1/16W,CHIP,G21A':
 ROOM='VTT_GHJ_PWR_VR';

SECTION_NUMBER 1
 '@BASEBOARD_FAB2_LIB.BASEBOARD_FAB2(SCH_1):PAGE229_I9@MSTR_DISCRETE.RES(CHIPS)':
 C_PATH='@baseboard_fab2_lib.baseboard_fab2(sch_1):page229_i9@mstr_discrete.res(~
chips)',
 P_PATH='@baseboard_fab2_lib.baseboard_fab2(sch_1):page229_i9@mstr_discrete.res(~
chips)',
 PATH='I9',
 DRAWING='@BASEBOARD_FAB2_LIB.BASEBOARD_FAB2(SCH_1):PAGE229',
 WATTAGE='1/16W',
 TOLERANCE='5%',
 SEC_TYPE='0402',
 MATERIAL='CHIP',
 BOM_COST='MEM_VRD_VTT_GHJ',
 PHYS_PAGE='229',
 XY='(25,1600)',
 ROT='0',
 VER='1',
 VALUE='0.0',
 PACK_TYPE='0402',
 PART_NUMBER='G21497-005',
 LOCATION='R6U7',
 ROOM='VTT_GHJ_PWR_VR',
 SEC='1',
 CDS_LIB='mstr_discrete',
 CDS_PART_NAME='RES_0402-0.0,5%,1/16W,CHIP,G21A',
 PRIM_FILE='./archive_libs/mstr_discrete/res/chips/chips.prt';

PART_NAME
 R6U13 'RES_0402-20.0,1%,1/16W,CHIP,G2A':
 ROOM='MEM';

SECTION_NUMBER 1
 '@BASEBOARD_FAB2_LIB.BASEBOARD_FAB2(SCH_1):PAGE99_I42@MSTR_DISCRETE.RES(CHIPS)':
 C_PATH='@baseboard_fab2_lib.baseboard_fab2(sch_1):page99_i42@mstr_discrete.res(~
chips)',
 P_PATH='@baseboard_fab2_lib.baseboard_fab2(sch_1):page99_i42@mstr_discrete.res(~
chips)',
 PATH='I42',
 DRAWING='@BASEBOARD_FAB2_LIB.BASEBOARD_FAB2(SCH_1):PAGE99',
 WATTAGE='1/16W',
 TOLERANCE='1%',
 MATERIAL='CHIP',
 PHYS_PAGE='99',
 XY='(1600,2150)',
 ROT='0',
 VER='1',
 VALUE='20.0',
 PACK_TYPE='0402',
 PART_NUMBER='G21796-173',
 LOCATION='R6U13',
 ROOM='MEM',
 CDS_LIB='mstr_discrete',
 CDS_PART_NAME='RES_0402-20.0,1%,1/16W,CHIP,G2A',
 PRIM_FILE='./archive_libs/mstr_discrete/res/chips/chips.prt';

PART_NAME
 R6U14 'RES_0402-20.0,1%,1/16W,CHIP,G2A':
 ROOM='MEM';

SECTION_NUMBER 1
 '@BASEBOARD_FAB2_LIB.BASEBOARD_FAB2(SCH_1):PAGE99_I115@MSTR_DISCRETE.RES(CHIPS)':
 C_PATH='@baseboard_fab2_lib.baseboard_fab2(sch_1):page99_i115@mstr_discrete.res~
(chips)',
 P_PATH='@baseboard_fab2_lib.baseboard_fab2(sch_1):page99_i115@mstr_discrete.res~
(chips)',
 PATH='I115',
 DRAWING='@BASEBOARD_FAB2_LIB.BASEBOARD_FAB2(SCH_1):PAGE99',
 WATTAGE='1/16W',
 TOLERANCE='1%',
 MATERIAL='CHIP',
 PHYS_PAGE='99',
 XY='(1600,2100)',
 ROT='0',
 VER='1',
 VALUE='20.0',
 PACK_TYPE='0402',
 PART_NUMBER='G21796-173',
 LOCATION='R6U14',
 ROOM='MEM',
 CDS_LIB='mstr_discrete',
 CDS_PART_NAME='RES_0402-20.0,1%,1/16W,CHIP,G2A',
 PRIM_FILE='./archive_libs/mstr_discrete/res/chips/chips.prt';

PART_NAME
 R6U15 'RES_0402-1.0M,1%,1/16W,EMPTY,GA':
 ROOM='VTT_ABC_PWR_VR';

SECTION_NUMBER 1
 '@BASEBOARD_FAB2_LIB.BASEBOARD_FAB2(SCH_1):PAGE221_I5@MSTR_DISCRETE.RES(CHIPS)':
 C_PATH='@baseboard_fab2_lib.baseboard_fab2(sch_1):page221_i5@mstr_discrete.res(~
chips)',
 P_PATH='@baseboard_fab2_lib.baseboard_fab2(sch_1):page221_i5@mstr_discrete.res(~
chips)',
 PATH='I5',
 DRAWING='@BASEBOARD_FAB2_LIB.BASEBOARD_FAB2(SCH_1):PAGE221',
 WATTAGE='1/16W',
 TOLERANCE='1%',
 SEC_TYPE='0402',
 MATERIAL='EMPTY',
 BOM_COST='MEM_VRD_VTT_ABC',
 PHYS_PAGE='221',
 XY='(-600,575)',
 ROT='2',
 VER='2',
 VALUE='1.0M',
 PACK_TYPE='0402',
 PART_NUMBER='G21796-021',
 LOCATION='R6U15',
 ROOM='VTT_ABC_PWR_VR',
 SEC='1',
 CDS_LIB='mstr_discrete',
 CDS_PART_NAME='RES_0402-1.0M,1%,1/16W,EMPTY,GA',
 PRIM_FILE='./archive_libs/mstr_discrete/res/chips/chips.prt';

PART_NAME
 R6U17 'RES_0402-665,1.0%,1/16W,CHIP,GA':
 ROOM='MEM';

SECTION_NUMBER 1
 '@BASEBOARD_FAB2_LIB.BASEBOARD_FAB2(SCH_1):PAGE99_I106@MSTR_DISCRETE.RES(CHIPS)':
 C_PATH='@baseboard_fab2_lib.baseboard_fab2(sch_1):page99_i106@mstr_discrete.res~
(chips)',
 P_PATH='@baseboard_fab2_lib.baseboard_fab2(sch_1):page99_i106@mstr_discrete.res~
(chips)',
 PATH='I106',
 DRAWING='@BASEBOARD_FAB2_LIB.BASEBOARD_FAB2(SCH_1):PAGE99',
 WATTAGE='1/16W',
 TOLERANCE='1.0%',
 SEC_TYPE='0402',
 MATERIAL='CHIP',
 BOM_COST='SM_CONTROLLER',
 PHYS_PAGE='99',
 XY='(875,2450)',
 ROT='0',
 VER='2',
 VALUE='665',
 PACK_TYPE='0402',
 PART_NUMBER='G21796-235',
 LOCATION='R6U17',
 ROOM='MEM',
 SEC='1',
 CDS_LIB='mstr_discrete',
 CDS_PART_NAME='RES_0402-665,1.0%,1/16W,CHIP,GA',
 PRIM_FILE='./archive_libs/mstr_discrete/res/chips/chips.prt';

PART_NAME
 R6U18 'RES_0402-665,1.0%,1/16W,CHIP,GA':
 ROOM='MEM';

SECTION_NUMBER 1
 '@BASEBOARD_FAB2_LIB.BASEBOARD_FAB2(SCH_1):PAGE99_I104@MSTR_DISCRETE.RES(CHIPS)':
 C_PATH='@baseboard_fab2_lib.baseboard_fab2(sch_1):page99_i104@mstr_discrete.res~
(chips)',
 P_PATH='@baseboard_fab2_lib.baseboard_fab2(sch_1):page99_i104@mstr_discrete.res~
(chips)',
 PATH='I104',
 DRAWING='@BASEBOARD_FAB2_LIB.BASEBOARD_FAB2(SCH_1):PAGE99',
 WATTAGE='1/16W',
 TOLERANCE='1.0%',
 SEC_TYPE='0402',
 MATERIAL='CHIP',
 BOM_COST='SM_CONTROLLER',
 PHYS_PAGE='99',
 XY='(1225,2450)',
 ROT='0',
 VER='2',
 VALUE='665',
 PACK_TYPE='0402',
 PART_NUMBER='G21796-235',
 LOCATION='R6U18',
 ROOM='MEM',
 SEC='1',
 CDS_LIB='mstr_discrete',
 CDS_PART_NAME='RES_0402-665,1.0%,1/16W,CHIP,GA',
 PRIM_FILE='./archive_libs/mstr_discrete/res/chips/chips.prt';

PART_NAME
 R6W1 'RES_0402-4.75K,1%,1/16W,CHIP,GA':
 ROOM='CPU_FANS';

SECTION_NUMBER 1
 '@BASEBOARD_FAB2_LIB.BASEBOARD_FAB2(SCH_1):PAGE137_I149@MSTR_DISCRETE.RES(CHIPS)':
 C_PATH='@baseboard_fab2_lib.baseboard_fab2(sch_1):page137_i149@mstr_discrete.re~
s(chips)',
 P_PATH='@baseboard_fab2_lib.baseboard_fab2(sch_1):page137_i149@mstr_discrete.re~
s(chips)',
 PATH='I149',
 DRAWING='@BASEBOARD_FAB2_LIB.BASEBOARD_FAB2(SCH_1):PAGE137',
 WATTAGE='1/16W',
 TOLERANCE='1%',
 SEC_TYPE='0402',
 MATERIAL='CHIP',
 BOM_COST='SM_THERM',
 PHYS_PAGE='137',
 XY='(-4500,3975)',
 ROT='0',
 VER='2',
 VALUE='4.75K',
 PACK_TYPE='0402',
 PART_NUMBER='G21796-072',
 LOCATION='R6W1',
 ROOM='CPU_FANS',
 SEC='1',
 CDS_LIB='mstr_discrete',
 CDS_PART_NAME='RES_0402-4.75K,1%,1/16W,CHIP,GA',
 PRIM_FILE='./archive_libs/mstr_discrete/res/chips/chips.prt';

PART_NAME
 R6W2 'RES_0402-10.0K,1%,1/16W,CHIP,GA':
 ROOM='HOT_SWAP';

SECTION_NUMBER 1
 '@BASEBOARD_FAB2_LIB.BASEBOARD_FAB2(SCH_1):PAGE137_I144@MSTR_DISCRETE.RES(CHIPS)':
 C_PATH='@baseboard_fab2_lib.baseboard_fab2(sch_1):page137_i144@mstr_discrete.re~
s(chips)',
 P_PATH='@baseboard_fab2_lib.baseboard_fab2(sch_1):page137_i144@mstr_discrete.re~
s(chips)',
 PATH='I144',
 DRAWING='@BASEBOARD_FAB2_LIB.BASEBOARD_FAB2(SCH_1):PAGE137',
 WATTAGE='1/16W',
 TOLERANCE='1%',
 MATERIAL='CHIP',
 PHYS_PAGE='137',
 XY='(-4500,3450)',
 ROT='0',
 VER='2',
 VALUE='10.0K',
 PACK_TYPE='0402',
 PART_NUMBER='G21796-016',
 LOCATION='R6W2',
 ROOM='HOT_SWAP',
 CDS_LIB='mstr_discrete',
 CDS_PART_NAME='RES_0402-10.0K,1%,1/16W,CHIP,GA',
 PRIM_FILE='./archive_libs/mstr_discrete/res/chips/chips.prt';

PART_NAME
 R6W3 '232KR2F-2-GP_SMD-RG1-232KR2F-2A':;

SECTION_NUMBER 1
 '@BASEBOARD_FAB2_LIB.BASEBOARD_FAB2(SCH_1):PAGE200_I250@W_HDL.232KR2F-2-GP(CHIPS)':
 C_PATH='@baseboard_fab2_lib.baseboard_fab2(sch_1):page200_i250@w_hdl.\232kr2f-2~
-gp\(chips)',
 P_PATH='@baseboard_fab2_lib.baseboard_fab2(sch_1):page200_i250@w_hdl.\232kr2f-2~
-gp\(chips)',
 PATH='I250',
 DRAWING='@BASEBOARD_FAB2_LIB.BASEBOARD_FAB2(SCH_1):PAGE200',
 PACK_SIZE='0402',
 RATED='1/16W',
 ATTRIBUTE='232KOHM',
 TOLERANCE='1%',
 SEC_TYPE='SMD-RG1',
 PHYS_PAGE='200',
 XY='(-800,1950)',
 ROT='1',
 VER='1',
 VALUE='232KR2F-2-GP',
 PACK_TYPE='SMD-RG1',
 PART_NUMBER='64.23235.L0L',
 LOCATION='R6W3',
 SEC='1',
 CDS_LIB='w_hdl',
 CDS_PART_NAME='232KR2F-2-GP_SMD-RG1-232KR2F-2A',
 PRIM_FILE='C:/<user>/w_hdl/232kr2f#2d2#2dgp/chips/chips.prt';

PART_NAME
 R6W4 'RES_0402-4.75K,1%,1/16W,CHIP,GA':
 ROOM='CPU_FANS';

SECTION_NUMBER 1
 '@BASEBOARD_FAB2_LIB.BASEBOARD_FAB2(SCH_1):PAGE247_I159@MSTR_DISCRETE.RES(CHIPS)':
 C_PATH='@baseboard_fab2_lib.baseboard_fab2(sch_1):page247_i159@mstr_discrete.re~
s(chips)',
 P_PATH='@baseboard_fab2_lib.baseboard_fab2(sch_1):page247_i159@mstr_discrete.re~
s(chips)',
 PATH='I159',
 DRAWING='@BASEBOARD_FAB2_LIB.BASEBOARD_FAB2(SCH_1):PAGE247',
 WATTAGE='1/16W',
 TOLERANCE='1%',
 SEC_TYPE='0402',
 MATERIAL='CHIP',
 BOM_COST='SM_THERM',
 PHYS_PAGE='247',
 XY='(-6600,4200)',
 ROT='2',
 VER='2',
 VALUE='4.75K',
 PACK_TYPE='0402',
 PART_NUMBER='G21796-072',
 LOCATION='R6W4',
 ROOM='CPU_FANS',
 SEC='1',
 CDS_LIB='mstr_discrete',
 CDS_PART_NAME='RES_0402-4.75K,1%,1/16W,CHIP,GA',
 PRIM_FILE='./archive_libs/mstr_discrete/res/chips/chips.prt';

PART_NAME
 R6W5 'RES_0402-4.75K,1%,1/16W,CHIP,GA':
 ROOM='CPU_FANS';

SECTION_NUMBER 1
 '@BASEBOARD_FAB2_LIB.BASEBOARD_FAB2(SCH_1):PAGE247_I160@MSTR_DISCRETE.RES(CHIPS)':
 C_PATH='@baseboard_fab2_lib.baseboard_fab2(sch_1):page247_i160@mstr_discrete.re~
s(chips)',
 P_PATH='@baseboard_fab2_lib.baseboard_fab2(sch_1):page247_i160@mstr_discrete.re~
s(chips)',
 PATH='I160',
 DRAWING='@BASEBOARD_FAB2_LIB.BASEBOARD_FAB2(SCH_1):PAGE247',
 WATTAGE='1/16W',
 TOLERANCE='1%',
 SEC_TYPE='0402',
 MATERIAL='CHIP',
 BOM_COST='SM_THERM',
 PHYS_PAGE='247',
 XY='(-6250,4200)',
 ROT='2',
 VER='2',
 VALUE='4.75K',
 PACK_TYPE='0402',
 PART_NUMBER='G21796-072',
 LOCATION='R6W5',
 ROOM='CPU_FANS',
 SEC='1',
 CDS_LIB='mstr_discrete',
 CDS_PART_NAME='RES_0402-4.75K,1%,1/16W,CHIP,GA',
 PRIM_FILE='./archive_libs/mstr_discrete/res/chips/chips.prt';

PART_NAME
 R6W6 'RES_0402-4.75K,1%,1/16W,CHIP,GA':
 ROOM='CPU_FANS';

SECTION_NUMBER 1
 '@BASEBOARD_FAB2_LIB.BASEBOARD_FAB2(SCH_1):PAGE247_I161@MSTR_DISCRETE.RES(CHIPS)':
 C_PATH='@baseboard_fab2_lib.baseboard_fab2(sch_1):page247_i161@mstr_discrete.re~
s(chips)',
 P_PATH='@baseboard_fab2_lib.baseboard_fab2(sch_1):page247_i161@mstr_discrete.re~
s(chips)',
 PATH='I161',
 DRAWING='@BASEBOARD_FAB2_LIB.BASEBOARD_FAB2(SCH_1):PAGE247',
 WATTAGE='1/16W',
 TOLERANCE='1%',
 SEC_TYPE='0402',
 MATERIAL='CHIP',
 BOM_COST='SM_THERM',
 PHYS_PAGE='247',
 XY='(-5900,4200)',
 ROT='2',
 VER='2',
 VALUE='4.75K',
 PACK_TYPE='0402',
 PART_NUMBER='G21796-072',
 LOCATION='R6W6',
 ROOM='CPU_FANS',
 SEC='1',
 CDS_LIB='mstr_discrete',
 CDS_PART_NAME='RES_0402-4.75K,1%,1/16W,CHIP,GA',
 PRIM_FILE='./archive_libs/mstr_discrete/res/chips/chips.prt';

PART_NAME
 R6W7 'RES_0402-4.75K,1%,1/16W,EMPTY,A':
 ROOM='HOT_SWAP',
 NO_XNET_CONNECTION='1';

SECTION_NUMBER 1
 '@BASEBOARD_FAB2_LIB.BASEBOARD_FAB2(SCH_1):PAGE247_I164@MSTR_DISCRETE.RES(CHIPS)':
 C_PATH='@baseboard_fab2_lib.baseboard_fab2(sch_1):page247_i164@mstr_discrete.re~
s(chips)',
 P_PATH='@baseboard_fab2_lib.baseboard_fab2(sch_1):page247_i164@mstr_discrete.re~
s(chips)',
 PATH='I164',
 DRAWING='@BASEBOARD_FAB2_LIB.BASEBOARD_FAB2(SCH_1):PAGE247',
 WATTAGE='1/16W',
 TOLERANCE='1%',
 SEC_TYPE='0402',
 MATERIAL='EMPTY',
 NO_XNET_CONNECTION='1',
 PHYS_PAGE='247',
 XY='(-6600,3650)',
 ROT='0',
 VER='2',
 VALUE='4.75K',
 PACK_TYPE='0402',
 PART_NUMBER='G21796-072',
 LOCATION='R6W7',
 ROOM='HOT_SWAP',
 SEC='1',
 CDS_LIB='mstr_discrete',
 CDS_PART_NAME='RES_0402-4.75K,1%,1/16W,EMPTY,A',
 PRIM_FILE='./archive_libs/mstr_discrete/res/chips/chips.prt';

PART_NAME
 R6W8 'RES_0402-4.75K,1%,1/16W,EMPTY,A':
 ROOM='HOT_SWAP',
 NO_XNET_CONNECTION='1';

SECTION_NUMBER 1
 '@BASEBOARD_FAB2_LIB.BASEBOARD_FAB2(SCH_1):PAGE247_I163@MSTR_DISCRETE.RES(CHIPS)':
 C_PATH='@baseboard_fab2_lib.baseboard_fab2(sch_1):page247_i163@mstr_discrete.re~
s(chips)',
 P_PATH='@baseboard_fab2_lib.baseboard_fab2(sch_1):page247_i163@mstr_discrete.re~
s(chips)',
 PATH='I163',
 DRAWING='@BASEBOARD_FAB2_LIB.BASEBOARD_FAB2(SCH_1):PAGE247',
 WATTAGE='1/16W',
 TOLERANCE='1%',
 SEC_TYPE='0402',
 MATERIAL='EMPTY',
 NO_XNET_CONNECTION='1',
 PHYS_PAGE='247',
 XY='(-6250,3650)',
 ROT='0',
 VER='2',
 VALUE='4.75K',
 PACK_TYPE='0402',
 PART_NUMBER='G21796-072',
 LOCATION='R6W8',
 ROOM='HOT_SWAP',
 SEC='1',
 CDS_LIB='mstr_discrete',
 CDS_PART_NAME='RES_0402-4.75K,1%,1/16W,EMPTY,A',
 PRIM_FILE='./archive_libs/mstr_discrete/res/chips/chips.prt';

PART_NAME
 R6W9 'RES_0402-4.75K,1%,1/16W,EMPTY,A':
 ROOM='HOT_SWAP',
 NO_XNET_CONNECTION='1';

SECTION_NUMBER 1
 '@BASEBOARD_FAB2_LIB.BASEBOARD_FAB2(SCH_1):PAGE247_I162@MSTR_DISCRETE.RES(CHIPS)':
 C_PATH='@baseboard_fab2_lib.baseboard_fab2(sch_1):page247_i162@mstr_discrete.re~
s(chips)',
 P_PATH='@baseboard_fab2_lib.baseboard_fab2(sch_1):page247_i162@mstr_discrete.re~
s(chips)',
 PATH='I162',
 DRAWING='@BASEBOARD_FAB2_LIB.BASEBOARD_FAB2(SCH_1):PAGE247',
 WATTAGE='1/16W',
 TOLERANCE='1%',
 SEC_TYPE='0402',
 MATERIAL='EMPTY',
 NO_XNET_CONNECTION='1',
 PHYS_PAGE='247',
 XY='(-5900,3650)',
 ROT='0',
 VER='2',
 VALUE='4.75K',
 PACK_TYPE='0402',
 PART_NUMBER='G21796-072',
 LOCATION='R6W9',
 ROOM='HOT_SWAP',
 SEC='1',
 CDS_LIB='mstr_discrete',
 CDS_PART_NAME='RES_0402-4.75K,1%,1/16W,EMPTY,A',
 PRIM_FILE='./archive_libs/mstr_discrete/res/chips/chips.prt';

PART_NAME
 R6W10 'RES_0402-4.75K,1%,1/16W,CHIP,GA':
 ROOM='CPU_FANS';

SECTION_NUMBER 1
 '@BASEBOARD_FAB2_LIB.BASEBOARD_FAB2(SCH_1):PAGE247_I1@MSTR_DISCRETE.RES(CHIPS)':
 C_PATH='@baseboard_fab2_lib.baseboard_fab2(sch_1):page247_i1@mstr_discrete.res(~
chips)',
 P_PATH='@baseboard_fab2_lib.baseboard_fab2(sch_1):page247_i1@mstr_discrete.res(~
chips)',
 PATH='I1',
 DRAWING='@BASEBOARD_FAB2_LIB.BASEBOARD_FAB2(SCH_1):PAGE247',
 WATTAGE='1/16W',
 TOLERANCE='1%',
 SEC_TYPE='0402',
 MATERIAL='CHIP',
 BOM_COST='SM_THERM',
 PHYS_PAGE='247',
 XY='(-7450,3350)',
 ROT='2',
 VER='2',
 VALUE='4.75K',
 PACK_TYPE='0402',
 PART_NUMBER='G21796-072',
 LOCATION='R6W10',
 ROOM='CPU_FANS',
 SEC='1',
 CDS_LIB='mstr_discrete',
 CDS_PART_NAME='RES_0402-4.75K,1%,1/16W,CHIP,GA',
 PRIM_FILE='./archive_libs/mstr_discrete/res/chips/chips.prt';

PART_NAME
 R6W11 'RES_0402-4.75K,1%,1/16W,CHIP,GA':;

SECTION_NUMBER 1
 '@BASEBOARD_FAB2_LIB.BASEBOARD_FAB2(SCH_1):PAGE247_I98@MSTR_DISCRETE.RES(CHIPS)':
 C_PATH='@baseboard_fab2_lib.baseboard_fab2(sch_1):page247_i98@mstr_discrete.res~
(chips)',
 P_PATH='@baseboard_fab2_lib.baseboard_fab2(sch_1):page247_i98@mstr_discrete.res~
(chips)',
 PATH='I98',
 DRAWING='@BASEBOARD_FAB2_LIB.BASEBOARD_FAB2(SCH_1):PAGE247',
 WATTAGE='1/16W',
 TOLERANCE='1%',
 SEC_TYPE='0402',
 MATERIAL='CHIP',
 PHYS_PAGE='247',
 XY='(-7350,3350)',
 ROT='1',
 VER='1',
 VALUE='4.75K',
 PACK_TYPE='0402',
 PART_NUMBER='G21796-072',
 LOCATION='R6W11',
 SEC='1',
 CDS_LIB='mstr_discrete',
 CDS_PART_NAME='RES_0402-4.75K,1%,1/16W,CHIP,GA',
 PRIM_FILE='./archive_libs/mstr_discrete/res/chips/chips.prt';

PART_NAME
 R6W12 'RES_0402-4.75K,1%,1/16W,CHIP,GA':;

SECTION_NUMBER 1
 '@BASEBOARD_FAB2_LIB.BASEBOARD_FAB2(SCH_1):PAGE247_I99@MSTR_DISCRETE.RES(CHIPS)':
 C_PATH='@baseboard_fab2_lib.baseboard_fab2(sch_1):page247_i99@mstr_discrete.res~
(chips)',
 P_PATH='@baseboard_fab2_lib.baseboard_fab2(sch_1):page247_i99@mstr_discrete.res~
(chips)',
 PATH='I99',
 DRAWING='@BASEBOARD_FAB2_LIB.BASEBOARD_FAB2(SCH_1):PAGE247',
 WATTAGE='1/16W',
 TOLERANCE='1%',
 SEC_TYPE='0402',
 MATERIAL='CHIP',
 PHYS_PAGE='247',
 XY='(-7050,3350)',
 ROT='1',
 VER='1',
 VALUE='4.75K',
 PACK_TYPE='0402',
 PART_NUMBER='G21796-072',
 LOCATION='R6W12',
 SEC='1',
 CDS_LIB='mstr_discrete',
 CDS_PART_NAME='RES_0402-4.75K,1%,1/16W,CHIP,GA',
 PRIM_FILE='./archive_libs/mstr_discrete/res/chips/chips.prt';

PART_NAME
 R6W16 'RES_0402-1.00K,1%,1/16W,CHIP,GA':
 ROOM='UART_MUX';

SECTION_NUMBER 1
 '@BASEBOARD_FAB2_LIB.BASEBOARD_FAB2(SCH_1):PAGE168_I46@MSTR_DISCRETE.RES(CHIPS)':
 C_PATH='@baseboard_fab2_lib.baseboard_fab2(sch_1):page168_i46@mstr_discrete.res~
(chips)',
 P_PATH='@baseboard_fab2_lib.baseboard_fab2(sch_1):page168_i46@mstr_discrete.res~
(chips)',
 PATH='I46',
 DRAWING='@BASEBOARD_FAB2_LIB.BASEBOARD_FAB2(SCH_1):PAGE168',
 WATTAGE='1/16W',
 TOLERANCE='1%',
 SEC_TYPE='0402',
 MATERIAL='CHIP',
 BOM_COST='DEBUG',
 PHYS_PAGE='168',
 XY='(-3950,2100)',
 ROT='0',
 VER='2',
 VALUE='1.00K',
 PACK_TYPE='0402',
 PART_NUMBER='G21796-026',
 LOCATION='R6W16',
 ROOM='UART_MUX',
 SEC='1',
 CDS_LIB='mstr_discrete',
 CDS_PART_NAME='RES_0402-1.00K,1%,1/16W,CHIP,GA',
 PRIM_FILE='./archive_libs/mstr_discrete/res/chips/chips.prt';

PART_NAME
 R6W17 'RES_0402-0.0,5%,1/16W,CHIP,G21A':
 ROOM='USB';

SECTION_NUMBER 1
 '@BASEBOARD_FAB2_LIB.BASEBOARD_FAB2(SCH_1):PAGE145_I120@MSTR_DISCRETE.RES(CHIPS)':
 C_PATH='@baseboard_fab2_lib.baseboard_fab2(sch_1):page145_i120@mstr_discrete.re~
s(chips)',
 P_PATH='@baseboard_fab2_lib.baseboard_fab2(sch_1):page145_i120@mstr_discrete.re~
s(chips)',
 PATH='I120',
 DRAWING='@BASEBOARD_FAB2_LIB.BASEBOARD_FAB2(SCH_1):PAGE145',
 WATTAGE='1/16W',
 TOLERANCE='5%',
 SEC_TYPE='0402',
 MATERIAL='CHIP',
 BOM_COST='MIO_USB',
 PHYS_PAGE='145',
 XY='(-6450,-2350)',
 ROT='0',
 VER='1',
 VALUE='0.0',
 PACK_TYPE='0402',
 PART_NUMBER='G21497-005',
 LOCATION='R6W17',
 ROOM='USB',
 SEC='1',
 CDS_LIB='mstr_discrete',
 CDS_PART_NAME='RES_0402-0.0,5%,1/16W,CHIP,G21A',
 PRIM_FILE='./archive_libs/mstr_discrete/res/chips/chips.prt';

PART_NAME
 R6W18 'RES_0402-0.0,5%,1/16W,CHIP,G21A':
 ROOM='USB';

SECTION_NUMBER 1
 '@BASEBOARD_FAB2_LIB.BASEBOARD_FAB2(SCH_1):PAGE145_I119@MSTR_DISCRETE.RES(CHIPS)':
 C_PATH='@baseboard_fab2_lib.baseboard_fab2(sch_1):page145_i119@mstr_discrete.re~
s(chips)',
 P_PATH='@baseboard_fab2_lib.baseboard_fab2(sch_1):page145_i119@mstr_discrete.re~
s(chips)',
 PATH='I119',
 DRAWING='@BASEBOARD_FAB2_LIB.BASEBOARD_FAB2(SCH_1):PAGE145',
 WATTAGE='1/16W',
 TOLERANCE='5%',
 SEC_TYPE='0402',
 MATERIAL='CHIP',
 BOM_COST='MIO_USB',
 PHYS_PAGE='145',
 XY='(-6450,-2300)',
 ROT='0',
 VER='1',
 VALUE='0.0',
 PACK_TYPE='0402',
 PART_NUMBER='G21497-005',
 LOCATION='R6W18',
 ROOM='USB',
 SEC='1',
 CDS_LIB='mstr_discrete',
 CDS_PART_NAME='RES_0402-0.0,5%,1/16W,CHIP,G21A',
 PRIM_FILE='./archive_libs/mstr_discrete/res/chips/chips.prt';

PART_NAME
 R6W19 'RES_0402-0.0,5%,1/16W,CHIP,G21A':
 ROOM='BMC_DEBUG_HEADER';

SECTION_NUMBER 1
 '@BASEBOARD_FAB2_LIB.BASEBOARD_FAB2(SCH_1):PAGE155_I196@MSTR_DISCRETE.RES(CHIPS)':
 C_PATH='@baseboard_fab2_lib.baseboard_fab2(sch_1):page155_i196@mstr_discrete.re~
s(chips)',
 P_PATH='@baseboard_fab2_lib.baseboard_fab2(sch_1):page155_i196@mstr_discrete.re~
s(chips)',
 PATH='I196',
 DRAWING='@BASEBOARD_FAB2_LIB.BASEBOARD_FAB2(SCH_1):PAGE155',
 POP='NOPOP',
 WATTAGE='1/16W',
 TOLERANCE='5%',
 SEC_TYPE='0402',
 MATERIAL='CHIP',
 BOM_COST='DEBUG',
 PHYS_PAGE='155',
 XY='(-1950,1775)',
 ROT='0',
 VER='1',
 VALUE='0.0',
 PACK_TYPE='0402',
 PART_NUMBER='G21497-005',
 LOCATION='R6W19',
 ROOM='BMC_DEBUG_HEADER',
 SEC='1',
 CDS_LIB='mstr_discrete',
 CDS_PART_NAME='RES_0402-0.0,5%,1/16W,CHIP,G21A',
 PRIM_FILE='./archive_libs/mstr_discrete/res/chips/chips.prt';

PART_NAME
 R6W20 'RES_0402-20.0,1%,1/16W,CHIP,G2A':
 ROOM='TEMP_SENSORS';

SECTION_NUMBER 1
 '@BASEBOARD_FAB2_LIB.BASEBOARD_FAB2(SCH_1):PAGE247_I87@MSTR_DISCRETE.RES(CHIPS)':
 C_PATH='@baseboard_fab2_lib.baseboard_fab2(sch_1):page247_i87@mstr_discrete.res~
(chips)',
 P_PATH='@baseboard_fab2_lib.baseboard_fab2(sch_1):page247_i87@mstr_discrete.res~
(chips)',
 PATH='I87',
 DRAWING='@BASEBOARD_FAB2_LIB.BASEBOARD_FAB2(SCH_1):PAGE247',
 WATTAGE='1/16W',
 TOLERANCE='1%',
 SEC_TYPE='0402',
 MATERIAL='CHIP',
 BOM_COST='SM_THERM',
 PHYS_PAGE='247',
 XY='(-1025,1750)',
 ROT='0',
 VER='1',
 VALUE='20.0',
 PACK_TYPE='0402',
 PART_NUMBER='G21796-173',
 LOCATION='R6W20',
 ROOM='TEMP_SENSORS',
 SEC='1',
 CDS_LIB='mstr_discrete',
 CDS_PART_NAME='RES_0402-20.0,1%,1/16W,CHIP,G2A',
 PRIM_FILE='./archive_libs/mstr_discrete/res/chips/chips.prt';

PART_NAME
 R6W21 'RES_0402-1.00K,1%,1/16W,CHIP,GA':
 ROOM='TEMP_SENSORS';

SECTION_NUMBER 1
 '@BASEBOARD_FAB2_LIB.BASEBOARD_FAB2(SCH_1):PAGE247_I90@MSTR_DISCRETE.RES(CHIPS)':
 C_PATH='@baseboard_fab2_lib.baseboard_fab2(sch_1):page247_i90@mstr_discrete.res~
(chips)',
 P_PATH='@baseboard_fab2_lib.baseboard_fab2(sch_1):page247_i90@mstr_discrete.res~
(chips)',
 PATH='I90',
 DRAWING='@BASEBOARD_FAB2_LIB.BASEBOARD_FAB2(SCH_1):PAGE247',
 WATTAGE='1/16W',
 TOLERANCE='1%',
 SEC_TYPE='0402',
 MATERIAL='CHIP',
 BOM_COST='SM_THERM',
 PHYS_PAGE='247',
 XY='(-3200,2200)',
 ROT='0',
 VER='2',
 VALUE='1.00K',
 PACK_TYPE='0402',
 PART_NUMBER='G21796-026',
 LOCATION='R6W21',
 ROOM='TEMP_SENSORS',
 SEC='1',
 CDS_LIB='mstr_discrete',
 CDS_PART_NAME='RES_0402-1.00K,1%,1/16W,CHIP,GA',
 PRIM_FILE='./archive_libs/mstr_discrete/res/chips/chips.prt';

PART_NAME
 R6W22 'RES_0402-20.0,1%,1/16W,CHIP,G2A':
 ROOM='TEMP_SENSORS';

SECTION_NUMBER 1
 '@BASEBOARD_FAB2_LIB.BASEBOARD_FAB2(SCH_1):PAGE247_I94@MSTR_DISCRETE.RES(CHIPS)':
 C_PATH='@baseboard_fab2_lib.baseboard_fab2(sch_1):page247_i94@mstr_discrete.res~
(chips)',
 P_PATH='@baseboard_fab2_lib.baseboard_fab2(sch_1):page247_i94@mstr_discrete.res~
(chips)',
 PATH='I94',
 DRAWING='@BASEBOARD_FAB2_LIB.BASEBOARD_FAB2(SCH_1):PAGE247',
 WATTAGE='1/16W',
 TOLERANCE='1%',
 SEC_TYPE='0402',
 MATERIAL='CHIP',
 BOM_COST='SM_THERM',
 PHYS_PAGE='247',
 XY='(-3425,1750)',
 ROT='0',
 VER='1',
 VALUE='20.0',
 PACK_TYPE='0402',
 PART_NUMBER='G21796-173',
 LOCATION='R6W22',
 ROOM='TEMP_SENSORS',
 SEC='1',
 CDS_LIB='mstr_discrete',
 CDS_PART_NAME='RES_0402-20.0,1%,1/16W,CHIP,G2A',
 PRIM_FILE='./archive_libs/mstr_discrete/res/chips/chips.prt';

PART_NAME
 R6W23 'RES_0402-1.00K,1%,1/16W,CHIP,GA':
 ROOM='TEMP_SENSORS';

SECTION_NUMBER 1
 '@BASEBOARD_FAB2_LIB.BASEBOARD_FAB2(SCH_1):PAGE247_I92@MSTR_DISCRETE.RES(CHIPS)':
 C_PATH='@baseboard_fab2_lib.baseboard_fab2(sch_1):page247_i92@mstr_discrete.res~
(chips)',
 P_PATH='@baseboard_fab2_lib.baseboard_fab2(sch_1):page247_i92@mstr_discrete.res~
(chips)',
 PATH='I92',
 DRAWING='@BASEBOARD_FAB2_LIB.BASEBOARD_FAB2(SCH_1):PAGE247',
 WATTAGE='1/16W',
 TOLERANCE='1%',
 SEC_TYPE='0402',
 MATERIAL='CHIP',
 BOM_COST='SM_THERM',
 PHYS_PAGE='247',
 XY='(-3200,1500)',
 ROT='0',
 VER='2',
 VALUE='1.00K',
 PACK_TYPE='0402',
 PART_NUMBER='G21796-026',
 LOCATION='R6W23',
 ROOM='TEMP_SENSORS',
 SEC='1',
 CDS_LIB='mstr_discrete',
 CDS_PART_NAME='RES_0402-1.00K,1%,1/16W,CHIP,GA',
 PRIM_FILE='./archive_libs/mstr_discrete/res/chips/chips.prt';

PART_NAME
 R6W24 'RES_0402-4.75K,1%,1/16W,CHIP,GA':
 ROOM='CPU_FANS';

SECTION_NUMBER 1
 '@BASEBOARD_FAB2_LIB.BASEBOARD_FAB2(SCH_1):PAGE247_I100@MSTR_DISCRETE.RES(CHIPS)':
 C_PATH='@baseboard_fab2_lib.baseboard_fab2(sch_1):page247_i100@mstr_discrete.re~
s(chips)',
 P_PATH='@baseboard_fab2_lib.baseboard_fab2(sch_1):page247_i100@mstr_discrete.re~
s(chips)',
 PATH='I100',
 DRAWING='@BASEBOARD_FAB2_LIB.BASEBOARD_FAB2(SCH_1):PAGE247',
 WATTAGE='1/16W',
 TOLERANCE='1%',
 SEC_TYPE='0402',
 MATERIAL='CHIP',
 BOM_COST='SM_THERM',
 PHYS_PAGE='247',
 XY='(-7550,1950)',
 ROT='2',
 VER='2',
 VALUE='4.75K',
 PACK_TYPE='0402',
 PART_NUMBER='G21796-072',
 LOCATION='R6W24',
 ROOM='CPU_FANS',
 SEC='1',
 CDS_LIB='mstr_discrete',
 CDS_PART_NAME='RES_0402-4.75K,1%,1/16W,CHIP,GA',
 PRIM_FILE='./archive_libs/mstr_discrete/res/chips/chips.prt';

PART_NAME
 R6W25 'RES_0402-4.75K,1%,1/16W,CHIP,GA':
 ROOM='CPU_FANS';

SECTION_NUMBER 1
 '@BASEBOARD_FAB2_LIB.BASEBOARD_FAB2(SCH_1):PAGE247_I101@MSTR_DISCRETE.RES(CHIPS)':
 C_PATH='@baseboard_fab2_lib.baseboard_fab2(sch_1):page247_i101@mstr_discrete.re~
s(chips)',
 P_PATH='@baseboard_fab2_lib.baseboard_fab2(sch_1):page247_i101@mstr_discrete.re~
s(chips)',
 PATH='I101',
 DRAWING='@BASEBOARD_FAB2_LIB.BASEBOARD_FAB2(SCH_1):PAGE247',
 WATTAGE='1/16W',
 TOLERANCE='1%',
 SEC_TYPE='0402',
 MATERIAL='CHIP',
 BOM_COST='SM_THERM',
 PHYS_PAGE='247',
 XY='(-7200,1950)',
 ROT='2',
 VER='2',
 VALUE='4.75K',
 PACK_TYPE='0402',
 PART_NUMBER='G21796-072',
 LOCATION='R6W25',
 ROOM='CPU_FANS',
 SEC='1',
 CDS_LIB='mstr_discrete',
 CDS_PART_NAME='RES_0402-4.75K,1%,1/16W,CHIP,GA',
 PRIM_FILE='./archive_libs/mstr_discrete/res/chips/chips.prt';

PART_NAME
 R6W26 'RES_0402-10.0,1%,1/16W,CHIP,G2A':
 ROOM='CPU1';

SECTION_NUMBER 1
 '@BASEBOARD_FAB2_LIB.BASEBOARD_FAB2(SCH_1):PAGE248_I24@MSTR_DISCRETE.RES(CHIPS)':
 C_PATH='@baseboard_fab2_lib.baseboard_fab2(sch_1):page248_i24@mstr_discrete.res~
(chips)',
 P_PATH='@baseboard_fab2_lib.baseboard_fab2(sch_1):page248_i24@mstr_discrete.res~
(chips)',
 PATH='I24',
 DRAWING='@BASEBOARD_FAB2_LIB.BASEBOARD_FAB2(SCH_1):PAGE248',
 WATTAGE='1/16W',
 TOLERANCE='1%',
 SEC_TYPE='0402',
 MATERIAL='CHIP',
 PHYS_PAGE='248',
 XY='(-6250,3525)',
 ROT='0',
 VER='1',
 VALUE='10.0',
 PACK_TYPE='0402',
 PART_NUMBER='G21796-066',
 LOCATION='R6W26',
 ROOM='CPU1',
 SEC='1',
 CDS_LIB='mstr_discrete',
 CDS_PART_NAME='RES_0402-10.0,1%,1/16W,CHIP,G2A',
 PRIM_FILE='./archive_libs/mstr_discrete/res/chips/chips.prt';

PART_NAME
 R6W27 'RES_0402-10.0,1%,1/16W,CHIP,G2A':
 ROOM='CPU1';

SECTION_NUMBER 1
 '@BASEBOARD_FAB2_LIB.BASEBOARD_FAB2(SCH_1):PAGE248_I25@MSTR_DISCRETE.RES(CHIPS)':
 C_PATH='@baseboard_fab2_lib.baseboard_fab2(sch_1):page248_i25@mstr_discrete.res~
(chips)',
 P_PATH='@baseboard_fab2_lib.baseboard_fab2(sch_1):page248_i25@mstr_discrete.res~
(chips)',
 PATH='I25',
 DRAWING='@BASEBOARD_FAB2_LIB.BASEBOARD_FAB2(SCH_1):PAGE248',
 WATTAGE='1/16W',
 TOLERANCE='1%',
 SEC_TYPE='0402',
 MATERIAL='CHIP',
 PHYS_PAGE='248',
 XY='(-5900,3475)',
 ROT='0',
 VER='1',
 VALUE='10.0',
 PACK_TYPE='0402',
 PART_NUMBER='G21796-066',
 LOCATION='R6W27',
 ROOM='CPU1',
 SEC='1',
 CDS_LIB='mstr_discrete',
 CDS_PART_NAME='RES_0402-10.0,1%,1/16W,CHIP,G2A',
 PRIM_FILE='./archive_libs/mstr_discrete/res/chips/chips.prt';

PART_NAME
 R6W28 'RES_0402-4.75K,1%,1/16W,CHIP,GA':
 ROOM='CPU_FANS';

SECTION_NUMBER 1
 '@BASEBOARD_FAB2_LIB.BASEBOARD_FAB2(SCH_1):PAGE247_I112@MSTR_DISCRETE.RES(CHIPS)':
 C_PATH='@baseboard_fab2_lib.baseboard_fab2(sch_1):page247_i112@mstr_discrete.re~
s(chips)',
 P_PATH='@baseboard_fab2_lib.baseboard_fab2(sch_1):page247_i112@mstr_discrete.re~
s(chips)',
 PATH='I112',
 DRAWING='@BASEBOARD_FAB2_LIB.BASEBOARD_FAB2(SCH_1):PAGE247',
 WATTAGE='1/16W',
 TOLERANCE='1%',
 SEC_TYPE='0402',
 MATERIAL='CHIP',
 BOM_COST='SM_THERM',
 PHYS_PAGE='247',
 XY='(-6850,1950)',
 ROT='2',
 VER='2',
 VALUE='4.75K',
 PACK_TYPE='0402',
 PART_NUMBER='G21796-072',
 LOCATION='R6W28',
 ROOM='CPU_FANS',
 SEC='1',
 CDS_LIB='mstr_discrete',
 CDS_PART_NAME='RES_0402-4.75K,1%,1/16W,CHIP,GA',
 PRIM_FILE='./archive_libs/mstr_discrete/res/chips/chips.prt';

PART_NAME
 R6W29 'RES_0402-10.0K,1%,1/16W,CHIP,GA':
 ROOM='NV_DIMM';

SECTION_NUMBER 1
 '@BASEBOARD_FAB2_LIB.BASEBOARD_FAB2(SCH_1):PAGE89_I40@MSTR_DISCRETE.RES(CHIPS)':
 C_PATH='@baseboard_fab2_lib.baseboard_fab2(sch_1):page89_i40@mstr_discrete.res(~
chips)',
 P_PATH='@baseboard_fab2_lib.baseboard_fab2(sch_1):page89_i40@mstr_discrete.res(~
chips)',
 PATH='I40',
 DRAWING='@BASEBOARD_FAB2_LIB.BASEBOARD_FAB2(SCH_1):PAGE89',
 WATTAGE='1/16W',
 TOLERANCE='1%',
 SEC_TYPE='0402',
 MATERIAL='CHIP',
 BOM_COST='MEM_NV',
 PHYS_PAGE='89',
 XY='(-450,2175)',
 ROT='0',
 VER='2',
 VALUE='10.0K',
 PACK_TYPE='0402',
 PART_NUMBER='G21796-016',
 LOCATION='R6W29',
 ROOM='NV_DIMM',
 SEC='1',
 CDS_LIB='mstr_discrete',
 CDS_PART_NAME='RES_0402-10.0K,1%,1/16W,CHIP,GA',
 PRIM_FILE='./archive_libs/mstr_discrete/res/chips/chips.prt';

PART_NAME
 R6W30 'RES_0603-100.0K,1%,1/10W,CHIP,A':
 ROOM='CPU0';

SECTION_NUMBER 1
 '@BASEBOARD_FAB2_LIB.BASEBOARD_FAB2(SCH_1):PAGE176_I147@MSTR_DISCRETE.RES(CHIPS)':
 C_PATH='@baseboard_fab2_lib.baseboard_fab2(sch_1):page176_i147@mstr_discrete.re~
s(chips)',
 P_PATH='@baseboard_fab2_lib.baseboard_fab2(sch_1):page176_i147@mstr_discrete.re~
s(chips)',
 PATH='I147',
 DRAWING='@BASEBOARD_FAB2_LIB.BASEBOARD_FAB2(SCH_1):PAGE176',
 WATTAGE='1/10W',
 TOLERANCE='1%',
 SEC_TYPE='0603',
 MATERIAL='CHIP',
 BOM_COST='PROC_SOCKET',
 PHYS_PAGE='176',
 XY='(-1550,1600)',
 ROT='0',
 VER='2',
 VALUE='100.0K',
 PACK_TYPE='0603',
 PART_NUMBER='G22026-050',
 LOCATION='R6W30',
 ROOM='CPU0',
 SEC='1',
 CDS_LIB='mstr_discrete',
 CDS_PART_NAME='RES_0603-100.0K,1%,1/10W,CHIP,A',
 PRIM_FILE='./archive_libs/mstr_discrete/res/chips/chips.prt';

PART_NAME
 R6W35 'RES_0402-100.0K,1%,1/16W,CHIP,A':
 ROOM='HOT_SWAP';

SECTION_NUMBER 1
 '@BASEBOARD_FAB2_LIB.BASEBOARD_FAB2(SCH_1):PAGE247_I165@MSTR_DISCRETE.RES(CHIPS)':
 C_PATH='@baseboard_fab2_lib.baseboard_fab2(sch_1):page247_i165@mstr_discrete.re~
s(chips)',
 P_PATH='@baseboard_fab2_lib.baseboard_fab2(sch_1):page247_i165@mstr_discrete.re~
s(chips)',
 PATH='I165',
 DRAWING='@BASEBOARD_FAB2_LIB.BASEBOARD_FAB2(SCH_1):PAGE247',
 WATTAGE='1/16W',
 TOLERANCE='1%',
 SEC_TYPE='0402',
 MATERIAL='CHIP',
 PHYS_PAGE='247',
 XY='(-1750,3750)',
 ROT='2',
 VER='2',
 VALUE='100.0K',
 PACK_TYPE='0402',
 PART_NUMBER='G21796-010',
 LOCATION='R6W35',
 ROOM='HOT_SWAP',
 SEC='1',
 CDS_LIB='mstr_discrete',
 CDS_PART_NAME='RES_0402-100.0K,1%,1/16W,CHIP,A',
 PRIM_FILE='./archive_libs/mstr_discrete/res/chips/chips.prt';

PART_NAME
 R6W36 'RES_0402-10.0,1%,1/16W,CHIP,G2A':
 ROOM='MEM';

SECTION_NUMBER 1
 '@BASEBOARD_FAB2_LIB.BASEBOARD_FAB2(SCH_1):PAGE176_I161@MSTR_DISCRETE.RES(CHIPS)':
 C_PATH='@baseboard_fab2_lib.baseboard_fab2(sch_1):page176_i161@mstr_discrete.re~
s(chips)',
 P_PATH='@baseboard_fab2_lib.baseboard_fab2(sch_1):page176_i161@mstr_discrete.re~
s(chips)',
 PATH='I161',
 DRAWING='@BASEBOARD_FAB2_LIB.BASEBOARD_FAB2(SCH_1):PAGE176',
 WATTAGE='1/16W',
 TOLERANCE='1%',
 MATERIAL='CHIP',
 BOM_COST='SM_CONTROLLER',
 PHYS_PAGE='176',
 XY='(-725,2600)',
 ROT='0',
 VER='1',
 VALUE='10.0',
 PACK_TYPE='0402',
 PART_NUMBER='G21796-066',
 LOCATION='R6W36',
 ROOM='MEM',
 CDS_LIB='mstr_discrete',
 CDS_PART_NAME='RES_0402-10.0,1%,1/16W,CHIP,G2A',
 PRIM_FILE='./archive_libs/mstr_discrete/res/chips/chips.prt';

PART_NAME
 R6W37 'RES_0402-10.0,1%,1/16W,CHIP,G2A':
 ROOM='MEM';

SECTION_NUMBER 1
 '@BASEBOARD_FAB2_LIB.BASEBOARD_FAB2(SCH_1):PAGE176_I160@MSTR_DISCRETE.RES(CHIPS)':
 C_PATH='@baseboard_fab2_lib.baseboard_fab2(sch_1):page176_i160@mstr_discrete.re~
s(chips)',
 P_PATH='@baseboard_fab2_lib.baseboard_fab2(sch_1):page176_i160@mstr_discrete.re~
s(chips)',
 PATH='I160',
 DRAWING='@BASEBOARD_FAB2_LIB.BASEBOARD_FAB2(SCH_1):PAGE176',
 WATTAGE='1/16W',
 TOLERANCE='1%',
 MATERIAL='CHIP',
 BOM_COST='SM_CONTROLLER',
 PHYS_PAGE='176',
 XY='(-700,3150)',
 ROT='0',
 VER='1',
 VALUE='10.0',
 PACK_TYPE='0402',
 PART_NUMBER='G21796-066',
 LOCATION='R6W37',
 ROOM='MEM',
 CDS_LIB='mstr_discrete',
 CDS_PART_NAME='RES_0402-10.0,1%,1/16W,CHIP,G2A',
 PRIM_FILE='./archive_libs/mstr_discrete/res/chips/chips.prt';

PART_NAME
 R6W38 'RES_0402-20.0K,1%,1/16W,CHIP,GA':
 ROOM='SB';

SECTION_NUMBER 1
 '@BASEBOARD_FAB2_LIB.BASEBOARD_FAB2(SCH_1):PAGE176_I156@MSTR_DISCRETE.RES(CHIPS)':
 C_PATH='@baseboard_fab2_lib.baseboard_fab2(sch_1):page176_i156@mstr_discrete.re~
s(chips)',
 P_PATH='@baseboard_fab2_lib.baseboard_fab2(sch_1):page176_i156@mstr_discrete.re~
s(chips)',
 PATH='I156',
 DRAWING='@BASEBOARD_FAB2_LIB.BASEBOARD_FAB2(SCH_1):PAGE176',
 WATTAGE='1/16W',
 TOLERANCE='1%',
 SEC_TYPE='0402',
 MATERIAL='CHIP',
 BOM_COST='SB',
 PHYS_PAGE='176',
 XY='(-1250,3525)',
 ROT='1',
 VER='2',
 VALUE='20.0K',
 PACK_TYPE='0402',
 PART_NUMBER='G21796-040',
 LOCATION='R6W38',
 ROOM='SB',
 SEC='1',
 CDS_LIB='mstr_discrete',
 CDS_PART_NAME='RES_0402-20.0K,1%,1/16W,CHIP,GA',
 PRIM_FILE='./archive_libs/mstr_discrete/res/chips/chips.prt';

PART_NAME
 R6W39 'RES_0402-10.0K,1%,1/16W,CHIP,GA':
 ROOM='USB_REAR';

SECTION_NUMBER 1
 '@BASEBOARD_FAB2_LIB.BASEBOARD_FAB2(SCH_1):PAGE176_I158@MSTR_DISCRETE.RES(CHIPS)':
 C_PATH='@baseboard_fab2_lib.baseboard_fab2(sch_1):page176_i158@mstr_discrete.re~
s(chips)',
 P_PATH='@baseboard_fab2_lib.baseboard_fab2(sch_1):page176_i158@mstr_discrete.re~
s(chips)',
 PATH='I158',
 DRAWING='@BASEBOARD_FAB2_LIB.BASEBOARD_FAB2(SCH_1):PAGE176',
 WATTAGE='1/16W',
 TOLERANCE='1%',
 SEC_TYPE='0402',
 MATERIAL='CHIP',
 BOM_COST='MIO_USB',
 PHYS_PAGE='176',
 XY='(-1300,2950)',
 ROT='1',
 VER='2',
 VALUE='10.0K',
 PACK_TYPE='0402',
 PART_NUMBER='G21796-016',
 LOCATION='R6W39',
 ROOM='USB_REAR',
 SEC='1',
 CDS_LIB='mstr_discrete',
 CDS_PART_NAME='RES_0402-10.0K,1%,1/16W,CHIP,GA',
 PRIM_FILE='./archive_libs/mstr_discrete/res/chips/chips.prt';

PART_NAME
 R6W40 'RES_0402-10.0K,1%,1/16W,CHIP,GA':
 ROOM='CPU0';

SECTION_NUMBER 1
 '@BASEBOARD_FAB2_LIB.BASEBOARD_FAB2(SCH_1):PAGE155_I201@MSTR_DISCRETE.RES(CHIPS)':
 C_PATH='@baseboard_fab2_lib.baseboard_fab2(sch_1):page155_i201@mstr_discrete.re~
s(chips)',
 P_PATH='@baseboard_fab2_lib.baseboard_fab2(sch_1):page155_i201@mstr_discrete.re~
s(chips)',
 PATH='I201',
 DRAWING='@BASEBOARD_FAB2_LIB.BASEBOARD_FAB2(SCH_1):PAGE155',
 WATTAGE='1/16W',
 TOLERANCE='1%',
 SEC_TYPE='0402',
 MATERIAL='CHIP',
 BOM_COST='PROC_SIDEBAND',
 PHYS_PAGE='155',
 XY='(-2700,1700)',
 ROT='0',
 VER='2',
 VALUE='10.0K',
 PACK_TYPE='0402',
 PART_NUMBER='G21796-016',
 LOCATION='R6W40',
 ROOM='CPU0',
 SEC='1',
 CDS_LIB='mstr_discrete',
 CDS_PART_NAME='RES_0402-10.0K,1%,1/16W,CHIP,GA',
 PRIM_FILE='./archive_libs/mstr_discrete/res/chips/chips.prt';

PART_NAME
 R6W41 'RES_0402-4.75K,1%,1/16W,CHIP,GA':
 ROOM='CPU_FANS';

SECTION_NUMBER 1
 '@BASEBOARD_FAB2_LIB.BASEBOARD_FAB2(SCH_1):PAGE164_I87@MSTR_DISCRETE.RES(CHIPS)':
 C_PATH='@baseboard_fab2_lib.baseboard_fab2(sch_1):page164_i87@mstr_discrete.res~
(chips)',
 P_PATH='@baseboard_fab2_lib.baseboard_fab2(sch_1):page164_i87@mstr_discrete.res~
(chips)',
 PATH='I87',
 DRAWING='@BASEBOARD_FAB2_LIB.BASEBOARD_FAB2(SCH_1):PAGE164',
 WATTAGE='1/16W',
 TOLERANCE='1%',
 SEC_TYPE='0402',
 MATERIAL='CHIP',
 BOM_COST='SM_THERM',
 PHYS_PAGE='164',
 XY='(-1000,3750)',
 ROT='2',
 VER='2',
 VALUE='4.75K',
 PACK_TYPE='0402',
 PART_NUMBER='G21796-072',
 LOCATION='R6W41',
 ROOM='CPU_FANS',
 SEC='1',
 CDS_LIB='mstr_discrete',
 CDS_PART_NAME='RES_0402-4.75K,1%,1/16W,CHIP,GA',
 PRIM_FILE='./archive_libs/mstr_discrete/res/chips/chips.prt';

PART_NAME
 R6W42 'RES_0402-4.75K,1%,1/16W,EMPTY,A':
 ROOM='HOT_SWAP',
 NO_XNET_CONNECTION='1';

SECTION_NUMBER 1
 '@BASEBOARD_FAB2_LIB.BASEBOARD_FAB2(SCH_1):PAGE164_I95@MSTR_DISCRETE.RES(CHIPS)':
 C_PATH='@baseboard_fab2_lib.baseboard_fab2(sch_1):page164_i95@mstr_discrete.res~
(chips)',
 P_PATH='@baseboard_fab2_lib.baseboard_fab2(sch_1):page164_i95@mstr_discrete.res~
(chips)',
 PATH='I95',
 DRAWING='@BASEBOARD_FAB2_LIB.BASEBOARD_FAB2(SCH_1):PAGE164',
 WATTAGE='1/16W',
 TOLERANCE='1%',
 SEC_TYPE='0402',
 MATERIAL='EMPTY',
 NO_XNET_CONNECTION='1',
 PHYS_PAGE='164',
 XY='(-2350,2350)',
 ROT='0',
 VER='2',
 VALUE='4.75K',
 PACK_TYPE='0402',
 PART_NUMBER='G21796-072',
 LOCATION='R6W42',
 ROOM='HOT_SWAP',
 SEC='1',
 CDS_LIB='mstr_discrete',
 CDS_PART_NAME='RES_0402-4.75K,1%,1/16W,EMPTY,A',
 PRIM_FILE='./archive_libs/mstr_discrete/res/chips/chips.prt';

PART_NAME
 R6W43 'RES_0402-4.75K,1%,1/16W,EMPTY,A':
 ROOM='HOT_SWAP',
 NO_XNET_CONNECTION='1';

SECTION_NUMBER 1
 '@BASEBOARD_FAB2_LIB.BASEBOARD_FAB2(SCH_1):PAGE164_I96@MSTR_DISCRETE.RES(CHIPS)':
 C_PATH='@baseboard_fab2_lib.baseboard_fab2(sch_1):page164_i96@mstr_discrete.res~
(chips)',
 P_PATH='@baseboard_fab2_lib.baseboard_fab2(sch_1):page164_i96@mstr_discrete.res~
(chips)',
 PATH='I96',
 DRAWING='@BASEBOARD_FAB2_LIB.BASEBOARD_FAB2(SCH_1):PAGE164',
 WATTAGE='1/16W',
 TOLERANCE='1%',
 SEC_TYPE='0402',
 MATERIAL='EMPTY',
 NO_XNET_CONNECTION='1',
 PHYS_PAGE='164',
 XY='(-2000,2350)',
 ROT='0',
 VER='2',
 VALUE='4.75K',
 PACK_TYPE='0402',
 PART_NUMBER='G21796-072',
 LOCATION='R6W43',
 ROOM='HOT_SWAP',
 SEC='1',
 CDS_LIB='mstr_discrete',
 CDS_PART_NAME='RES_0402-4.75K,1%,1/16W,EMPTY,A',
 PRIM_FILE='./archive_libs/mstr_discrete/res/chips/chips.prt';

PART_NAME
 R6W44 'RES_0402-4.75K,1%,1/16W,CHIP,GA':
 ROOM='CPU_FANS';

SECTION_NUMBER 1
 '@BASEBOARD_FAB2_LIB.BASEBOARD_FAB2(SCH_1):PAGE164_I78@MSTR_DISCRETE.RES(CHIPS)':
 C_PATH='@baseboard_fab2_lib.baseboard_fab2(sch_1):page164_i78@mstr_discrete.res~
(chips)',
 P_PATH='@baseboard_fab2_lib.baseboard_fab2(sch_1):page164_i78@mstr_discrete.res~
(chips)',
 PATH='I78',
 DRAWING='@BASEBOARD_FAB2_LIB.BASEBOARD_FAB2(SCH_1):PAGE164',
 WATTAGE='1/16W',
 TOLERANCE='1%',
 SEC_TYPE='0402',
 MATERIAL='CHIP',
 BOM_COST='SM_THERM',
 PHYS_PAGE='164',
 XY='(-1650,2350)',
 ROT='2',
 VER='2',
 VALUE='4.75K',
 PACK_TYPE='0402',
 PART_NUMBER='G21796-072',
 LOCATION='R6W44',
 ROOM='CPU_FANS',
 SEC='1',
 CDS_LIB='mstr_discrete',
 CDS_PART_NAME='RES_0402-4.75K,1%,1/16W,CHIP,GA',
 PRIM_FILE='./archive_libs/mstr_discrete/res/chips/chips.prt';

PART_NAME
 R6W45 'RES_0402-4.75K,1%,1/16W,CHIP,GA':
 ROOM='CPU_FANS';

SECTION_NUMBER 1
 '@BASEBOARD_FAB2_LIB.BASEBOARD_FAB2(SCH_1):PAGE164_I94@MSTR_DISCRETE.RES(CHIPS)':
 C_PATH='@baseboard_fab2_lib.baseboard_fab2(sch_1):page164_i94@mstr_discrete.res~
(chips)',
 P_PATH='@baseboard_fab2_lib.baseboard_fab2(sch_1):page164_i94@mstr_discrete.res~
(chips)',
 PATH='I94',
 DRAWING='@BASEBOARD_FAB2_LIB.BASEBOARD_FAB2(SCH_1):PAGE164',
 WATTAGE='1/16W',
 TOLERANCE='1%',
 SEC_TYPE='0402',
 MATERIAL='CHIP',
 BOM_COST='SM_THERM',
 PHYS_PAGE='164',
 XY='(-2350,1800)',
 ROT='2',
 VER='2',
 VALUE='4.75K',
 PACK_TYPE='0402',
 PART_NUMBER='G21796-072',
 LOCATION='R6W45',
 ROOM='CPU_FANS',
 SEC='1',
 CDS_LIB='mstr_discrete',
 CDS_PART_NAME='RES_0402-4.75K,1%,1/16W,CHIP,GA',
 PRIM_FILE='./archive_libs/mstr_discrete/res/chips/chips.prt';

PART_NAME
 R6W46 'RES_0402-4.75K,1%,1/16W,CHIP,GA':
 ROOM='CPU_FANS';

SECTION_NUMBER 1
 '@BASEBOARD_FAB2_LIB.BASEBOARD_FAB2(SCH_1):PAGE164_I93@MSTR_DISCRETE.RES(CHIPS)':
 C_PATH='@baseboard_fab2_lib.baseboard_fab2(sch_1):page164_i93@mstr_discrete.res~
(chips)',
 P_PATH='@baseboard_fab2_lib.baseboard_fab2(sch_1):page164_i93@mstr_discrete.res~
(chips)',
 PATH='I93',
 DRAWING='@BASEBOARD_FAB2_LIB.BASEBOARD_FAB2(SCH_1):PAGE164',
 WATTAGE='1/16W',
 TOLERANCE='1%',
 SEC_TYPE='0402',
 MATERIAL='CHIP',
 BOM_COST='SM_THERM',
 PHYS_PAGE='164',
 XY='(-2000,1800)',
 ROT='2',
 VER='2',
 VALUE='4.75K',
 PACK_TYPE='0402',
 PART_NUMBER='G21796-072',
 LOCATION='R6W46',
 ROOM='CPU_FANS',
 SEC='1',
 CDS_LIB='mstr_discrete',
 CDS_PART_NAME='RES_0402-4.75K,1%,1/16W,CHIP,GA',
 PRIM_FILE='./archive_libs/mstr_discrete/res/chips/chips.prt';

PART_NAME
 R6W47 'RES_0402-4.75K,1%,1/16W,EMPTY,A':
 ROOM='HOT_SWAP',
 NO_XNET_CONNECTION='1';

SECTION_NUMBER 1
 '@BASEBOARD_FAB2_LIB.BASEBOARD_FAB2(SCH_1):PAGE164_I76@MSTR_DISCRETE.RES(CHIPS)':
 C_PATH='@baseboard_fab2_lib.baseboard_fab2(sch_1):page164_i76@mstr_discrete.res~
(chips)',
 P_PATH='@baseboard_fab2_lib.baseboard_fab2(sch_1):page164_i76@mstr_discrete.res~
(chips)',
 PATH='I76',
 DRAWING='@BASEBOARD_FAB2_LIB.BASEBOARD_FAB2(SCH_1):PAGE164',
 WATTAGE='1/16W',
 TOLERANCE='1%',
 SEC_TYPE='0402',
 MATERIAL='EMPTY',
 NO_XNET_CONNECTION='1',
 PHYS_PAGE='164',
 XY='(-1650,1800)',
 ROT='0',
 VER='2',
 VALUE='4.75K',
 PACK_TYPE='0402',
 PART_NUMBER='G21796-072',
 LOCATION='R6W47',
 ROOM='HOT_SWAP',
 SEC='1',
 CDS_LIB='mstr_discrete',
 CDS_PART_NAME='RES_0402-4.75K,1%,1/16W,EMPTY,A',
 PRIM_FILE='./archive_libs/mstr_discrete/res/chips/chips.prt';

PART_NAME
 R6W49 'RES_0402-40.2K,1%,1/16W,CHIP,GA':
 ROOM='HOT_SWAP';

SECTION_NUMBER 1
 '@BASEBOARD_FAB2_LIB.BASEBOARD_FAB2(SCH_1):PAGE168_I48@MSTR_DISCRETE.RES(CHIPS)':
 C_PATH='@baseboard_fab2_lib.baseboard_fab2(sch_1):page168_i48@mstr_discrete.res~
(chips)',
 P_PATH='@baseboard_fab2_lib.baseboard_fab2(sch_1):page168_i48@mstr_discrete.res~
(chips)',
 PATH='I48',
 DRAWING='@BASEBOARD_FAB2_LIB.BASEBOARD_FAB2(SCH_1):PAGE168',
 WATTAGE='1/16W',
 TOLERANCE='1%',
 SEC_TYPE='0402',
 MATERIAL='CHIP',
 PHYS_PAGE='168',
 XY='(-5950,1450)',
 ROT='1',
 VER='2',
 VALUE='40.2K',
 PACK_TYPE='0402',
 PART_NUMBER='G21796-133',
 LOCATION='R6W49',
 ROOM='HOT_SWAP',
 SEC='1',
 CDS_LIB='mstr_discrete',
 CDS_PART_NAME='RES_0402-40.2K,1%,1/16W,CHIP,GA',
 PRIM_FILE='./archive_libs/mstr_discrete/res/chips/chips.prt';

PART_NAME
 R6W50 'RES_0402-4.75K,1%,1/16W,CHIP,GA':;

SECTION_NUMBER 1
 '@BASEBOARD_FAB2_LIB.BASEBOARD_FAB2(SCH_1):PAGE176_I178@MSTR_DISCRETE.RES(CHIPS)':
 C_PATH='@baseboard_fab2_lib.baseboard_fab2(sch_1):page176_i178@mstr_discrete.re~
s(chips)',
 P_PATH='@baseboard_fab2_lib.baseboard_fab2(sch_1):page176_i178@mstr_discrete.re~
s(chips)',
 PATH='I178',
 DRAWING='@BASEBOARD_FAB2_LIB.BASEBOARD_FAB2(SCH_1):PAGE176',
 POP='NOPOP',
 WATTAGE='1/16W',
 TOLERANCE='1%',
 SEC_TYPE='0402',
 MATERIAL='CHIP',
 PHYS_PAGE='176',
 XY='(-2150,4950)',
 ROT='5',
 VER='1',
 VALUE='4.75K',
 PACK_TYPE='0402',
 PART_NUMBER='G21796-072',
 LOCATION='R6W50',
 SEC='1',
 CDS_LIB='mstr_discrete',
 CDS_PART_NAME='RES_0402-4.75K,1%,1/16W,CHIP,GA',
 PRIM_FILE='./archive_libs/mstr_discrete/res/chips/chips.prt';

PART_NAME
 R7A7 'RES_0402-10.0,1%,1/16W,CHIP,G2A':
 ROOM='VDDQ_DEF_PWR_VR';

SECTION_NUMBER 1
 '@BASEBOARD_FAB2_LIB.BASEBOARD_FAB2(SCH_1):PAGE218_I13@MSTR_DISCRETE.RES(CHIPS)':
 C_PATH='@baseboard_fab2_lib.baseboard_fab2(sch_1):page218_i13@mstr_discrete.res~
(chips)',
 P_PATH='@baseboard_fab2_lib.baseboard_fab2(sch_1):page218_i13@mstr_discrete.res~
(chips)',
 PATH='I13',
 DRAWING='@BASEBOARD_FAB2_LIB.BASEBOARD_FAB2(SCH_1):PAGE218',
 WATTAGE='1/16W',
 TOLERANCE='1%',
 SEC_TYPE='0402',
 MATERIAL='CHIP',
 PHYS_PAGE='218',
 XY='(-2925,875)',
 ROT='0',
 VER='1',
 VALUE='10.0',
 PACK_TYPE='0402',
 PART_NUMBER='G21796-066',
 LOCATION='R7A7',
 ROOM='VDDQ_DEF_PWR_VR',
 SEC='1',
 CDS_LIB='mstr_discrete',
 CDS_PART_NAME='RES_0402-10.0,1%,1/16W,CHIP,G2A',
 PRIM_FILE='./archive_libs/mstr_discrete/res/chips/chips.prt';

PART_NAME
 R7A8 'RES_0402-2.26K,1.0%,1/16W,CHIPA':
 ROOM='SMBUS';

SECTION_NUMBER 1
 '@BASEBOARD_FAB2_LIB.BASEBOARD_FAB2(SCH_1):PAGE218_I74@MSTR_DISCRETE.RES(CHIPS)':
 C_PATH='@baseboard_fab2_lib.baseboard_fab2(sch_1):page218_i74@mstr_discrete.res~
(chips)',
 P_PATH='@baseboard_fab2_lib.baseboard_fab2(sch_1):page218_i74@mstr_discrete.res~
(chips)',
 PATH='I74',
 DRAWING='@BASEBOARD_FAB2_LIB.BASEBOARD_FAB2(SCH_1):PAGE218',
 SKU='B',
 WATTAGE='1/16W',
 TOLERANCE='1.0%',
 SEC_TYPE='0402',
 MATERIAL='CHIP',
 BOM_COST='SM_CONTROLLER',
 PHYS_PAGE='218',
 XY='(-775,-150)',
 ROT='0',
 VER='2',
 VALUE='2.26K',
 PACK_TYPE='0402',
 PART_NUMBER='G21796-311',
 LOCATION='R7A8',
 ROOM='SMBUS',
 SEC='1',
 CDS_LIB='mstr_discrete',
 CDS_PART_NAME='RES_0402-2.26K,1.0%,1/16W,CHIPA',
 PRIM_FILE='./archive_libs/mstr_discrete/res/chips/chips.prt';

PART_NAME
 R7A9 'RES_0402-2.26K,1.0%,1/16W,CHIPA':
 ROOM='SMBUS';

SECTION_NUMBER 1
 '@BASEBOARD_FAB2_LIB.BASEBOARD_FAB2(SCH_1):PAGE218_I76@MSTR_DISCRETE.RES(CHIPS)':
 C_PATH='@baseboard_fab2_lib.baseboard_fab2(sch_1):page218_i76@mstr_discrete.res~
(chips)',
 P_PATH='@baseboard_fab2_lib.baseboard_fab2(sch_1):page218_i76@mstr_discrete.res~
(chips)',
 PATH='I76',
 DRAWING='@BASEBOARD_FAB2_LIB.BASEBOARD_FAB2(SCH_1):PAGE218',
 SKU='B',
 WATTAGE='1/16W',
 TOLERANCE='1.0%',
 SEC_TYPE='0402',
 MATERIAL='CHIP',
 BOM_COST='SM_CONTROLLER',
 PHYS_PAGE='218',
 XY='(2150,2800)',
 ROT='0',
 VER='2',
 VALUE='2.26K',
 PACK_TYPE='0402',
 PART_NUMBER='G21796-311',
 LOCATION='R7A9',
 ROOM='SMBUS',
 SEC='1',
 CDS_LIB='mstr_discrete',
 CDS_PART_NAME='RES_0402-2.26K,1.0%,1/16W,CHIPA',
 PRIM_FILE='./archive_libs/mstr_discrete/res/chips/chips.prt';

PART_NAME
 R7A10 'RES_0402-16K,1.0%,1/16W,CHIP,GA':
 ROOM='VDDQ_ABC_PWR_VR';

SECTION_NUMBER 1
 '@BASEBOARD_FAB2_LIB.BASEBOARD_FAB2(SCH_1):PAGE218_I73@MSTR_DISCRETE.RES(CHIPS)':
 C_PATH='@baseboard_fab2_lib.baseboard_fab2(sch_1):page218_i73@mstr_discrete.res~
(chips)',
 P_PATH='@baseboard_fab2_lib.baseboard_fab2(sch_1):page218_i73@mstr_discrete.res~
(chips)',
 PATH='I73',
 DRAWING='@BASEBOARD_FAB2_LIB.BASEBOARD_FAB2(SCH_1):PAGE218',
 WATTAGE='1/16W',
 TOLERANCE='1.0%',
 SEC_TYPE='0402',
 MATERIAL='CHIP',
 PHYS_PAGE='218',
 XY='(-1075,-150)',
 ROT='0',
 VER='2',
 VALUE='16K',
 PACK_TYPE='0402',
 PART_NUMBER='G21796-317',
 LOCATION='R7A10',
 ROOM='VDDQ_ABC_PWR_VR',
 SEC='1',
 CDS_LIB='mstr_discrete',
 CDS_PART_NAME='RES_0402-16K,1.0%,1/16W,CHIP,GA',
 PRIM_FILE='./archive_libs/mstr_discrete/res/chips/chips.prt';

PART_NAME
 R7A11 'RES_0402-0.0,5%,1/16W,CHIP,G21A':
 ROOM='VDDQ_DEF_PWR_VR';

SECTION_NUMBER 1
 '@BASEBOARD_FAB2_LIB.BASEBOARD_FAB2(SCH_1):PAGE218_I56@MSTR_DISCRETE.RES(CHIPS)':
 C_PATH='@baseboard_fab2_lib.baseboard_fab2(sch_1):page218_i56@mstr_discrete.res~
(chips)',
 P_PATH='@baseboard_fab2_lib.baseboard_fab2(sch_1):page218_i56@mstr_discrete.res~
(chips)',
 PATH='I56',
 DRAWING='@BASEBOARD_FAB2_LIB.BASEBOARD_FAB2(SCH_1):PAGE218',
 WATTAGE='1/16W',
 TOLERANCE='5%',
 SEC_TYPE='0402',
 MATERIAL='CHIP',
 PHYS_PAGE='218',
 XY='(1350,2100)',
 ROT='0',
 VER='1',
 VALUE='0.0',
 PACK_TYPE='0402',
 PART_NUMBER='G21497-005',
 LOCATION='R7A11',
 ROOM='VDDQ_DEF_PWR_VR',
 SEC='1',
 CDS_LIB='mstr_discrete',
 CDS_PART_NAME='RES_0402-0.0,5%,1/16W,CHIP,G21A',
 PRIM_FILE='./archive_libs/mstr_discrete/res/chips/chips.prt';

PART_NAME
 R7A12 'RES_0402-0.0,5%,1/16W,CHIP,G21A':
 ROOM='VDDQ_DEF_PWR_VR';

SECTION_NUMBER 1
 '@BASEBOARD_FAB2_LIB.BASEBOARD_FAB2(SCH_1):PAGE218_I45@MSTR_DISCRETE.RES(CHIPS)':
 C_PATH='@baseboard_fab2_lib.baseboard_fab2(sch_1):page218_i45@mstr_discrete.res~
(chips)',
 P_PATH='@baseboard_fab2_lib.baseboard_fab2(sch_1):page218_i45@mstr_discrete.res~
(chips)',
 PATH='I45',
 DRAWING='@BASEBOARD_FAB2_LIB.BASEBOARD_FAB2(SCH_1):PAGE218',
 WATTAGE='1/16W',
 TOLERANCE='5%',
 SEC_TYPE='0402',
 MATERIAL='CHIP',
 PHYS_PAGE='218',
 XY='(1500,1400)',
 ROT='0',
 VER='1',
 VALUE='0.0',
 PACK_TYPE='0402',
 PART_NUMBER='G21497-005',
 LOCATION='R7A12',
 ROOM='VDDQ_DEF_PWR_VR',
 SEC='1',
 CDS_LIB='mstr_discrete',
 CDS_PART_NAME='RES_0402-0.0,5%,1/16W,CHIP,G21A',
 PRIM_FILE='./archive_libs/mstr_discrete/res/chips/chips.prt';

PART_NAME
 R7A13 'RES_0402-100.0,1%,1/16W,CHIP,GA':
 ROOM='P1V05_PCH_STBY';

SECTION_NUMBER 1
 '@BASEBOARD_FAB2_LIB.BASEBOARD_FAB2(SCH_1):PAGE236_I90@MSTR_DISCRETE.RES(CHIPS)':
 C_PATH='@baseboard_fab2_lib.baseboard_fab2(sch_1):page236_i90@mstr_discrete.res~
(chips)',
 P_PATH='@baseboard_fab2_lib.baseboard_fab2(sch_1):page236_i90@mstr_discrete.res~
(chips)',
 PATH='I90',
 DRAWING='@BASEBOARD_FAB2_LIB.BASEBOARD_FAB2(SCH_1):PAGE236',
 SPOF='TRUE',
 WATTAGE='1/16W',
 TOLERANCE='1%',
 SEC_TYPE='0402',
 MATERIAL='CHIP',
 BOM_COST='P1V05_PCH_STBY',
 PHYS_PAGE='236',
 XY='(9200,1400)',
 ROT='0',
 VER='1',
 VALUE='100.0',
 PACK_TYPE='0402',
 PART_NUMBER='G21796-017',
 LOCATION='R7A13',
 ROOM='P1V05_PCH_STBY',
 SEC='1',
 CDS_LIB='mstr_discrete',
 CDS_PART_NAME='RES_0402-100.0,1%,1/16W,CHIP,GA',
 PRIM_FILE='./archive_libs/mstr_discrete/res/chips/chips.prt';

PART_NAME
 R7A14 'RES_0402-10.0,1%,1/16W,CHIP,G2A':
 ROOM='P1V05_PCH_STBY',
 NO_XNET_CONNECTION='1';

SECTION_NUMBER 1
 '@BASEBOARD_FAB2_LIB.BASEBOARD_FAB2(SCH_1):PAGE236_I94@MSTR_DISCRETE.RES(CHIPS)':
 C_PATH='@baseboard_fab2_lib.baseboard_fab2(sch_1):page236_i94@mstr_discrete.res~
(chips)',
 P_PATH='@baseboard_fab2_lib.baseboard_fab2(sch_1):page236_i94@mstr_discrete.res~
(chips)',
 PATH='I94',
 DRAWING='@BASEBOARD_FAB2_LIB.BASEBOARD_FAB2(SCH_1):PAGE236',
 SPOF='TRUE',
 WATTAGE='1/16W',
 TOLERANCE='1%',
 SEC_TYPE='0402',
 MATERIAL='CHIP',
 BOM_COST='P1V05_PCH_STBY',
 NO_XNET_CONNECTION='1',
 PHYS_PAGE='236',
 XY='(8750,900)',
 ROT='0',
 VER='1',
 VALUE='10.0',
 PACK_TYPE='0402',
 PART_NUMBER='G21796-066',
 LOCATION='R7A14',
 ROOM='P1V05_PCH_STBY',
 SEC='1',
 CDS_LIB='mstr_discrete',
 CDS_PART_NAME='RES_0402-10.0,1%,1/16W,CHIP,G2A',
 PRIM_FILE='./archive_libs/mstr_discrete/res/chips/chips.prt';

PART_NAME
 R7A15 'RES_0402-2.2,5%,1/16W,EMPTY,G2A':
 ROOM='PVPP_KLM_VR',
 REUSE_ID='29';

SECTION_NUMBER 1
 '@BASEBOARD_FAB2_LIB.BASEBOARD_FAB2(SCH_1):PAGE232_I218@MSTR_DISCRETE.RES(CHIPS)':
 C_PATH='@baseboard_fab2_lib.baseboard_fab2(sch_1):page232_i218@mstr_discrete.re~
s(chips)',
 P_PATH='@baseboard_fab2_lib.baseboard_fab2(sch_1):page232_i218@mstr_discrete.re~
s(chips)',
 PATH='I218',
 DRAWING='@BASEBOARD_FAB2_LIB.BASEBOARD_FAB2(SCH_1):PAGE232',
 WATTAGE='1/16W',
 TOLERANCE='5%',
 SEC_TYPE='0402',
 MATERIAL='EMPTY',
 BOM_COST='PVPP_KLM_VR',
 PHYS_PAGE='232',
 REUSE_ID='29',
 XY='(-2875,3325)',
 ROT='0',
 VER='2',
 VALUE='2.2',
 PACK_TYPE='0402',
 PART_NUMBER='G21497-016',
 LOCATION='R7A15',
 ROOM='PVPP_KLM_VR',
 SEC='1',
 CDS_LIB='mstr_discrete',
 CDS_PART_NAME='RES_0402-2.2,5%,1/16W,EMPTY,G2A',
 PRIM_FILE='./archive_libs/mstr_discrete/res/chips/chips.prt';

PART_NAME
 R7A17 'RES_0402-150.0,1%,1/16W,CHIP,GA':
 ROOM='VDDQ_DEF_PWR_VR';

SECTION_NUMBER 1
 '@BASEBOARD_FAB2_LIB.BASEBOARD_FAB2(SCH_1):PAGE218_I21@MSTR_DISCRETE.RES(CHIPS)':
 C_PATH='@baseboard_fab2_lib.baseboard_fab2(sch_1):page218_i21@mstr_discrete.res~
(chips)',
 P_PATH='@baseboard_fab2_lib.baseboard_fab2(sch_1):page218_i21@mstr_discrete.res~
(chips)',
 PATH='I21',
 DRAWING='@BASEBOARD_FAB2_LIB.BASEBOARD_FAB2(SCH_1):PAGE218',
 WATTAGE='1/16W',
 TOLERANCE='1%',
 SEC_TYPE='0402',
 MATERIAL='CHIP',
 PHYS_PAGE='218',
 XY='(-1475,2725)',
 ROT='0',
 VER='1',
 VALUE='150.0',
 PACK_TYPE='0402',
 PART_NUMBER='G21796-009',
 LOCATION='R7A17',
 ROOM='VDDQ_DEF_PWR_VR',
 SEC='1',
 CDS_LIB='mstr_discrete',
 CDS_PART_NAME='RES_0402-150.0,1%,1/16W,CHIP,GA',
 PRIM_FILE='./archive_libs/mstr_discrete/res/chips/chips.prt';

PART_NAME
 R7A18 'RES_0402-0.0,5%,1/16W,CHIP,G21A':
 ROOM='P1V05_PCH_STBY';

SECTION_NUMBER 1
 '@BASEBOARD_FAB2_LIB.BASEBOARD_FAB2(SCH_1):PAGE236_I92@MSTR_DISCRETE.RES(CHIPS)':
 C_PATH='@baseboard_fab2_lib.baseboard_fab2(sch_1):page236_i92@mstr_discrete.res~
(chips)',
 P_PATH='@baseboard_fab2_lib.baseboard_fab2(sch_1):page236_i92@mstr_discrete.res~
(chips)',
 PATH='I92',
 DRAWING='@BASEBOARD_FAB2_LIB.BASEBOARD_FAB2(SCH_1):PAGE236',
 SPOF='TRUE',
 WATTAGE='1/16W',
 TOLERANCE='5%',
 SEC_TYPE='0402',
 MATERIAL='CHIP',
 BOM_COST='P1V05_PCH_STBY',
 PHYS_PAGE='236',
 XY='(9200,950)',
 ROT='0',
 VER='1',
 VALUE='0.0',
 PACK_TYPE='0402',
 PART_NUMBER='G21497-005',
 LOCATION='R7A18',
 ROOM='P1V05_PCH_STBY',
 SEC='1',
 CDS_LIB='mstr_discrete',
 CDS_PART_NAME='RES_0402-0.0,5%,1/16W,CHIP,G21A',
 PRIM_FILE='./archive_libs/mstr_discrete/res/chips/chips.prt';

PART_NAME
 R7A19 'RES_0402-10.0,1%,1/16W,CHIP,G2A':
 ROOM='P1V05_PCH_STBY',
 NO_XNET_CONNECTION='1';

SECTION_NUMBER 1
 '@BASEBOARD_FAB2_LIB.BASEBOARD_FAB2(SCH_1):PAGE236_I93@MSTR_DISCRETE.RES(CHIPS)':
 C_PATH='@baseboard_fab2_lib.baseboard_fab2(sch_1):page236_i93@mstr_discrete.res~
(chips)',
 P_PATH='@baseboard_fab2_lib.baseboard_fab2(sch_1):page236_i93@mstr_discrete.res~
(chips)',
 PATH='I93',
 DRAWING='@BASEBOARD_FAB2_LIB.BASEBOARD_FAB2(SCH_1):PAGE236',
 SPOF='TRUE',
 WATTAGE='1/16W',
 TOLERANCE='1%',
 SEC_TYPE='0402',
 MATERIAL='CHIP',
 BOM_COST='P1V05_PCH_STBY',
 NO_XNET_CONNECTION='1',
 PHYS_PAGE='236',
 XY='(8725,1175)',
 ROT='0',
 VER='1',
 VALUE='10.0',
 PACK_TYPE='0402',
 PART_NUMBER='G21796-066',
 LOCATION='R7A19',
 ROOM='P1V05_PCH_STBY',
 SEC='1',
 CDS_LIB='mstr_discrete',
 CDS_PART_NAME='RES_0402-10.0,1%,1/16W,CHIP,G2A',
 PRIM_FILE='./archive_libs/mstr_discrete/res/chips/chips.prt';

PART_NAME
 R7A20 'RES_0402-68.1K,1%,1/16W,EMPTY,A':;

SECTION_NUMBER 1
 '@BASEBOARD_FAB2_LIB.BASEBOARD_FAB2(SCH_1):PAGE219_I108@MSTR_DISCRETE.RES(CHIPS)':
 C_PATH='@baseboard_fab2_lib.baseboard_fab2(sch_1):page219_i108@mstr_discrete.re~
s(chips)',
 P_PATH='@baseboard_fab2_lib.baseboard_fab2(sch_1):page219_i108@mstr_discrete.re~
s(chips)',
 PATH='I108',
 DRAWING='@BASEBOARD_FAB2_LIB.BASEBOARD_FAB2(SCH_1):PAGE219',
 WATTAGE='1/16W',
 TOLERANCE='1%',
 MATERIAL='EMPTY',
 PHYS_PAGE='219',
 XY='(4575,2300)',
 ROT='0',
 VER='2',
 VALUE='68.1K',
 PACK_TYPE='0402',
 PART_NUMBER='G21796-187',
 LOCATION='R7A20',
 CDS_LIB='mstr_discrete',
 CDS_PART_NAME='RES_0402-68.1K,1%,1/16W,EMPTY,A',
 PRIM_FILE='./archive_libs/mstr_discrete/res/chips/chips.prt';

PART_NAME
 R7A21 'RES_0402-68.1K,1%,1/16W,EMPTY,A':;

SECTION_NUMBER 1
 '@BASEBOARD_FAB2_LIB.BASEBOARD_FAB2(SCH_1):PAGE219_I110@MSTR_DISCRETE.RES(CHIPS)':
 C_PATH='@baseboard_fab2_lib.baseboard_fab2(sch_1):page219_i110@mstr_discrete.re~
s(chips)',
 P_PATH='@baseboard_fab2_lib.baseboard_fab2(sch_1):page219_i110@mstr_discrete.re~
s(chips)',
 PATH='I110',
 DRAWING='@BASEBOARD_FAB2_LIB.BASEBOARD_FAB2(SCH_1):PAGE219',
 BOM_SS='NOPOP',
 WATTAGE='1/16W',
 TOLERANCE='1%',
 SEC_TYPE='0402',
 MATERIAL='EMPTY',
 PHYS_PAGE='219',
 XY='(4575,25)',
 ROT='0',
 VER='2',
 VALUE='68.1K',
 PACK_TYPE='0402',
 PART_NUMBER='G21796-187',
 LOCATION='R7A21',
 SEC='1',
 CDS_LIB='mstr_discrete',
 CDS_PART_NAME='RES_0402-68.1K,1%,1/16W,EMPTY,A',
 PRIM_FILE='./archive_libs/mstr_discrete/res/chips/chips.prt';

PART_NAME
 R7B1 'RES_0402-33.2,1%,1/16W,CHIP,G2A':;

SECTION_NUMBER 1
 '@BASEBOARD_FAB2_LIB.BASEBOARD_FAB2(SCH_1):PAGE218_I59@MSTR_DISCRETE.RES(CHIPS)':
 C_PATH='@baseboard_fab2_lib.baseboard_fab2(sch_1):page218_i59@mstr_discrete.res~
(chips)',
 P_PATH='@baseboard_fab2_lib.baseboard_fab2(sch_1):page218_i59@mstr_discrete.res~
(chips)',
 PATH='I59',
 DRAWING='@BASEBOARD_FAB2_LIB.BASEBOARD_FAB2(SCH_1):PAGE218',
 WATTAGE='1/16W',
 TOLERANCE='1%',
 SEC_TYPE='0402',
 MATERIAL='CHIP',
 PHYS_PAGE='218',
 XY='(1825,2150)',
 ROT='0',
 VER='1',
 VALUE='33.2',
 PACK_TYPE='0402',
 PART_NUMBER='G21796-074',
 LOCATION='R7B1',
 SEC='1',
 CDS_LIB='mstr_discrete',
 CDS_PART_NAME='RES_0402-33.2,1%,1/16W,CHIP,G2A',
 PRIM_FILE='./archive_libs/mstr_discrete/res/chips/chips.prt';

PART_NAME
 R7B4 'RES_0402-1.00K,1%,1/16W,CHIP,GA':
 ROOM='VDDQ_DEF_PWR_VR';

SECTION_NUMBER 1
 '@BASEBOARD_FAB2_LIB.BASEBOARD_FAB2(SCH_1):PAGE218_I57@MSTR_DISCRETE.RES(CHIPS)':
 C_PATH='@baseboard_fab2_lib.baseboard_fab2(sch_1):page218_i57@mstr_discrete.res~
(chips)',
 P_PATH='@baseboard_fab2_lib.baseboard_fab2(sch_1):page218_i57@mstr_discrete.res~
(chips)',
 PATH='I57',
 DRAWING='@BASEBOARD_FAB2_LIB.BASEBOARD_FAB2(SCH_1):PAGE218',
 WATTAGE='1/16W',
 TOLERANCE='1%',
 SEC_TYPE='0402',
 MATERIAL='CHIP',
 PHYS_PAGE='218',
 XY='(975,2800)',
 ROT='0',
 VER='2',
 VALUE='1.00K',
 PACK_TYPE='0402',
 PART_NUMBER='G21796-026',
 LOCATION='R7B4',
 ROOM='VDDQ_DEF_PWR_VR',
 SEC='1',
 CDS_LIB='mstr_discrete',
 CDS_PART_NAME='RES_0402-1.00K,1%,1/16W,CHIP,GA',
 PRIM_FILE='./archive_libs/mstr_discrete/res/chips/chips.prt';

PART_NAME
 R7B5 'RES_0402-1.00K,1%,1/16W,CHIP,GA':
 ROOM='VDDQ_DEF_PWR_VR';

SECTION_NUMBER 1
 '@BASEBOARD_FAB2_LIB.BASEBOARD_FAB2(SCH_1):PAGE218_I58@MSTR_DISCRETE.RES(CHIPS)':
 C_PATH='@baseboard_fab2_lib.baseboard_fab2(sch_1):page218_i58@mstr_discrete.res~
(chips)',
 P_PATH='@baseboard_fab2_lib.baseboard_fab2(sch_1):page218_i58@mstr_discrete.res~
(chips)',
 PATH='I58',
 DRAWING='@BASEBOARD_FAB2_LIB.BASEBOARD_FAB2(SCH_1):PAGE218',
 WATTAGE='1/16W',
 TOLERANCE='1%',
 SEC_TYPE='0402',
 MATERIAL='CHIP',
 PHYS_PAGE='218',
 XY='(1175,2800)',
 ROT='0',
 VER='2',
 VALUE='1.00K',
 PACK_TYPE='0402',
 PART_NUMBER='G21796-026',
 LOCATION='R7B5',
 ROOM='VDDQ_DEF_PWR_VR',
 SEC='1',
 CDS_LIB='mstr_discrete',
 CDS_PART_NAME='RES_0402-1.00K,1%,1/16W,CHIP,GA',
 PRIM_FILE='./archive_libs/mstr_discrete/res/chips/chips.prt';

PART_NAME
 R7B6 'RES_0402-10.0K,1%,1/16W,CHIP,GA':
 ROOM='SB_PU_PD';

SECTION_NUMBER 1
 '@BASEBOARD_FAB2_LIB.BASEBOARD_FAB2(SCH_1):PAGE133_I295@MSTR_DISCRETE.RES(CHIPS)':
 C_PATH='@baseboard_fab2_lib.baseboard_fab2(sch_1):page133_i295@mstr_discrete.re~
s(chips)',
 P_PATH='@baseboard_fab2_lib.baseboard_fab2(sch_1):page133_i295@mstr_discrete.re~
s(chips)',
 PATH='I295',
 DRAWING='@BASEBOARD_FAB2_LIB.BASEBOARD_FAB2(SCH_1):PAGE133',
 WATTAGE='1/16W',
 TOLERANCE='1%',
 SEC_TYPE='0402',
 MATERIAL='CHIP',
 PHYS_PAGE='133',
 XY='(-175,1425)',
 ROT='0',
 VER='2',
 VALUE='10.0K',
 PACK_TYPE='0402',
 PART_NUMBER='G21796-016',
 LOCATION='R7B6',
 ROOM='SB_PU_PD',
 SEC='1',
 CDS_LIB='mstr_discrete',
 CDS_PART_NAME='RES_0402-10.0K,1%,1/16W,CHIP,GA',
 PRIM_FILE='./archive_libs/mstr_discrete/res/chips/chips.prt';

PART_NAME
 R7B7 'RES_0402-10.0K,1%,1/16W,EMPTY,A':
 ROOM='SB';

SECTION_NUMBER 1
 '@BASEBOARD_FAB2_LIB.BASEBOARD_FAB2(SCH_1):PAGE116_I230@MSTR_DISCRETE.RES(CHIPS)':
 C_PATH='@baseboard_fab2_lib.baseboard_fab2(sch_1):page116_i230@mstr_discrete.re~
s(chips)',
 P_PATH='@baseboard_fab2_lib.baseboard_fab2(sch_1):page116_i230@mstr_discrete.re~
s(chips)',
 PATH='I230',
 DRAWING='@BASEBOARD_FAB2_LIB.BASEBOARD_FAB2(SCH_1):PAGE116',
 WATTAGE='1/16W',
 TOLERANCE='1%',
 SEC_TYPE='0402',
 MATERIAL='EMPTY',
 PHYS_PAGE='116',
 XY='(-1825,1400)',
 ROT='0',
 VER='2',
 VALUE='10.0K',
 PACK_TYPE='0402',
 PART_NUMBER='G21796-016',
 LOCATION='R7B7',
 ROOM='SB',
 SEC='1',
 CDS_LIB='mstr_discrete',
 CDS_PART_NAME='RES_0402-10.0K,1%,1/16W,EMPTY,A',
 PRIM_FILE='./archive_libs/mstr_discrete/res/chips/chips.prt';

PART_NAME
 R7B8 'RES_0402-10.0K,1%,1/16W,EMPTY,A':
 ROOM='SB';

SECTION_NUMBER 1
 '@BASEBOARD_FAB2_LIB.BASEBOARD_FAB2(SCH_1):PAGE116_I229@MSTR_DISCRETE.RES(CHIPS)':
 C_PATH='@baseboard_fab2_lib.baseboard_fab2(sch_1):page116_i229@mstr_discrete.re~
s(chips)',
 P_PATH='@baseboard_fab2_lib.baseboard_fab2(sch_1):page116_i229@mstr_discrete.re~
s(chips)',
 PATH='I229',
 DRAWING='@BASEBOARD_FAB2_LIB.BASEBOARD_FAB2(SCH_1):PAGE116',
 WATTAGE='1/16W',
 TOLERANCE='1%',
 SEC_TYPE='0402',
 MATERIAL='EMPTY',
 PHYS_PAGE='116',
 XY='(-2125,1400)',
 ROT='0',
 VER='2',
 VALUE='10.0K',
 PACK_TYPE='0402',
 PART_NUMBER='G21796-016',
 LOCATION='R7B8',
 ROOM='SB',
 SEC='1',
 CDS_LIB='mstr_discrete',
 CDS_PART_NAME='RES_0402-10.0K,1%,1/16W,EMPTY,A',
 PRIM_FILE='./archive_libs/mstr_discrete/res/chips/chips.prt';

PART_NAME
 R7B9 'RES_0402-0.0,5%,1/16W,CHIP,G21A':
 ROOM='PVCCIN_CPU0_VR';

SECTION_NUMBER 1
 '@BASEBOARD_FAB2_LIB.BASEBOARD_FAB2(SCH_1):PAGE232_I307@MSTR_DISCRETE.RES(CHIPS)':
 C_PATH='@baseboard_fab2_lib.baseboard_fab2(sch_1):page232_i307@mstr_discrete.re~
s(chips)',
 P_PATH='@baseboard_fab2_lib.baseboard_fab2(sch_1):page232_i307@mstr_discrete.re~
s(chips)',
 PATH='I307',
 DRAWING='@BASEBOARD_FAB2_LIB.BASEBOARD_FAB2(SCH_1):PAGE232',
 WATTAGE='1/16W',
 TOLERANCE='5%',
 SEC_TYPE='0402',
 MATERIAL='CHIP',
 PHYS_PAGE='232',
 XY='(-6500,2825)',
 ROT='0',
 VER='1',
 VALUE='0.0',
 PACK_TYPE='0402',
 PART_NUMBER='G21497-005',
 LOCATION='R7B9',
 ROOM='PVCCIN_CPU0_VR',
 SEC='1',
 CDS_LIB='mstr_discrete',
 CDS_PART_NAME='RES_0402-0.0,5%,1/16W,CHIP,G21A',
 PRIM_FILE='./archive_libs/mstr_discrete/res/chips/chips.prt';

PART_NAME
 R7B10 'RES_0603-120.0,1%,1/10W,CHIP,GA':
 ROOM='PVPP_KLM_VR',
 REUSE_ID='34';

SECTION_NUMBER 1
 '@BASEBOARD_FAB2_LIB.BASEBOARD_FAB2(SCH_1):PAGE232_I227@MSTR_DISCRETE.RES(CHIPS)':
 C_PATH='@baseboard_fab2_lib.baseboard_fab2(sch_1):page232_i227@mstr_discrete.re~
s(chips)',
 P_PATH='@baseboard_fab2_lib.baseboard_fab2(sch_1):page232_i227@mstr_discrete.re~
s(chips)',
 PATH='I227',
 DRAWING='@BASEBOARD_FAB2_LIB.BASEBOARD_FAB2(SCH_1):PAGE232',
 WATTAGE='1/10W',
 TOLERANCE='1%',
 SEC_TYPE='0603',
 MATERIAL='CHIP',
 BOM_COST='PVPP_KLM_VR',
 PHYS_PAGE='232',
 REUSE_ID='34',
 XY='(-2400,3650)',
 ROT='0',
 VER='2',
 VALUE='120.0',
 PACK_TYPE='0603',
 PART_NUMBER='G22026-003',
 LOCATION='R7B10',
 ROOM='PVPP_KLM_VR',
 SEC='1',
 CDS_LIB='mstr_discrete',
 CDS_PART_NAME='RES_0603-120.0,1%,1/10W,CHIP,GA',
 PRIM_FILE='./archive_libs/mstr_discrete/res/chips/chips.prt';

PART_NAME
 R7B11 'RES_0402-0.0,5%,1/16W,CHIP,G21A':
 ROOM='PVPP_KLM_VR';

SECTION_NUMBER 1
 '@BASEBOARD_FAB2_LIB.BASEBOARD_FAB2(SCH_1):PAGE232_I299@MSTR_DISCRETE.RES(CHIPS)':
 C_PATH='@baseboard_fab2_lib.baseboard_fab2(sch_1):page232_i299@mstr_discrete.re~
s(chips)',
 P_PATH='@baseboard_fab2_lib.baseboard_fab2(sch_1):page232_i299@mstr_discrete.re~
s(chips)',
 PATH='I299',
 DRAWING='@BASEBOARD_FAB2_LIB.BASEBOARD_FAB2(SCH_1):PAGE232',
 SPOF='TRUE',
 WATTAGE='1/16W',
 TOLERANCE='5%',
 SEC_TYPE='0402',
 MATERIAL='CHIP',
 PHYS_PAGE='232',
 XY='(-1700,2925)',
 ROT='5',
 VER='1',
 VALUE='0.0',
 PACK_TYPE='0402',
 PART_NUMBER='G21497-005',
 LOCATION='R7B11',
 ROOM='PVPP_KLM_VR',
 SEC='1',
 CDS_LIB='mstr_discrete',
 CDS_PART_NAME='RES_0402-0.0,5%,1/16W,CHIP,G21A',
 PRIM_FILE='./archive_libs/mstr_discrete/res/chips/chips.prt';

PART_NAME
 R7B12 'RES_0402-22.1,1.0%,1/16W,CHIP,A':
 ROOM='PVPP_DEF_VR';

SECTION_NUMBER 1
 '@BASEBOARD_FAB2_LIB.BASEBOARD_FAB2(SCH_1):PAGE232_I257@MSTR_DISCRETE.RES(CHIPS)':
 C_PATH='@baseboard_fab2_lib.baseboard_fab2(sch_1):page232_i257@mstr_discrete.re~
s(chips)',
 P_PATH='@baseboard_fab2_lib.baseboard_fab2(sch_1):page232_i257@mstr_discrete.re~
s(chips)',
 PATH='I257',
 DRAWING='@BASEBOARD_FAB2_LIB.BASEBOARD_FAB2(SCH_1):PAGE232',
 WATTAGE='1/16W',
 TOLERANCE='1.0%',
 SEC_TYPE='0402',
 MATERIAL='CHIP',
 PHYS_PAGE='232',
 XY='(-3650,975)',
 ROT='0',
 VER='1',
 VALUE='22.1',
 PACK_TYPE='0402',
 PART_NUMBER='G21796-250',
 LOCATION='R7B12',
 ROOM='PVPP_DEF_VR',
 SEC='1',
 CDS_LIB='mstr_discrete',
 CDS_PART_NAME='RES_0402-22.1,1.0%,1/16W,CHIP,A',
 PRIM_FILE='./archive_libs/mstr_discrete/res/chips/chips.prt';

PART_NAME
 R7B13 'RES_0402-6.19K,1%,1/16W,CHIP,GA':
 ROOM='IO_SLOT';

SECTION_NUMBER 1
 '@BASEBOARD_FAB2_LIB.BASEBOARD_FAB2(SCH_1):PAGE232_I314@MSTR_DISCRETE.RES(CHIPS)':
 C_PATH='@baseboard_fab2_lib.baseboard_fab2(sch_1):page232_i314@mstr_discrete.re~
s(chips)',
 P_PATH='@baseboard_fab2_lib.baseboard_fab2(sch_1):page232_i314@mstr_discrete.re~
s(chips)',
 PATH='I314',
 DRAWING='@BASEBOARD_FAB2_LIB.BASEBOARD_FAB2(SCH_1):PAGE232',
 WATTAGE='1/16W',
 TOLERANCE='1%',
 SEC_TYPE='0402',
 MATERIAL='CHIP',
 BOM_COST='IO_SLOT',
 PHYS_PAGE='232',
 XY='(-1700,1300)',
 ROT='0',
 VER='2',
 VALUE='6.19K',
 PACK_TYPE='0402',
 PART_NUMBER='G21796-161',
 LOCATION='R7B13',
 ROOM='IO_SLOT',
 SEC='1',
 CDS_LIB='mstr_discrete',
 CDS_PART_NAME='RES_0402-6.19K,1%,1/16W,CHIP,GA',
 PRIM_FILE='./archive_libs/mstr_discrete/res/chips/chips.prt';

PART_NAME
 R7B14 'RES_0402-7.87K,1.0%,1/16W,CHIPA':
 ROOM='PVPP_KLM_VR';

SECTION_NUMBER 1
 '@BASEBOARD_FAB2_LIB.BASEBOARD_FAB2(SCH_1):PAGE232_I315@MSTR_DISCRETE.RES(CHIPS)':
 C_PATH='@baseboard_fab2_lib.baseboard_fab2(sch_1):page232_i315@mstr_discrete.re~
s(chips)',
 P_PATH='@baseboard_fab2_lib.baseboard_fab2(sch_1):page232_i315@mstr_discrete.re~
s(chips)',
 PATH='I315',
 DRAWING='@BASEBOARD_FAB2_LIB.BASEBOARD_FAB2(SCH_1):PAGE232',
 NEW_VALUE='3.9K',
 CONFIG='64.39015.6DL',
 WATTAGE='1/16W',
 TOLERANCE='1.0%',
 MATERIAL='CHIP',
 BOM_COST='PVPP_KLM_VR',
 PHYS_PAGE='232',
 XY='(-5100,1650)',
 ROT='2',
 VER='2',
 VALUE='7.87K',
 PACK_TYPE='0402',
 PART_NUMBER='G21796-242',
 LOCATION='R7B14',
 ROOM='PVPP_KLM_VR',
 CDS_LIB='mstr_discrete',
 CDS_PART_NAME='RES_0402-7.87K,1.0%,1/16W,CHIPA',
 PRIM_FILE='./archive_libs/mstr_discrete/res/chips/chips.prt';

PART_NAME
 R7B15 'RES_0402-20.0K,1%,1/16W,CHIP,GA':
 ROOM='PVPP_KLM_VR',
 REUSE_ID='9';

SECTION_NUMBER 1
 '@BASEBOARD_FAB2_LIB.BASEBOARD_FAB2(SCH_1):PAGE232_I303@MSTR_DISCRETE.RES(CHIPS)':
 C_PATH='@baseboard_fab2_lib.baseboard_fab2(sch_1):page232_i303@mstr_discrete.re~
s(chips)',
 P_PATH='@baseboard_fab2_lib.baseboard_fab2(sch_1):page232_i303@mstr_discrete.re~
s(chips)',
 PATH='I303',
 DRAWING='@BASEBOARD_FAB2_LIB.BASEBOARD_FAB2(SCH_1):PAGE232',
 SPOF='TRUE',
 WATTAGE='1/16W',
 TOLERANCE='1%',
 MATERIAL='CHIP',
 BOM_COST='PVPP_KLM_VR',
 PHYS_PAGE='232',
 REUSE_ID='9',
 XY='(-1700,1850)',
 ROT='0',
 VER='2',
 VALUE='20.0K',
 PACK_TYPE='0402',
 PART_NUMBER='G21796-040',
 LOCATION='R7B15',
 ROOM='PVPP_KLM_VR',
 CDS_LIB='mstr_discrete',
 CDS_PART_NAME='RES_0402-20.0K,1%,1/16W,CHIP,GA',
 PRIM_FILE='./archive_libs/mstr_discrete/res/chips/chips.prt';

PART_NAME
 R7B16 'RES_0402-7.87K,1.0%,1/16W,CHIPA':
 ROOM='PVPP_KLM_VR',
 REUSE_ID='13';

SECTION_NUMBER 1
 '@BASEBOARD_FAB2_LIB.BASEBOARD_FAB2(SCH_1):PAGE232_I300@MSTR_DISCRETE.RES(CHIPS)':
 C_PATH='@baseboard_fab2_lib.baseboard_fab2(sch_1):page232_i300@mstr_discrete.re~
s(chips)',
 P_PATH='@baseboard_fab2_lib.baseboard_fab2(sch_1):page232_i300@mstr_discrete.re~
s(chips)',
 PATH='I300',
 DRAWING='@BASEBOARD_FAB2_LIB.BASEBOARD_FAB2(SCH_1):PAGE232',
 WATTAGE='1/16W',
 TOLERANCE='1.0%',
 SEC_TYPE='0402',
 MATERIAL='CHIP',
 BOM_COST='PVPP_KLM_VR',
 PHYS_PAGE='232',
 REUSE_ID='13',
 XY='(-2400,2450)',
 ROT='0',
 VER='1',
 VALUE='7.87K',
 PACK_TYPE='0402',
 PART_NUMBER='G21796-242',
 LOCATION='R7B16',
 ROOM='PVPP_KLM_VR',
 SEC='1',
 CDS_LIB='mstr_discrete',
 CDS_PART_NAME='RES_0402-7.87K,1.0%,1/16W,CHIPA',
 PRIM_FILE='./archive_libs/mstr_discrete/res/chips/chips.prt';

PART_NAME
 R7B17 'RES_0402-1.00K,1%,1/16W,CHIP,GA':
 ROOM='PVPP_KLM_VR',
 REUSE_ID='21';

SECTION_NUMBER 1
 '@BASEBOARD_FAB2_LIB.BASEBOARD_FAB2(SCH_1):PAGE232_I210@MSTR_DISCRETE.RES(CHIPS)':
 C_PATH='@baseboard_fab2_lib.baseboard_fab2(sch_1):page232_i210@mstr_discrete.re~
s(chips)',
 P_PATH='@baseboard_fab2_lib.baseboard_fab2(sch_1):page232_i210@mstr_discrete.re~
s(chips)',
 PATH='I210',
 DRAWING='@BASEBOARD_FAB2_LIB.BASEBOARD_FAB2(SCH_1):PAGE232',
 WATTAGE='1/16W',
 TOLERANCE='1%',
 SEC_TYPE='0402',
 MATERIAL='CHIP',
 BOM_COST='PVPP_KLM_VR',
 PHYS_PAGE='232',
 REUSE_ID='21',
 XY='(-4575,1250)',
 ROT='0',
 VER='2',
 VALUE='1.00K',
 PACK_TYPE='0402',
 PART_NUMBER='G21796-026',
 LOCATION='R7B17',
 ROOM='PVPP_KLM_VR',
 SEC='1',
 CDS_LIB='mstr_discrete',
 CDS_PART_NAME='RES_0402-1.00K,1%,1/16W,CHIP,GA',
 PRIM_FILE='./archive_libs/mstr_discrete/res/chips/chips.prt';

PART_NAME
 R7B18 'RES_0402-1.0K,0.1%,1/16W,CHIP,A':
 ROOM='PVPP_KLM_VR',
 REUSE_ID='9';

SECTION_NUMBER 1
 '@BASEBOARD_FAB2_LIB.BASEBOARD_FAB2(SCH_1):PAGE232_I298@MSTR_DISCRETE.RES(CHIPS)':
 C_PATH='@baseboard_fab2_lib.baseboard_fab2(sch_1):page232_i298@mstr_discrete.re~
s(chips)',
 P_PATH='@baseboard_fab2_lib.baseboard_fab2(sch_1):page232_i298@mstr_discrete.re~
s(chips)',
 PATH='I298',
 DRAWING='@BASEBOARD_FAB2_LIB.BASEBOARD_FAB2(SCH_1):PAGE232',
 SPOF='TRUE',
 WATTAGE='1/16W',
 TOLERANCE='0.1%',
 SEC_TYPE='0402',
 MATERIAL='CHIP',
 BOM_COST='PVPP_KLM_VR',
 PHYS_PAGE='232',
 REUSE_ID='9',
 XY='(-1350,2525)',
 ROT='0',
 VER='2',
 VALUE='1.0K',
 PACK_TYPE='0402',
 PART_NUMBER='G85996-004',
 LOCATION='R7B18',
 ROOM='PVPP_KLM_VR',
 SEC='1',
 CDS_LIB='mstr_discrete',
 CDS_PART_NAME='RES_0402-1.0K,0.1%,1/16W,CHIP,A',
 PRIM_FILE='./archive_libs/mstr_discrete/res/chips/chips.prt';

PART_NAME
 R7B19 'RES_0603-0,5.0%,1/10W,CHIP,G22A':
 ROOM='NIC_SPRV';

SECTION_NUMBER 1
 '@BASEBOARD_FAB2_LIB.BASEBOARD_FAB2(SCH_1):PAGE232_I313@MSTR_DISCRETE.RES(CHIPS)':
 C_PATH='@baseboard_fab2_lib.baseboard_fab2(sch_1):page232_i313@mstr_discrete.re~
s(chips)',
 P_PATH='@baseboard_fab2_lib.baseboard_fab2(sch_1):page232_i313@mstr_discrete.re~
s(chips)',
 PATH='I313',
 DRAWING='@BASEBOARD_FAB2_LIB.BASEBOARD_FAB2(SCH_1):PAGE232',
 WATTAGE='1/10W',
 TOLERANCE='5.0%',
 SEC_TYPE='0603',
 MATERIAL='CHIP',
 BOM_COST='NT_GBE_BASE',
 PHYS_PAGE='232',
 XY='(-4500,4175)',
 ROT='0',
 VER='1',
 VALUE='0',
 PACK_TYPE='0603',
 PART_NUMBER='G22178-002',
 LOCATION='R7B19',
 ROOM='NIC_SPRV',
 SEC='1',
 CDS_LIB='mstr_discrete',
 CDS_PART_NAME='RES_0603-0,5.0%,1/10W,CHIP,G22A',
 PRIM_FILE='./archive_libs/mstr_discrete/res/chips/chips.prt';

PART_NAME
 R7B20 'RES_0402-0.0,5%,1/16W,CHIP,G21A':
 ROOM='PVPP_KLM_VR';

SECTION_NUMBER 1
 '@BASEBOARD_FAB2_LIB.BASEBOARD_FAB2(SCH_1):PAGE232_I150@MSTR_DISCRETE.RES(CHIPS)':
 C_PATH='@baseboard_fab2_lib.baseboard_fab2(sch_1):page232_i150@mstr_discrete.re~
s(chips)',
 P_PATH='@baseboard_fab2_lib.baseboard_fab2(sch_1):page232_i150@mstr_discrete.re~
s(chips)',
 PATH='I150',
 DRAWING='@BASEBOARD_FAB2_LIB.BASEBOARD_FAB2(SCH_1):PAGE232',
 WATTAGE='1/16W',
 TOLERANCE='5%',
 MATERIAL='CHIP',
 PHYS_PAGE='232',
 XY='(-1575,775)',
 ROT='0',
 VER='1',
 VALUE='0.0',
 PACK_TYPE='0402',
 PART_NUMBER='G21497-005',
 LOCATION='R7B20',
 ROOM='PVPP_KLM_VR',
 CDS_LIB='mstr_discrete',
 CDS_PART_NAME='RES_0402-0.0,5%,1/16W,CHIP,G21A',
 PRIM_FILE='./archive_libs/mstr_discrete/res/chips/chips.prt';

PART_NAME
 R7C1 'RES_0603-200K,0.1%,1/10W,CHIP,A':
 ROOM='SB';

SECTION_NUMBER 1
 '@BASEBOARD_FAB2_LIB.BASEBOARD_FAB2(SCH_1):PAGE114_I48@MSTR_DISCRETE.RES(CHIPS)':
 C_PATH='@baseboard_fab2_lib.baseboard_fab2(sch_1):page114_i48@mstr_discrete.res~
(chips)',
 P_PATH='@baseboard_fab2_lib.baseboard_fab2(sch_1):page114_i48@mstr_discrete.res~
(chips)',
 PATH='I48',
 DRAWING='@BASEBOARD_FAB2_LIB.BASEBOARD_FAB2(SCH_1):PAGE114',
 WATTAGE='1/10W',
 TOLERANCE='0.1%',
 SEC_TYPE='0603',
 MATERIAL='CHIP',
 PHYS_PAGE='114',
 XY='(-1775,475)',
 ROT='0',
 VER='1',
 VALUE='200K',
 PACK_TYPE='0603',
 PART_NUMBER='G22369-010',
 LOCATION='R7C1',
 ROOM='SB',
 SEC='1',
 CDS_LIB='mstr_discrete',
 CDS_PART_NAME='RES_0603-200K,0.1%,1/10W,CHIP,A',
 PRIM_FILE='./archive_libs/mstr_discrete/res/chips/chips.prt';

PART_NAME
 R7C2 'RES_0402-0.0,5%,1/16W,CHIP,G21A':
 GROUP='AST2500',
 ROOM='CPU0';

SECTION_NUMBER 1
 '@BASEBOARD_FAB2_LIB.BASEBOARD_FAB2(SCH_1):PAGE114_I192@MSTR_DISCRETE.RES(CHIPS)':
 C_PATH='@baseboard_fab2_lib.baseboard_fab2(sch_1):page114_i192@mstr_discrete.re~
s(chips)',
 P_PATH='@baseboard_fab2_lib.baseboard_fab2(sch_1):page114_i192@mstr_discrete.re~
s(chips)',
 PATH='I192',
 DRAWING='@BASEBOARD_FAB2_LIB.BASEBOARD_FAB2(SCH_1):PAGE114',
 WATTAGE='1/16W',
 TOLERANCE='5%',
 SEC_TYPE='0402',
 MATERIAL='CHIP',
 BOM_COST='PROC_SIDEBAND',
 PHYS_PAGE='114',
 XY='(-1275,2800)',
 ROT='0',
 VER='1',
 VALUE='0.0',
 PACK_TYPE='0402',
 PART_NUMBER='G21497-005',
 LOCATION='R7C2',
 ROOM='CPU0',
 GROUP='AST2500',
 SEC='1',
 CDS_LIB='mstr_discrete',
 CDS_PART_NAME='RES_0402-0.0,5%,1/16W,CHIP,G21A',
 PRIM_FILE='./archive_libs/mstr_discrete/res/chips/chips.prt';

PART_NAME
 R7C3 'RES_0402-51.1,1.0%,1/16W,CHIP,A':;

SECTION_NUMBER 1
 '@BASEBOARD_FAB2_LIB.BASEBOARD_FAB2(SCH_1):PAGE212_I78@MSTR_DISCRETE.RES(CHIPS)':
 C_PATH='@baseboard_fab2_lib.baseboard_fab2(sch_1):page212_i78@mstr_discrete.res~
(chips)',
 P_PATH='@baseboard_fab2_lib.baseboard_fab2(sch_1):page212_i78@mstr_discrete.res~
(chips)',
 PATH='I78',
 DRAWING='@BASEBOARD_FAB2_LIB.BASEBOARD_FAB2(SCH_1):PAGE212',
 WATTAGE='1/16W',
 TOLERANCE='1.0%',
 SEC_TYPE='0402',
 MATERIAL='CHIP',
 PHYS_PAGE='212',
 XY='(4025,3450)',
 ROT='0',
 VER='2',
 VALUE='51.1',
 PACK_TYPE='0402',
 PART_NUMBER='G21796-208',
 LOCATION='R7C3',
 SEC='1',
 CDS_LIB='mstr_discrete',
 CDS_PART_NAME='RES_0402-51.1,1.0%,1/16W,CHIP,A',
 PRIM_FILE='./archive_libs/mstr_discrete/res/chips/chips.prt';

PART_NAME
 R7C4 'RES_0402-0.0,5%,1/16W,CHIP,G21A':
 GROUP='AST2500',
 ROOM='CPU0';

SECTION_NUMBER 1
 '@BASEBOARD_FAB2_LIB.BASEBOARD_FAB2(SCH_1):PAGE114_I191@MSTR_DISCRETE.RES(CHIPS)':
 C_PATH='@baseboard_fab2_lib.baseboard_fab2(sch_1):page114_i191@mstr_discrete.re~
s(chips)',
 P_PATH='@baseboard_fab2_lib.baseboard_fab2(sch_1):page114_i191@mstr_discrete.re~
s(chips)',
 PATH='I191',
 DRAWING='@BASEBOARD_FAB2_LIB.BASEBOARD_FAB2(SCH_1):PAGE114',
 WATTAGE='1/16W',
 TOLERANCE='5%',
 SEC_TYPE='0402',
 MATERIAL='CHIP',
 BOM_COST='PROC_SIDEBAND',
 PHYS_PAGE='114',
 XY='(-1625,2850)',
 ROT='0',
 VER='1',
 VALUE='0.0',
 PACK_TYPE='0402',
 PART_NUMBER='G21497-005',
 LOCATION='R7C4',
 ROOM='CPU0',
 GROUP='AST2500',
 SEC='1',
 CDS_LIB='mstr_discrete',
 CDS_PART_NAME='RES_0402-0.0,5%,1/16W,CHIP,G21A',
 PRIM_FILE='./archive_libs/mstr_discrete/res/chips/chips.prt';

PART_NAME
 R7C5 'RES_0402-10.0K,1%,1/16W,CHIP,GA':
 ROOM='SB_PU_PD';

SECTION_NUMBER 1
 '@BASEBOARD_FAB2_LIB.BASEBOARD_FAB2(SCH_1):PAGE133_I297@MSTR_DISCRETE.RES(CHIPS)':
 C_PATH='@baseboard_fab2_lib.baseboard_fab2(sch_1):page133_i297@mstr_discrete.re~
s(chips)',
 P_PATH='@baseboard_fab2_lib.baseboard_fab2(sch_1):page133_i297@mstr_discrete.re~
s(chips)',
 PATH='I297',
 DRAWING='@BASEBOARD_FAB2_LIB.BASEBOARD_FAB2(SCH_1):PAGE133',
 WATTAGE='1/16W',
 TOLERANCE='1%',
 SEC_TYPE='0402',
 MATERIAL='CHIP',
 PHYS_PAGE='133',
 XY='(-650,1425)',
 ROT='0',
 VER='2',
 VALUE='10.0K',
 PACK_TYPE='0402',
 PART_NUMBER='G21796-016',
 LOCATION='R7C5',
 ROOM='SB_PU_PD',
 SEC='1',
 CDS_LIB='mstr_discrete',
 CDS_PART_NAME='RES_0402-10.0K,1%,1/16W,CHIP,GA',
 PRIM_FILE='./archive_libs/mstr_discrete/res/chips/chips.prt';

PART_NAME
 R7C6 'RES_0603-10M,1.0%,1/10W,CHIP,GA':
 ROOM='SB';

SECTION_NUMBER 1
 '@BASEBOARD_FAB2_LIB.BASEBOARD_FAB2(SCH_1):PAGE114_I54@MSTR_DISCRETE.RES(CHIPS)':
 C_PATH='@baseboard_fab2_lib.baseboard_fab2(sch_1):page114_i54@mstr_discrete.res~
(chips)',
 P_PATH='@baseboard_fab2_lib.baseboard_fab2(sch_1):page114_i54@mstr_discrete.res~
(chips)',
 PATH='I54',
 DRAWING='@BASEBOARD_FAB2_LIB.BASEBOARD_FAB2(SCH_1):PAGE114',
 WATTAGE='1/10W',
 TOLERANCE='1.0%',
 MATERIAL='CHIP',
 BOM_COST='SYS_CLOCK',
 PHYS_PAGE='114',
 XY='(-25,475)',
 ROT='0',
 VER='1',
 VALUE='10M',
 PACK_TYPE='0603',
 PART_NUMBER='G22026-112',
 LOCATION='R7C6',
 ROOM='SB',
 CDS_LIB='mstr_discrete',
 CDS_PART_NAME='RES_0603-10M,1.0%,1/10W,CHIP,GA',
 PRIM_FILE='./archive_libs/mstr_discrete/res/chips/chips.prt';

PART_NAME
 R7C8 'RES_0402-10.0K,1%,1/16W,CHIP,GA':
 ROOM='SB_PU_PD';

SECTION_NUMBER 1
 '@BASEBOARD_FAB2_LIB.BASEBOARD_FAB2(SCH_1):PAGE133_I296@MSTR_DISCRETE.RES(CHIPS)':
 C_PATH='@baseboard_fab2_lib.baseboard_fab2(sch_1):page133_i296@mstr_discrete.re~
s(chips)',
 P_PATH='@baseboard_fab2_lib.baseboard_fab2(sch_1):page133_i296@mstr_discrete.re~
s(chips)',
 PATH='I296',
 DRAWING='@BASEBOARD_FAB2_LIB.BASEBOARD_FAB2(SCH_1):PAGE133',
 WATTAGE='1/16W',
 TOLERANCE='1%',
 SEC_TYPE='0402',
 MATERIAL='CHIP',
 PHYS_PAGE='133',
 XY='(-425,1425)',
 ROT='0',
 VER='2',
 VALUE='10.0K',
 PACK_TYPE='0402',
 PART_NUMBER='G21796-016',
 LOCATION='R7C8',
 ROOM='SB_PU_PD',
 SEC='1',
 CDS_LIB='mstr_discrete',
 CDS_PART_NAME='RES_0402-10.0K,1%,1/16W,CHIP,GA',
 PRIM_FILE='./archive_libs/mstr_discrete/res/chips/chips.prt';

PART_NAME
 R7C10 'RES_0402-20.0K,1%,1/16W,CHIP,GA':
 ROOM='SB',
 NO_XNET_CONNECTION='1';

SECTION_NUMBER 1
 '@BASEBOARD_FAB2_LIB.BASEBOARD_FAB2(SCH_1):PAGE137_I13@MSTR_DISCRETE.RES(CHIPS)':
 C_PATH='@baseboard_fab2_lib.baseboard_fab2(sch_1):page137_i13@mstr_discrete.res~
(chips)',
 P_PATH='@baseboard_fab2_lib.baseboard_fab2(sch_1):page137_i13@mstr_discrete.res~
(chips)',
 PATH='I13',
 DRAWING='@BASEBOARD_FAB2_LIB.BASEBOARD_FAB2(SCH_1):PAGE137',
 WATTAGE='1/16W',
 TOLERANCE='1%',
 SEC_TYPE='0402',
 MATERIAL='CHIP',
 BOM_COST='SB',
 NO_XNET_CONNECTION='1',
 PHYS_PAGE='137',
 XY='(-200,4025)',
 ROT='0',
 VER='2',
 VALUE='20.0K',
 PACK_TYPE='0402',
 PART_NUMBER='G21796-040',
 LOCATION='R7C10',
 ROOM='SB',
 SEC='1',
 CDS_LIB='mstr_discrete',
 CDS_PART_NAME='RES_0402-20.0K,1%,1/16W,CHIP,GA',
 PRIM_FILE='./archive_libs/mstr_discrete/res/chips/chips.prt';

PART_NAME
 R7C11 'RES_0402-1.0M,1%,1/16W,EMPTY,GA':
 ROOM='SB';

SECTION_NUMBER 1
 '@BASEBOARD_FAB2_LIB.BASEBOARD_FAB2(SCH_1):PAGE137_I11@MSTR_DISCRETE.RES(CHIPS)':
 C_PATH='@baseboard_fab2_lib.baseboard_fab2(sch_1):page137_i11@mstr_discrete.res~
(chips)',
 P_PATH='@baseboard_fab2_lib.baseboard_fab2(sch_1):page137_i11@mstr_discrete.res~
(chips)',
 PATH='I11',
 DRAWING='@BASEBOARD_FAB2_LIB.BASEBOARD_FAB2(SCH_1):PAGE137',
 WATTAGE='1/16W',
 TOLERANCE='1%',
 MATERIAL='EMPTY',
 BOM_COST='SB',
 PHYS_PAGE='137',
 XY='(325,3450)',
 ROT='1',
 VER='1',
 VALUE='1.0M',
 PACK_TYPE='0402',
 PART_NUMBER='G21796-021',
 LOCATION='R7C11',
 ROOM='SB',
 CDS_LIB='mstr_discrete',
 CDS_PART_NAME='RES_0402-1.0M,1%,1/16W,EMPTY,GA',
 PRIM_FILE='./archive_libs/mstr_discrete/res/chips/chips.prt';

PART_NAME
 R7C13 'RES_0402-10.0K,1%,1/16W,CHIP,GA':
 ROOM='SB';

SECTION_NUMBER 1
 '@BASEBOARD_FAB2_LIB.BASEBOARD_FAB2(SCH_1):PAGE137_I67@MSTR_DISCRETE.RES(CHIPS)':
 C_PATH='@baseboard_fab2_lib.baseboard_fab2(sch_1):page137_i67@mstr_discrete.res~
(chips)',
 P_PATH='@baseboard_fab2_lib.baseboard_fab2(sch_1):page137_i67@mstr_discrete.res~
(chips)',
 PATH='I67',
 DRAWING='@BASEBOARD_FAB2_LIB.BASEBOARD_FAB2(SCH_1):PAGE137',
 WATTAGE='1/16W',
 TOLERANCE='1%',
 SEC_TYPE='0402',
 MATERIAL='CHIP',
 BOM_COST='SB',
 PHYS_PAGE='137',
 XY='(-2650,4225)',
 ROT='0',
 VER='2',
 VALUE='10.0K',
 PACK_TYPE='0402',
 PART_NUMBER='G21796-016',
 LOCATION='R7C13',
 ROOM='SB',
 SEC='1',
 CDS_LIB='mstr_discrete',
 CDS_PART_NAME='RES_0402-10.0K,1%,1/16W,CHIP,GA',
 PRIM_FILE='./archive_libs/mstr_discrete/res/chips/chips.prt';

PART_NAME
 R7C14 'RES_0402-33.2,1%,1/16W,CHIP,G2A':
 ROOM='SB';

SECTION_NUMBER 1
 '@BASEBOARD_FAB2_LIB.BASEBOARD_FAB2(SCH_1):PAGE121_I98@MSTR_DISCRETE.RES(CHIPS)':
 C_PATH='@baseboard_fab2_lib.baseboard_fab2(sch_1):page121_i98@mstr_discrete.res~
(chips)',
 P_PATH='@baseboard_fab2_lib.baseboard_fab2(sch_1):page121_i98@mstr_discrete.res~
(chips)',
 PATH='I98',
 DRAWING='@BASEBOARD_FAB2_LIB.BASEBOARD_FAB2(SCH_1):PAGE121',
 WATTAGE='1/16W',
 TOLERANCE='1%',
 SEC_TYPE='0402',
 MATERIAL='CHIP',
 PHYS_PAGE='121',
 XY='(-5100,1025)',
 ROT='0',
 VER='1',
 VALUE='33.2',
 PACK_TYPE='0402',
 PART_NUMBER='G21796-074',
 LOCATION='R7C14',
 ROOM='SB',
 SEC='1',
 CDS_LIB='mstr_discrete',
 CDS_PART_NAME='RES_0402-33.2,1%,1/16W,CHIP,G2A',
 PRIM_FILE='./archive_libs/mstr_discrete/res/chips/chips.prt';

PART_NAME
 R7C15 'RES_0402-0.0,5%,1/16W,CHIP,G21A':
 ROOM='SB';

SECTION_NUMBER 1
 '@BASEBOARD_FAB2_LIB.BASEBOARD_FAB2(SCH_1):PAGE121_I31@MSTR_DISCRETE.RES(CHIPS)':
 C_PATH='@baseboard_fab2_lib.baseboard_fab2(sch_1):page121_i31@mstr_discrete.res~
(chips)',
 P_PATH='@baseboard_fab2_lib.baseboard_fab2(sch_1):page121_i31@mstr_discrete.res~
(chips)',
 PATH='I31',
 DRAWING='@BASEBOARD_FAB2_LIB.BASEBOARD_FAB2(SCH_1):PAGE121',
 WATTAGE='1/16W',
 TOLERANCE='5%',
 MATERIAL='CHIP',
 PHYS_PAGE='121',
 XY='(-1925,3150)',
 ROT='0',
 VER='1',
 VALUE='0.0',
 PACK_TYPE='0402',
 PART_NUMBER='G21497-005',
 LOCATION='R7C15',
 ROOM='SB',
 CDS_LIB='mstr_discrete',
 CDS_PART_NAME='RES_0402-0.0,5%,1/16W,CHIP,G21A',
 PRIM_FILE='./archive_libs/mstr_discrete/res/chips/chips.prt';

PART_NAME
 R7C16 'RES_0402-33.2,1%,1/16W,CHIP,G2A':
 ROOM='SB';

SECTION_NUMBER 1
 '@BASEBOARD_FAB2_LIB.BASEBOARD_FAB2(SCH_1):PAGE121_I33@MSTR_DISCRETE.RES(CHIPS)':
 C_PATH='@baseboard_fab2_lib.baseboard_fab2(sch_1):page121_i33@mstr_discrete.res~
(chips)',
 P_PATH='@baseboard_fab2_lib.baseboard_fab2(sch_1):page121_i33@mstr_discrete.res~
(chips)',
 PATH='I33',
 DRAWING='@BASEBOARD_FAB2_LIB.BASEBOARD_FAB2(SCH_1):PAGE121',
 WATTAGE='1/16W',
 TOLERANCE='1%',
 MATERIAL='CHIP',
 PHYS_PAGE='121',
 XY='(-1950,3550)',
 ROT='0',
 VER='1',
 VALUE='33.2',
 PACK_TYPE='0402',
 PART_NUMBER='G21796-074',
 LOCATION='R7C16',
 ROOM='SB',
 CDS_LIB='mstr_discrete',
 CDS_PART_NAME='RES_0402-33.2,1%,1/16W,CHIP,G2A',
 PRIM_FILE='./archive_libs/mstr_discrete/res/chips/chips.prt';

PART_NAME
 R7C17 'RES_0402-4.75K,1%,1/16W,CHIP,GA':
 ROOM='PECI';

SECTION_NUMBER 1
 '@BASEBOARD_FAB2_LIB.BASEBOARD_FAB2(SCH_1):PAGE166_I28@MSTR_DISCRETE.RES(CHIPS)':
 C_PATH='@baseboard_fab2_lib.baseboard_fab2(sch_1):page166_i28@mstr_discrete.res~
(chips)',
 P_PATH='@baseboard_fab2_lib.baseboard_fab2(sch_1):page166_i28@mstr_discrete.res~
(chips)',
 PATH='I28',
 DRAWING='@BASEBOARD_FAB2_LIB.BASEBOARD_FAB2(SCH_1):PAGE166',
 WATTAGE='1/16W',
 TOLERANCE='1%',
 SEC_TYPE='0402',
 MATERIAL='CHIP',
 BOM_COST='DEBUG',
 PHYS_PAGE='166',
 XY='(-5050,3500)',
 ROT='2',
 VER='2',
 VALUE='4.75K',
 PACK_TYPE='0402',
 PART_NUMBER='G21796-072',
 LOCATION='R7C17',
 ROOM='PECI',
 SEC='1',
 CDS_LIB='mstr_discrete',
 CDS_PART_NAME='RES_0402-4.75K,1%,1/16W,CHIP,GA',
 PRIM_FILE='./archive_libs/mstr_discrete/res/chips/chips.prt';

PART_NAME
 R7C20 'RES_0402-10.0K,1%,1/16W,CHIP,GA':
 ROOM='NIC_SPRV';

SECTION_NUMBER 1
 '@BASEBOARD_FAB2_LIB.BASEBOARD_FAB2(SCH_1):PAGE121_I73@MSTR_DISCRETE.RES(CHIPS)':
 C_PATH='@baseboard_fab2_lib.baseboard_fab2(sch_1):page121_i73@mstr_discrete.res~
(chips)',
 P_PATH='@baseboard_fab2_lib.baseboard_fab2(sch_1):page121_i73@mstr_discrete.res~
(chips)',
 PATH='I73',
 DRAWING='@BASEBOARD_FAB2_LIB.BASEBOARD_FAB2(SCH_1):PAGE121',
 WATTAGE='1/16W',
 TOLERANCE='1%',
 SEC_TYPE='0402',
 MATERIAL='CHIP',
 BOM_COST='NT_GBE_BASE',
 PHYS_PAGE='121',
 XY='(-8125,950)',
 ROT='0',
 VER='2',
 VALUE='10.0K',
 PACK_TYPE='0402',
 PART_NUMBER='G21796-016',
 LOCATION='R7C20',
 ROOM='NIC_SPRV',
 SEC='1',
 CDS_LIB='mstr_discrete',
 CDS_PART_NAME='RES_0402-10.0K,1%,1/16W,CHIP,GA',
 PRIM_FILE='./archive_libs/mstr_discrete/res/chips/chips.prt';

PART_NAME
 R7C21 'RES_0402-10.0K,1%,1/16W,CHIP,GA':
 ROOM='THERMTRIP_PCH';

SECTION_NUMBER 1
 '@BASEBOARD_FAB2_LIB.BASEBOARD_FAB2(SCH_1):PAGE134_I9@MSTR_DISCRETE.RES(CHIPS)':
 C_PATH='@baseboard_fab2_lib.baseboard_fab2(sch_1):page134_i9@mstr_discrete.res(~
chips)',
 P_PATH='@baseboard_fab2_lib.baseboard_fab2(sch_1):page134_i9@mstr_discrete.res(~
chips)',
 PATH='I9',
 DRAWING='@BASEBOARD_FAB2_LIB.BASEBOARD_FAB2(SCH_1):PAGE134',
 WATTAGE='1/16W',
 TOLERANCE='1%',
 SEC_TYPE='0402',
 MATERIAL='CHIP',
 BOM_COST='SB',
 PHYS_PAGE='134',
 XY='(-2875,4875)',
 ROT='0',
 VER='2',
 VALUE='10.0K',
 PACK_TYPE='0402',
 PART_NUMBER='G21796-016',
 LOCATION='R7C21',
 ROOM='THERMTRIP_PCH',
 SEC='1',
 CDS_LIB='mstr_discrete',
 CDS_PART_NAME='RES_0402-10.0K,1%,1/16W,CHIP,GA',
 PRIM_FILE='./archive_libs/mstr_discrete/res/chips/chips.prt';

PART_NAME
 R7C23 'RES_0402-10.0K,1%,1/16W,CHIP,GA':
 ROOM='SB';

SECTION_NUMBER 1
 '@BASEBOARD_FAB2_LIB.BASEBOARD_FAB2(SCH_1):PAGE118_I144@MSTR_DISCRETE.RES(CHIPS)':
 C_PATH='@baseboard_fab2_lib.baseboard_fab2(sch_1):page118_i144@mstr_discrete.re~
s(chips)',
 P_PATH='@baseboard_fab2_lib.baseboard_fab2(sch_1):page118_i144@mstr_discrete.re~
s(chips)',
 PATH='I144',
 DRAWING='@BASEBOARD_FAB2_LIB.BASEBOARD_FAB2(SCH_1):PAGE118',
 WATTAGE='1/16W',
 TOLERANCE='1%',
 SEC_TYPE='0402',
 MATERIAL='CHIP',
 BOM_COST='SB',
 PHYS_PAGE='118',
 XY='(-5175,1275)',
 ROT='0',
 VER='2',
 VALUE='10.0K',
 PACK_TYPE='0402',
 PART_NUMBER='G21796-016',
 LOCATION='R7C23',
 ROOM='SB',
 SEC='1',
 CDS_LIB='mstr_discrete',
 CDS_PART_NAME='RES_0402-10.0K,1%,1/16W,CHIP,GA',
 PRIM_FILE='./archive_libs/mstr_discrete/res/chips/chips.prt';

PART_NAME
 R7C24 'RES_0402-4.02K,1%,1/16W,CHIP,GA':
 GROUP='MCP',
 ROOM='PVCCIN_CPU1_VR';

SECTION_NUMBER 1
 '@BASEBOARD_FAB2_LIB.BASEBOARD_FAB2(SCH_1):PAGE194_I155@MSTR_DISCRETE.RES(CHIPS)':
 C_PATH='@baseboard_fab2_lib.baseboard_fab2(sch_1):page194_i155@mstr_discrete.re~
s(chips)',
 P_PATH='@baseboard_fab2_lib.baseboard_fab2(sch_1):page194_i155@mstr_discrete.re~
s(chips)',
 PATH='I155',
 DRAWING='@BASEBOARD_FAB2_LIB.BASEBOARD_FAB2(SCH_1):PAGE194',
 WATTAGE='1/16W',
 TOLERANCE='1%',
 SEC_TYPE='0402',
 MATERIAL='CHIP',
 PHYS_PAGE='194',
 XY='(-7825,100)',
 ROT='0',
 VER='2',
 VALUE='4.02K',
 PACK_TYPE='0402',
 PART_NUMBER='G21796-082',
 LOCATION='R7C24',
 ROOM='PVCCIN_CPU1_VR',
 GROUP='MCP',
 SEC='1',
 CDS_LIB='mstr_discrete',
 CDS_PART_NAME='RES_0402-4.02K,1%,1/16W,CHIP,GA',
 PRIM_FILE='./archive_libs/mstr_discrete/res/chips/chips.prt';

PART_NAME
 R7C25 'RES_0402-68.1K,1%,1/16W,EMPTY,A':;

SECTION_NUMBER 1
 '@BASEBOARD_FAB2_LIB.BASEBOARD_FAB2(SCH_1):PAGE212_I103@MSTR_DISCRETE.RES(CHIPS)':
 C_PATH='@baseboard_fab2_lib.baseboard_fab2(sch_1):page212_i103@mstr_discrete.re~
s(chips)',
 P_PATH='@baseboard_fab2_lib.baseboard_fab2(sch_1):page212_i103@mstr_discrete.re~
s(chips)',
 PATH='I103',
 DRAWING='@BASEBOARD_FAB2_LIB.BASEBOARD_FAB2(SCH_1):PAGE212',
 WATTAGE='1/16W',
 TOLERANCE='1%',
 MATERIAL='EMPTY',
 PHYS_PAGE='212',
 XY='(3525,4125)',
 ROT='0',
 VER='2',
 VALUE='68.1K',
 PACK_TYPE='0402',
 PART_NUMBER='G21796-187',
 LOCATION='R7C25',
 CDS_LIB='mstr_discrete',
 CDS_PART_NAME='RES_0402-68.1K,1%,1/16W,EMPTY,A',
 PRIM_FILE='./archive_libs/mstr_discrete/res/chips/chips.prt';

PART_NAME
 R7C26 'RES_0402-33.2,1%,1/16W,CHIP,G2A':
 ROOM='SYS_CLOCK';

SECTION_NUMBER 1
 '@BASEBOARD_FAB2_LIB.BASEBOARD_FAB2(SCH_1):PAGE119_I189@MSTR_DISCRETE.RES(CHIPS)':
 C_PATH='@baseboard_fab2_lib.baseboard_fab2(sch_1):page119_i189@mstr_discrete.re~
s(chips)',
 P_PATH='@baseboard_fab2_lib.baseboard_fab2(sch_1):page119_i189@mstr_discrete.re~
s(chips)',
 PATH='I189',
 DRAWING='@BASEBOARD_FAB2_LIB.BASEBOARD_FAB2(SCH_1):PAGE119',
 WATTAGE='1/16W',
 TOLERANCE='1%',
 SEC_TYPE='0402',
 MATERIAL='CHIP',
 BOM_COST='SM_CONTROLLER',
 PHYS_PAGE='119',
 XY='(-6750,3700)',
 ROT='0',
 VER='1',
 VALUE='33.2',
 PACK_TYPE='0402',
 PART_NUMBER='G21796-074',
 LOCATION='R7C26',
 ROOM='SYS_CLOCK',
 SEC='1',
 CDS_LIB='mstr_discrete',
 CDS_PART_NAME='RES_0402-33.2,1%,1/16W,CHIP,G2A',
 PRIM_FILE='./archive_libs/mstr_discrete/res/chips/chips.prt';

PART_NAME
 R7D1 'RES_0402-1.00K,1%,1/16W,EMPTY,A':
 ROOM='SB';

SECTION_NUMBER 1
 '@BASEBOARD_FAB2_LIB.BASEBOARD_FAB2(SCH_1):PAGE125_I86@MSTR_DISCRETE.RES(CHIPS)':
 C_PATH='@baseboard_fab2_lib.baseboard_fab2(sch_1):page125_i86@mstr_discrete.res~
(chips)',
 P_PATH='@baseboard_fab2_lib.baseboard_fab2(sch_1):page125_i86@mstr_discrete.res~
(chips)',
 PATH='I86',
 DRAWING='@BASEBOARD_FAB2_LIB.BASEBOARD_FAB2(SCH_1):PAGE125',
 WATTAGE='1/16W',
 TOLERANCE='1%',
 MATERIAL='EMPTY',
 BOM_COST='SB',
 PHYS_PAGE='125',
 XY='(-5050,3375)',
 ROT='0',
 VER='2',
 VALUE='1.00K',
 PACK_TYPE='0402',
 PART_NUMBER='G21796-026',
 LOCATION='R7D1',
 ROOM='SB',
 CDS_LIB='mstr_discrete',
 CDS_PART_NAME='RES_0402-1.00K,1%,1/16W,EMPTY,A',
 PRIM_FILE='./archive_libs/mstr_discrete/res/chips/chips.prt';

PART_NAME
 R7D2 'RES_0402-1.00K,1%,1/16W,CHIP,GA':
 ROOM='SB';

SECTION_NUMBER 1
 '@BASEBOARD_FAB2_LIB.BASEBOARD_FAB2(SCH_1):PAGE133_I332@MSTR_DISCRETE.RES(CHIPS)':
 C_PATH='@baseboard_fab2_lib.baseboard_fab2(sch_1):page133_i332@mstr_discrete.re~
s(chips)',
 P_PATH='@baseboard_fab2_lib.baseboard_fab2(sch_1):page133_i332@mstr_discrete.re~
s(chips)',
 PATH='I332',
 DRAWING='@BASEBOARD_FAB2_LIB.BASEBOARD_FAB2(SCH_1):PAGE133',
 WATTAGE='1/16W',
 TOLERANCE='1%',
 SEC_TYPE='0402',
 MATERIAL='CHIP',
 BOM_COST='SB_PU_PD',
 PHYS_PAGE='133',
 XY='(-4700,5100)',
 ROT='0',
 VER='1',
 VALUE='1.00K',
 PACK_TYPE='0402',
 PART_NUMBER='G21796-026',
 LOCATION='R7D2',
 ROOM='SB',
 SEC='1',
 CDS_LIB='mstr_discrete',
 CDS_PART_NAME='RES_0402-1.00K,1%,1/16W,CHIP,GA',
 PRIM_FILE='./archive_libs/mstr_discrete/res/chips/chips.prt';

PART_NAME
 R7D3 'RES_0402-4.75K,1%,1/16W,CHIP,GA':
 ROOM='SB';

SECTION_NUMBER 1
 '@BASEBOARD_FAB2_LIB.BASEBOARD_FAB2(SCH_1):PAGE133_I243@MSTR_DISCRETE.RES(CHIPS)':
 C_PATH='@baseboard_fab2_lib.baseboard_fab2(sch_1):page133_i243@mstr_discrete.re~
s(chips)',
 P_PATH='@baseboard_fab2_lib.baseboard_fab2(sch_1):page133_i243@mstr_discrete.re~
s(chips)',
 PATH='I243',
 DRAWING='@BASEBOARD_FAB2_LIB.BASEBOARD_FAB2(SCH_1):PAGE133',
 WATTAGE='1/16W',
 TOLERANCE='1%',
 SEC_TYPE='0402',
 MATERIAL='CHIP',
 PHYS_PAGE='133',
 XY='(-4700,4900)',
 ROT='0',
 VER='1',
 VALUE='4.75K',
 PACK_TYPE='0402',
 PART_NUMBER='G21796-072',
 LOCATION='R7D3',
 ROOM='SB',
 SEC='1',
 CDS_LIB='mstr_discrete',
 CDS_PART_NAME='RES_0402-4.75K,1%,1/16W,CHIP,GA',
 PRIM_FILE='./archive_libs/mstr_discrete/res/chips/chips.prt';

PART_NAME
 R7D4 'RES_0402-10.0K,1%,1/16W,CHIP,GA':
 ROOM='SB';

SECTION_NUMBER 1
 '@BASEBOARD_FAB2_LIB.BASEBOARD_FAB2(SCH_1):PAGE133_I245@MSTR_DISCRETE.RES(CHIPS)':
 C_PATH='@baseboard_fab2_lib.baseboard_fab2(sch_1):page133_i245@mstr_discrete.re~
s(chips)',
 P_PATH='@baseboard_fab2_lib.baseboard_fab2(sch_1):page133_i245@mstr_discrete.re~
s(chips)',
 PATH='I245',
 DRAWING='@BASEBOARD_FAB2_LIB.BASEBOARD_FAB2(SCH_1):PAGE133',
 WATTAGE='1/16W',
 TOLERANCE='1%',
 SEC_TYPE='0402',
 MATERIAL='CHIP',
 PHYS_PAGE='133',
 XY='(-4700,4125)',
 ROT='0',
 VER='1',
 VALUE='10.0K',
 PACK_TYPE='0402',
 PART_NUMBER='G21796-016',
 LOCATION='R7D4',
 ROOM='SB',
 SEC='1',
 CDS_LIB='mstr_discrete',
 CDS_PART_NAME='RES_0402-10.0K,1%,1/16W,CHIP,GA',
 PRIM_FILE='./archive_libs/mstr_discrete/res/chips/chips.prt';

PART_NAME
 R7D5 'RES_0402-2.26K,1.0%,1/16W,CHIPA':
 ROOM='IO_SLOT';

SECTION_NUMBER 1
 '@BASEBOARD_FAB2_LIB.BASEBOARD_FAB2(SCH_1):PAGE181_I82@MSTR_DISCRETE.RES(CHIPS)':
 C_PATH='@baseboard_fab2_lib.baseboard_fab2(sch_1):page181_i82@mstr_discrete.res~
(chips)',
 P_PATH='@baseboard_fab2_lib.baseboard_fab2(sch_1):page181_i82@mstr_discrete.res~
(chips)',
 PATH='I82',
 DRAWING='@BASEBOARD_FAB2_LIB.BASEBOARD_FAB2(SCH_1):PAGE181',
 WATTAGE='1/16W',
 TOLERANCE='1.0%',
 SEC_TYPE='0402',
 MATERIAL='CHIP',
 PHYS_PAGE='181',
 XY='(2650,2225)',
 ROT='0',
 VER='1',
 VALUE='2.26K',
 PACK_TYPE='0402',
 PART_NUMBER='G21796-311',
 LOCATION='R7D5',
 ROOM='IO_SLOT',
 SEC='1',
 CDS_LIB='mstr_discrete',
 CDS_PART_NAME='RES_0402-2.26K,1.0%,1/16W,CHIPA',
 PRIM_FILE='./archive_libs/mstr_discrete/res/chips/chips.prt';

PART_NAME
 R7D6 'RES_0402-4.75K,1%,1/16W,CHIP,GA':
 ROOM='SB_PU_PD';

SECTION_NUMBER 1
 '@BASEBOARD_FAB2_LIB.BASEBOARD_FAB2(SCH_1):PAGE133_I306@MSTR_DISCRETE.RES(CHIPS)':
 C_PATH='@baseboard_fab2_lib.baseboard_fab2(sch_1):page133_i306@mstr_discrete.re~
s(chips)',
 P_PATH='@baseboard_fab2_lib.baseboard_fab2(sch_1):page133_i306@mstr_discrete.re~
s(chips)',
 PATH='I306',
 DRAWING='@BASEBOARD_FAB2_LIB.BASEBOARD_FAB2(SCH_1):PAGE133',
 WATTAGE='1/16W',
 TOLERANCE='1%',
 SEC_TYPE='0402',
 MATERIAL='CHIP',
 PHYS_PAGE='133',
 XY='(-4700,3700)',
 ROT='0',
 VER='1',
 VALUE='4.75K',
 PACK_TYPE='0402',
 PART_NUMBER='G21796-072',
 LOCATION='R7D6',
 ROOM='SB_PU_PD',
 SEC='1',
 CDS_LIB='mstr_discrete',
 CDS_PART_NAME='RES_0402-4.75K,1%,1/16W,CHIP,GA',
 PRIM_FILE='./archive_libs/mstr_discrete/res/chips/chips.prt';

PART_NAME
 R7D7 'RES_0402-1.00K,1%,1/16W,CHIP,GA':
 ROOM='SB';

SECTION_NUMBER 1
 '@BASEBOARD_FAB2_LIB.BASEBOARD_FAB2(SCH_1):PAGE133_I331@MSTR_DISCRETE.RES(CHIPS)':
 C_PATH='@baseboard_fab2_lib.baseboard_fab2(sch_1):page133_i331@mstr_discrete.re~
s(chips)',
 P_PATH='@baseboard_fab2_lib.baseboard_fab2(sch_1):page133_i331@mstr_discrete.re~
s(chips)',
 PATH='I331',
 DRAWING='@BASEBOARD_FAB2_LIB.BASEBOARD_FAB2(SCH_1):PAGE133',
 WATTAGE='1/16W',
 TOLERANCE='1%',
 SEC_TYPE='0402',
 MATERIAL='CHIP',
 BOM_COST='SB_PU_PD',
 PHYS_PAGE='133',
 XY='(-4700,4700)',
 ROT='0',
 VER='1',
 VALUE='1.00K',
 PACK_TYPE='0402',
 PART_NUMBER='G21796-026',
 LOCATION='R7D7',
 ROOM='SB',
 SEC='1',
 CDS_LIB='mstr_discrete',
 CDS_PART_NAME='RES_0402-1.00K,1%,1/16W,CHIP,GA',
 PRIM_FILE='./archive_libs/mstr_discrete/res/chips/chips.prt';

PART_NAME
 R7D8 'RES_0402-10.0K,1%,1/16W,CHIP,GA':
 ROOM='SB';

SECTION_NUMBER 1
 '@BASEBOARD_FAB2_LIB.BASEBOARD_FAB2(SCH_1):PAGE133_I200@MSTR_DISCRETE.RES(CHIPS)':
 C_PATH='@baseboard_fab2_lib.baseboard_fab2(sch_1):page133_i200@mstr_discrete.re~
s(chips)',
 P_PATH='@baseboard_fab2_lib.baseboard_fab2(sch_1):page133_i200@mstr_discrete.re~
s(chips)',
 PATH='I200',
 DRAWING='@BASEBOARD_FAB2_LIB.BASEBOARD_FAB2(SCH_1):PAGE133',
 WATTAGE='1/16W',
 TOLERANCE='1%',
 SEC_TYPE='0402',
 MATERIAL='CHIP',
 PHYS_PAGE='133',
 XY='(-4700,4500)',
 ROT='0',
 VER='1',
 VALUE='10.0K',
 PACK_TYPE='0402',
 PART_NUMBER='G21796-016',
 LOCATION='R7D8',
 ROOM='SB',
 SEC='1',
 CDS_LIB='mstr_discrete',
 CDS_PART_NAME='RES_0402-10.0K,1%,1/16W,CHIP,GA',
 PRIM_FILE='./archive_libs/mstr_discrete/res/chips/chips.prt';

PART_NAME
 R7D9 'RES_0402-2.26K,1.0%,1/16W,CHIPA':
 ROOM='IO_SLOT';

SECTION_NUMBER 1
 '@BASEBOARD_FAB2_LIB.BASEBOARD_FAB2(SCH_1):PAGE181_I80@MSTR_DISCRETE.RES(CHIPS)':
 C_PATH='@baseboard_fab2_lib.baseboard_fab2(sch_1):page181_i80@mstr_discrete.res~
(chips)',
 P_PATH='@baseboard_fab2_lib.baseboard_fab2(sch_1):page181_i80@mstr_discrete.res~
(chips)',
 PATH='I80',
 DRAWING='@BASEBOARD_FAB2_LIB.BASEBOARD_FAB2(SCH_1):PAGE181',
 WATTAGE='1/16W',
 TOLERANCE='1.0%',
 SEC_TYPE='0402',
 MATERIAL='CHIP',
 PHYS_PAGE='181',
 XY='(2650,2050)',
 ROT='0',
 VER='1',
 VALUE='2.26K',
 PACK_TYPE='0402',
 PART_NUMBER='G21796-311',
 LOCATION='R7D9',
 ROOM='IO_SLOT',
 SEC='1',
 CDS_LIB='mstr_discrete',
 CDS_PART_NAME='RES_0402-2.26K,1.0%,1/16W,CHIPA',
 PRIM_FILE='./archive_libs/mstr_discrete/res/chips/chips.prt';

PART_NAME
 R7D10 'RES_0402-10.0K,1%,1/16W,CHIP,GA':
 ROOM='SB';

SECTION_NUMBER 1
 '@BASEBOARD_FAB2_LIB.BASEBOARD_FAB2(SCH_1):PAGE133_I202@MSTR_DISCRETE.RES(CHIPS)':
 C_PATH='@baseboard_fab2_lib.baseboard_fab2(sch_1):page133_i202@mstr_discrete.re~
s(chips)',
 P_PATH='@baseboard_fab2_lib.baseboard_fab2(sch_1):page133_i202@mstr_discrete.re~
s(chips)',
 PATH='I202',
 DRAWING='@BASEBOARD_FAB2_LIB.BASEBOARD_FAB2(SCH_1):PAGE133',
 WATTAGE='1/16W',
 TOLERANCE='1%',
 SEC_TYPE='0402',
 MATERIAL='CHIP',
 PHYS_PAGE='133',
 XY='(-4700,4325)',
 ROT='0',
 VER='1',
 VALUE='10.0K',
 PACK_TYPE='0402',
 PART_NUMBER='G21796-016',
 LOCATION='R7D10',
 ROOM='SB',
 SEC='1',
 CDS_LIB='mstr_discrete',
 CDS_PART_NAME='RES_0402-10.0K,1%,1/16W,CHIP,GA',
 PRIM_FILE='./archive_libs/mstr_discrete/res/chips/chips.prt';

PART_NAME
 R7D12 'RES_0402-10.0K,1%,1/16W,CHIP,GA':
 ROOM='SB';

SECTION_NUMBER 1
 '@BASEBOARD_FAB2_LIB.BASEBOARD_FAB2(SCH_1):PAGE133_I237@MSTR_DISCRETE.RES(CHIPS)':
 C_PATH='@baseboard_fab2_lib.baseboard_fab2(sch_1):page133_i237@mstr_discrete.re~
s(chips)',
 P_PATH='@baseboard_fab2_lib.baseboard_fab2(sch_1):page133_i237@mstr_discrete.re~
s(chips)',
 PATH='I237',
 DRAWING='@BASEBOARD_FAB2_LIB.BASEBOARD_FAB2(SCH_1):PAGE133',
 WATTAGE='1/16W',
 TOLERANCE='1%',
 SEC_TYPE='0402',
 MATERIAL='CHIP',
 PHYS_PAGE='133',
 XY='(-4700,3925)',
 ROT='0',
 VER='1',
 VALUE='10.0K',
 PACK_TYPE='0402',
 PART_NUMBER='G21796-016',
 LOCATION='R7D12',
 ROOM='SB',
 SEC='1',
 CDS_LIB='mstr_discrete',
 CDS_PART_NAME='RES_0402-10.0K,1%,1/16W,CHIP,GA',
 PRIM_FILE='./archive_libs/mstr_discrete/res/chips/chips.prt';

PART_NAME
 R7D13 'RES_0402-8.2K,1%,1/16W,EMPTY,GA':
 ROOM='SB';

SECTION_NUMBER 1
 '@BASEBOARD_FAB2_LIB.BASEBOARD_FAB2(SCH_1):PAGE125_I60@MSTR_DISCRETE.RES(CHIPS)':
 C_PATH='@baseboard_fab2_lib.baseboard_fab2(sch_1):page125_i60@mstr_discrete.res~
(chips)',
 P_PATH='@baseboard_fab2_lib.baseboard_fab2(sch_1):page125_i60@mstr_discrete.res~
(chips)',
 PATH='I60',
 DRAWING='@BASEBOARD_FAB2_LIB.BASEBOARD_FAB2(SCH_1):PAGE125',
 WATTAGE='1/16W',
 TOLERANCE='1%',
 MATERIAL='EMPTY',
 BOM_COST='SB',
 PHYS_PAGE='125',
 XY='(-3275,4975)',
 ROT='0',
 VER='2',
 VALUE='8.2K',
 PACK_TYPE='0402',
 PART_NUMBER='G21796-345',
 LOCATION='R7D13',
 ROOM='SB',
 CDS_LIB='mstr_discrete',
 CDS_PART_NAME='RES_0402-8.2K,1%,1/16W,EMPTY,GA',
 PRIM_FILE='./archive_libs/mstr_discrete/res/chips/chips.prt';

PART_NAME
 R7D15 'RES_0402-348,1%,1/16W,CHIP,G21A':
 ROOM='PECI';

SECTION_NUMBER 1
 '@BASEBOARD_FAB2_LIB.BASEBOARD_FAB2(SCH_1):PAGE166_I32@MSTR_DISCRETE.RES(CHIPS)':
 C_PATH='@baseboard_fab2_lib.baseboard_fab2(sch_1):page166_i32@mstr_discrete.res~
(chips)',
 P_PATH='@baseboard_fab2_lib.baseboard_fab2(sch_1):page166_i32@mstr_discrete.res~
(chips)',
 PATH='I32',
 DRAWING='@BASEBOARD_FAB2_LIB.BASEBOARD_FAB2(SCH_1):PAGE166',
 WATTAGE='1/16W',
 TOLERANCE='1%',
 SEC_TYPE='0402',
 MATERIAL='CHIP',
 BOM_COST='DEBUG',
 PHYS_PAGE='166',
 XY='(-4475,2150)',
 ROT='0',
 VER='2',
 VALUE='348',
 PACK_TYPE='0402',
 PART_NUMBER='G21796-340',
 LOCATION='R7D15',
 ROOM='PECI',
 SEC='1',
 CDS_LIB='mstr_discrete',
 CDS_PART_NAME='RES_0402-348,1%,1/16W,CHIP,G21A',
 PRIM_FILE='./archive_libs/mstr_discrete/res/chips/chips.prt';

PART_NAME
 R7D18 'RES_0402-1.00K,1%,1/16W,CHIP,GA':
 ROOM='PROC_SIDEBAND';

SECTION_NUMBER 1
 '@BASEBOARD_FAB2_LIB.BASEBOARD_FAB2(SCH_1):PAGE134_I11@MSTR_DISCRETE.RES(CHIPS)':
 C_PATH='@baseboard_fab2_lib.baseboard_fab2(sch_1):page134_i11@mstr_discrete.res~
(chips)',
 P_PATH='@baseboard_fab2_lib.baseboard_fab2(sch_1):page134_i11@mstr_discrete.res~
(chips)',
 PATH='I11',
 DRAWING='@BASEBOARD_FAB2_LIB.BASEBOARD_FAB2(SCH_1):PAGE134',
 WATTAGE='1/16W',
 TOLERANCE='1%',
 SEC_TYPE='0402',
 MATERIAL='CHIP',
 PHYS_PAGE='134',
 XY='(-3950,4300)',
 ROT='0',
 VER='1',
 VALUE='1.00K',
 PACK_TYPE='0402',
 PART_NUMBER='G21796-026',
 LOCATION='R7D18',
 ROOM='PROC_SIDEBAND',
 SEC='1',
 CDS_LIB='mstr_discrete',
 CDS_PART_NAME='RES_0402-1.00K,1%,1/16W,CHIP,GA',
 PRIM_FILE='./archive_libs/mstr_discrete/res/chips/chips.prt';

PART_NAME
 R7D19 'RES_0402-1.00K,1%,1/16W,EMPTY,A':
 ROOM='SB';

SECTION_NUMBER 1
 '@BASEBOARD_FAB2_LIB.BASEBOARD_FAB2(SCH_1):PAGE126_I6@MSTR_DISCRETE.RES(CHIPS)':
 C_PATH='@baseboard_fab2_lib.baseboard_fab2(sch_1):page126_i6@mstr_discrete.res(~
chips)',
 P_PATH='@baseboard_fab2_lib.baseboard_fab2(sch_1):page126_i6@mstr_discrete.res(~
chips)',
 PATH='I6',
 DRAWING='@BASEBOARD_FAB2_LIB.BASEBOARD_FAB2(SCH_1):PAGE126',
 WATTAGE='1/16W',
 TOLERANCE='1%',
 SEC_TYPE='0402',
 MATERIAL='EMPTY',
 BOM_COST='SB',
 PHYS_PAGE='126',
 XY='(-6200,2350)',
 ROT='0',
 VER='2',
 VALUE='1.00K',
 PACK_TYPE='0402',
 PART_NUMBER='G21796-026',
 LOCATION='R7D19',
 ROOM='SB',
 SEC='1',
 CDS_LIB='mstr_discrete',
 CDS_PART_NAME='RES_0402-1.00K,1%,1/16W,EMPTY,A',
 PRIM_FILE='./archive_libs/mstr_discrete/res/chips/chips.prt';

PART_NAME
 R7D23 'RES_0402-0.0,5%,1/16W,CHIP,G21A':
 ROOM='SB';

SECTION_NUMBER 1
 '@BASEBOARD_FAB2_LIB.BASEBOARD_FAB2(SCH_1):PAGE118_I131@MSTR_DISCRETE.RES(CHIPS)':
 C_PATH='@baseboard_fab2_lib.baseboard_fab2(sch_1):page118_i131@mstr_discrete.re~
s(chips)',
 P_PATH='@baseboard_fab2_lib.baseboard_fab2(sch_1):page118_i131@mstr_discrete.re~
s(chips)',
 PATH='I131',
 DRAWING='@BASEBOARD_FAB2_LIB.BASEBOARD_FAB2(SCH_1):PAGE118',
 POP='NOPOP',
 WATTAGE='1/16W',
 TOLERANCE='5%',
 SEC_TYPE='0402',
 MATERIAL='CHIP',
 BOM_COST='SB',
 PHYS_PAGE='118',
 XY='(-6625,3975)',
 ROT='0',
 VER='1',
 VALUE='0.0',
 PACK_TYPE='0402',
 PART_NUMBER='G21497-005',
 LOCATION='R7D23',
 ROOM='SB',
 SEC='1',
 CDS_LIB='mstr_discrete',
 CDS_PART_NAME='RES_0402-0.0,5%,1/16W,CHIP,G21A',
 PRIM_FILE='./archive_libs/mstr_discrete/res/chips/chips.prt';

PART_NAME
 R7D24 'RES_0402-33.2,1%,1/16W,CHIP,G2A':
 ROOM='PROC_SIDEBAND';

SECTION_NUMBER 1
 '@BASEBOARD_FAB2_LIB.BASEBOARD_FAB2(SCH_1):PAGE93_I62@MSTR_DISCRETE.RES(CHIPS)':
 C_PATH='@baseboard_fab2_lib.baseboard_fab2(sch_1):page93_i62@mstr_discrete.res(~
chips)',
 P_PATH='@baseboard_fab2_lib.baseboard_fab2(sch_1):page93_i62@mstr_discrete.res(~
chips)',
 PATH='I62',
 DRAWING='@BASEBOARD_FAB2_LIB.BASEBOARD_FAB2(SCH_1):PAGE93',
 WATTAGE='1/16W',
 TOLERANCE='1%',
 SEC_TYPE='0402',
 MATERIAL='CHIP',
 BOM_COST='PROC',
 PHYS_PAGE='93',
 XY='(2950,2575)',
 ROT='0',
 VER='1',
 VALUE='33.2',
 PACK_TYPE='0402',
 PART_NUMBER='G21796-074',
 LOCATION='R7D24',
 ROOM='PROC_SIDEBAND',
 SEC='1',
 CDS_LIB='mstr_discrete',
 CDS_PART_NAME='RES_0402-33.2,1%,1/16W,CHIP,G2A',
 PRIM_FILE='./archive_libs/mstr_discrete/res/chips/chips.prt';

PART_NAME
 R7D25 'RES_0402-33.2,1%,1/16W,CHIP,G2A':
 ROOM='PROC_SIDEBAND';

SECTION_NUMBER 1
 '@BASEBOARD_FAB2_LIB.BASEBOARD_FAB2(SCH_1):PAGE92_I70@MSTR_DISCRETE.RES(CHIPS)':
 C_PATH='@baseboard_fab2_lib.baseboard_fab2(sch_1):page92_i70@mstr_discrete.res(~
chips)',
 P_PATH='@baseboard_fab2_lib.baseboard_fab2(sch_1):page92_i70@mstr_discrete.res(~
chips)',
 PATH='I70',
 DRAWING='@BASEBOARD_FAB2_LIB.BASEBOARD_FAB2(SCH_1):PAGE92',
 WATTAGE='1/16W',
 TOLERANCE='1%',
 SEC_TYPE='0402',
 MATERIAL='CHIP',
 BOM_COST='PROC_SIDEBAND',
 PHYS_PAGE='92',
 XY='(-100,1250)',
 ROT='0',
 VER='1',
 VALUE='33.2',
 PACK_TYPE='0402',
 PART_NUMBER='G21796-074',
 LOCATION='R7D25',
 ROOM='PROC_SIDEBAND',
 SEC='1',
 CDS_LIB='mstr_discrete',
 CDS_PART_NAME='RES_0402-33.2,1%,1/16W,CHIP,G2A',
 PRIM_FILE='./archive_libs/mstr_discrete/res/chips/chips.prt';

PART_NAME
 R7D26 'RES_0402-1.00K,1%,1/16W,CHIP,GA':
 ROOM='PROC_SIDEBAND';

SECTION_NUMBER 1
 '@BASEBOARD_FAB2_LIB.BASEBOARD_FAB2(SCH_1):PAGE92_I54@MSTR_DISCRETE.RES(CHIPS)':
 C_PATH='@baseboard_fab2_lib.baseboard_fab2(sch_1):page92_i54@mstr_discrete.res(~
chips)',
 P_PATH='@baseboard_fab2_lib.baseboard_fab2(sch_1):page92_i54@mstr_discrete.res(~
chips)',
 PATH='I54',
 DRAWING='@BASEBOARD_FAB2_LIB.BASEBOARD_FAB2(SCH_1):PAGE92',
 WATTAGE='1/16W',
 TOLERANCE='1%',
 SEC_TYPE='0402',
 MATERIAL='CHIP',
 BOM_COST='PROC_SIDEBAND',
 PHYS_PAGE='92',
 XY='(-600,2200)',
 ROT='0',
 VER='1',
 VALUE='1.00K',
 PACK_TYPE='0402',
 PART_NUMBER='G21796-026',
 LOCATION='R7D26',
 ROOM='PROC_SIDEBAND',
 SEC='1',
 CDS_LIB='mstr_discrete',
 CDS_PART_NAME='RES_0402-1.00K,1%,1/16W,CHIP,GA',
 PRIM_FILE='./archive_libs/mstr_discrete/res/chips/chips.prt';

PART_NAME
 R7D27 'RES_0402-0.0,5%,1/16W,CHIP,G21A':
 ROOM='PROC_SIDEBAND';

SECTION_NUMBER 1
 '@BASEBOARD_FAB2_LIB.BASEBOARD_FAB2(SCH_1):PAGE92_I68@MSTR_DISCRETE.RES(CHIPS)':
 C_PATH='@baseboard_fab2_lib.baseboard_fab2(sch_1):page92_i68@mstr_discrete.res(~
chips)',
 P_PATH='@baseboard_fab2_lib.baseboard_fab2(sch_1):page92_i68@mstr_discrete.res(~
chips)',
 PATH='I68',
 DRAWING='@BASEBOARD_FAB2_LIB.BASEBOARD_FAB2(SCH_1):PAGE92',
 WATTAGE='1/16W',
 TOLERANCE='5%',
 SEC_TYPE='0402',
 MATERIAL='CHIP',
 BOM_COST='PROC_SIDEBAND',
 PHYS_PAGE='92',
 XY='(-3775,1550)',
 ROT='0',
 VER='1',
 VALUE='0.0',
 PACK_TYPE='0402',
 PART_NUMBER='G21497-005',
 LOCATION='R7D27',
 ROOM='PROC_SIDEBAND',
 SEC='1',
 CDS_LIB='mstr_discrete',
 CDS_PART_NAME='RES_0402-0.0,5%,1/16W,CHIP,G21A',
 PRIM_FILE='./archive_libs/mstr_discrete/res/chips/chips.prt';

PART_NAME
 R7D28 'RES_0402-0.0,5%,1/16W,CHIP,G21A':
 ROOM='PROC_SIDEBAND';

SECTION_NUMBER 1
 '@BASEBOARD_FAB2_LIB.BASEBOARD_FAB2(SCH_1):PAGE92_I67@MSTR_DISCRETE.RES(CHIPS)':
 C_PATH='@baseboard_fab2_lib.baseboard_fab2(sch_1):page92_i67@mstr_discrete.res(~
chips)',
 P_PATH='@baseboard_fab2_lib.baseboard_fab2(sch_1):page92_i67@mstr_discrete.res(~
chips)',
 PATH='I67',
 DRAWING='@BASEBOARD_FAB2_LIB.BASEBOARD_FAB2(SCH_1):PAGE92',
 WATTAGE='1/16W',
 TOLERANCE='5%',
 SEC_TYPE='0402',
 MATERIAL='CHIP',
 BOM_COST='PROC_SIDEBAND',
 PHYS_PAGE='92',
 XY='(-3725,1275)',
 ROT='0',
 VER='1',
 VALUE='0.0',
 PACK_TYPE='0402',
 PART_NUMBER='G21497-005',
 LOCATION='R7D28',
 ROOM='PROC_SIDEBAND',
 SEC='1',
 CDS_LIB='mstr_discrete',
 CDS_PART_NAME='RES_0402-0.0,5%,1/16W,CHIP,G21A',
 PRIM_FILE='./archive_libs/mstr_discrete/res/chips/chips.prt';

PART_NAME
 R7D29 'RES_0402-33.2,1%,1/16W,CHIP,G2A':
 ROOM='PROC_SIDEBAND';

SECTION_NUMBER 1
 '@BASEBOARD_FAB2_LIB.BASEBOARD_FAB2(SCH_1):PAGE92_I30@MSTR_DISCRETE.RES(CHIPS)':
 C_PATH='@baseboard_fab2_lib.baseboard_fab2(sch_1):page92_i30@mstr_discrete.res(~
chips)',
 P_PATH='@baseboard_fab2_lib.baseboard_fab2(sch_1):page92_i30@mstr_discrete.res(~
chips)',
 PATH='I30',
 DRAWING='@BASEBOARD_FAB2_LIB.BASEBOARD_FAB2(SCH_1):PAGE92',
 WATTAGE='1/16W',
 TOLERANCE='1%',
 SEC_TYPE='0402',
 MATERIAL='CHIP',
 BOM_COST='PROC_SIDEBAND',
 PHYS_PAGE='92',
 XY='(-100,1550)',
 ROT='0',
 VER='1',
 VALUE='33.2',
 PACK_TYPE='0402',
 PART_NUMBER='G21796-074',
 LOCATION='R7D29',
 ROOM='PROC_SIDEBAND',
 SEC='1',
 CDS_LIB='mstr_discrete',
 CDS_PART_NAME='RES_0402-33.2,1%,1/16W,CHIP,G2A',
 PRIM_FILE='./archive_libs/mstr_discrete/res/chips/chips.prt';

PART_NAME
 R7D30 'RES_0402-4.75K,1%,1/16W,CHIP,GA':
 ROOM='UART_MUX';

SECTION_NUMBER 1
 '@BASEBOARD_FAB2_LIB.BASEBOARD_FAB2(SCH_1):PAGE135_I121@MSTR_DISCRETE.RES(CHIPS)':
 C_PATH='@baseboard_fab2_lib.baseboard_fab2(sch_1):page135_i121@mstr_discrete.re~
s(chips)',
 P_PATH='@baseboard_fab2_lib.baseboard_fab2(sch_1):page135_i121@mstr_discrete.re~
s(chips)',
 PATH='I121',
 DRAWING='@BASEBOARD_FAB2_LIB.BASEBOARD_FAB2(SCH_1):PAGE135',
 WATTAGE='1/16W',
 TOLERANCE='1%',
 SEC_TYPE='0402',
 MATERIAL='CHIP',
 BOM_COST='DEBUG',
 PHYS_PAGE='135',
 XY='(-1525,2250)',
 ROT='0',
 VER='2',
 VALUE='4.75K',
 PACK_TYPE='0402',
 PART_NUMBER='G21796-072',
 LOCATION='R7D30',
 ROOM='UART_MUX',
 SEC='1',
 CDS_LIB='mstr_discrete',
 CDS_PART_NAME='RES_0402-4.75K,1%,1/16W,CHIP,GA',
 PRIM_FILE='./archive_libs/mstr_discrete/res/chips/chips.prt';

PART_NAME
 R7D31 'RES_0402-33.2,1%,1/16W,CHIP,G2A':
 ROOM='PROC_SIDEBAND';

SECTION_NUMBER 1
 '@BASEBOARD_FAB2_LIB.BASEBOARD_FAB2(SCH_1):PAGE92_I29@MSTR_DISCRETE.RES(CHIPS)':
 C_PATH='@baseboard_fab2_lib.baseboard_fab2(sch_1):page92_i29@mstr_discrete.res(~
chips)',
 P_PATH='@baseboard_fab2_lib.baseboard_fab2(sch_1):page92_i29@mstr_discrete.res(~
chips)',
 PATH='I29',
 DRAWING='@BASEBOARD_FAB2_LIB.BASEBOARD_FAB2(SCH_1):PAGE92',
 WATTAGE='1/16W',
 TOLERANCE='1%',
 SEC_TYPE='0402',
 MATERIAL='CHIP',
 BOM_COST='PROC_SIDEBAND',
 PHYS_PAGE='92',
 XY='(-100,1800)',
 ROT='0',
 VER='1',
 VALUE='33.2',
 PACK_TYPE='0402',
 PART_NUMBER='G21796-074',
 LOCATION='R7D31',
 ROOM='PROC_SIDEBAND',
 SEC='1',
 CDS_LIB='mstr_discrete',
 CDS_PART_NAME='RES_0402-33.2,1%,1/16W,CHIP,G2A',
 PRIM_FILE='./archive_libs/mstr_discrete/res/chips/chips.prt';

PART_NAME
 R7D32 'RES_0402-100.0,1%,1/16W,CHIP,GA':
 ROOM='PROC_SIDEBAND';

SECTION_NUMBER 1
 '@BASEBOARD_FAB2_LIB.BASEBOARD_FAB2(SCH_1):PAGE92_I48@MSTR_DISCRETE.RES(CHIPS)':
 C_PATH='@baseboard_fab2_lib.baseboard_fab2(sch_1):page92_i48@mstr_discrete.res(~
chips)',
 P_PATH='@baseboard_fab2_lib.baseboard_fab2(sch_1):page92_i48@mstr_discrete.res(~
chips)',
 PATH='I48',
 DRAWING='@BASEBOARD_FAB2_LIB.BASEBOARD_FAB2(SCH_1):PAGE92',
 WATTAGE='1/16W',
 TOLERANCE='1%',
 SEC_TYPE='0402',
 MATERIAL='CHIP',
 BOM_COST='PROC_SIDEBAND',
 PHYS_PAGE='92',
 XY='(350,2550)',
 ROT='0',
 VER='2',
 VALUE='100.0',
 PACK_TYPE='0402',
 PART_NUMBER='G21796-017',
 LOCATION='R7D32',
 ROOM='PROC_SIDEBAND',
 SEC='1',
 CDS_LIB='mstr_discrete',
 CDS_PART_NAME='RES_0402-100.0,1%,1/16W,CHIP,GA',
 PRIM_FILE='./archive_libs/mstr_discrete/res/chips/chips.prt';

PART_NAME
 R7D33 '374R2F-1-GP_SMD-RG-374R2F-1-GPA':;

SECTION_NUMBER 1
 '@BASEBOARD_FAB2_LIB.BASEBOARD_FAB2(SCH_1):PAGE92_I111@W_HDL.374R2F-1-GP(CHIPS)':
 C_PATH='@baseboard_fab2_lib.baseboard_fab2(sch_1):page92_i111@w_hdl.\374r2f-1-g~
p\(chips)',
 P_PATH='@baseboard_fab2_lib.baseboard_fab2(sch_1):page92_i111@w_hdl.\374r2f-1-g~
p\(chips)',
 PATH='I111',
 DRAWING='@BASEBOARD_FAB2_LIB.BASEBOARD_FAB2(SCH_1):PAGE92',
 PACK_SIZE='0402',
 RATED='1/16W',
 ATTRIBUTE='374 OHM',
 TOLERANCE='1%',
 PHYS_PAGE='92',
 XY='(350,3025)',
 ROT='0',
 VER='1',
 VALUE='374R2F-1-GP',
 PACK_TYPE='SMD-RG',
 PART_NUMBER='64.37405.6DL',
 LOCATION='R7D33',
 CDS_LIB='w_hdl',
 CDS_PART_NAME='374R2F-1-GP_SMD-RG-374R2F-1-GPA',
 PRIM_FILE='C:/<user>/w_hdl/374r2f#2d1#2dgp/chips/chips.prt';

PART_NAME
 R7D34 'RES_0402-33.2,1%,1/16W,CHIP,G2A':
 ROOM='PROC_SIDEBAND';

SECTION_NUMBER 1
 '@BASEBOARD_FAB2_LIB.BASEBOARD_FAB2(SCH_1):PAGE92_I24@MSTR_DISCRETE.RES(CHIPS)':
 C_PATH='@baseboard_fab2_lib.baseboard_fab2(sch_1):page92_i24@mstr_discrete.res(~
chips)',
 P_PATH='@baseboard_fab2_lib.baseboard_fab2(sch_1):page92_i24@mstr_discrete.res(~
chips)',
 PATH='I24',
 DRAWING='@BASEBOARD_FAB2_LIB.BASEBOARD_FAB2(SCH_1):PAGE92',
 WATTAGE='1/16W',
 TOLERANCE='1%',
 SEC_TYPE='0402',
 MATERIAL='CHIP',
 BOM_COST='PROC_SIDEBAND',
 PHYS_PAGE='92',
 XY='(-125,2050)',
 ROT='0',
 VER='1',
 VALUE='33.2',
 PACK_TYPE='0402',
 PART_NUMBER='G21796-074',
 LOCATION='R7D34',
 ROOM='PROC_SIDEBAND',
 SEC='1',
 CDS_LIB='mstr_discrete',
 CDS_PART_NAME='RES_0402-33.2,1%,1/16W,CHIP,G2A',
 PRIM_FILE='./archive_libs/mstr_discrete/res/chips/chips.prt';

PART_NAME
 R7D36 'RES_0402-0.0,5%,1/16W,CHIP,G21A':
 ROOM='CLOCK_CPU1_OSC';

SECTION_NUMBER 1
 '@BASEBOARD_FAB2_LIB.BASEBOARD_FAB2(SCH_1):PAGE104_I96@MSTR_DISCRETE.RES(CHIPS)':
 C_PATH='@baseboard_fab2_lib.baseboard_fab2(sch_1):page104_i96@mstr_discrete.res~
(chips)',
 P_PATH='@baseboard_fab2_lib.baseboard_fab2(sch_1):page104_i96@mstr_discrete.res~
(chips)',
 PATH='I96',
 DRAWING='@BASEBOARD_FAB2_LIB.BASEBOARD_FAB2(SCH_1):PAGE104',
 WATTAGE='1/16W',
 TOLERANCE='5%',
 SEC_TYPE='0402',
 MATERIAL='CHIP',
 PHYS_PAGE='104',
 XY='(550,1500)',
 ROT='0',
 VER='1',
 VALUE='0.0',
 PACK_TYPE='0402',
 PART_NUMBER='G21497-005',
 LOCATION='R7D36',
 ROOM='CLOCK_CPU1_OSC',
 SEC='1',
 CDS_LIB='mstr_discrete',
 CDS_PART_NAME='RES_0402-0.0,5%,1/16W,CHIP,G21A',
 PRIM_FILE='./archive_libs/mstr_discrete/res/chips/chips.prt';

PART_NAME
 R7D37 'RES_0402-0.0,5%,1/16W,CHIP,G21A':
 ROOM='CLOCK_CPU1_OSC',
 NO_XNET_CONNECTION='1';

SECTION_NUMBER 1
 '@BASEBOARD_FAB2_LIB.BASEBOARD_FAB2(SCH_1):PAGE104_I104@MSTR_DISCRETE.RES(CHIPS)':
 C_PATH='@baseboard_fab2_lib.baseboard_fab2(sch_1):page104_i104@mstr_discrete.re~
s(chips)',
 P_PATH='@baseboard_fab2_lib.baseboard_fab2(sch_1):page104_i104@mstr_discrete.re~
s(chips)',
 PATH='I104',
 DRAWING='@BASEBOARD_FAB2_LIB.BASEBOARD_FAB2(SCH_1):PAGE104',
 WATTAGE='1/16W',
 TOLERANCE='5%',
 SEC_TYPE='0402',
 MATERIAL='CHIP',
 NO_XNET_CONNECTION='1',
 PHYS_PAGE='104',
 XY='(550,1100)',
 ROT='0',
 VER='1',
 VALUE='0.0',
 PACK_TYPE='0402',
 PART_NUMBER='G21497-005',
 LOCATION='R7D37',
 ROOM='CLOCK_CPU1_OSC',
 SEC='1',
 CDS_LIB='mstr_discrete',
 CDS_PART_NAME='RES_0402-0.0,5%,1/16W,CHIP,G21A',
 PRIM_FILE='./archive_libs/mstr_discrete/res/chips/chips.prt';

PART_NAME
 R7D38 'RES_0402-0.0,5%,1/16W,EMPTY,G2A':
 ROOM='CLOCK_CPU1_OSC';

SECTION_NUMBER 1
 '@BASEBOARD_FAB2_LIB.BASEBOARD_FAB2(SCH_1):PAGE104_I97@MSTR_DISCRETE.RES(CHIPS)':
 C_PATH='@baseboard_fab2_lib.baseboard_fab2(sch_1):page104_i97@mstr_discrete.res~
(chips)',
 P_PATH='@baseboard_fab2_lib.baseboard_fab2(sch_1):page104_i97@mstr_discrete.res~
(chips)',
 PATH='I97',
 DRAWING='@BASEBOARD_FAB2_LIB.BASEBOARD_FAB2(SCH_1):PAGE104',
 WATTAGE='1/16W',
 TOLERANCE='5%',
 SEC_TYPE='0402',
 MATERIAL='EMPTY',
 PHYS_PAGE='104',
 XY='(550,1300)',
 ROT='0',
 VER='1',
 VALUE='0.0',
 PACK_TYPE='0402',
 PART_NUMBER='G21497-005',
 LOCATION='R7D38',
 ROOM='CLOCK_CPU1_OSC',
 SEC='1',
 CDS_LIB='mstr_discrete',
 CDS_PART_NAME='RES_0402-0.0,5%,1/16W,EMPTY,G2A',
 PRIM_FILE='./archive_libs/mstr_discrete/res/chips/chips.prt';

PART_NAME
 R7D39 'RES_0402-0.0,5%,1/16W,CHIP,G21A':
 ROOM='CLOCK_CPU1_OSC',
 NO_XNET_CONNECTION='1';

SECTION_NUMBER 1
 '@BASEBOARD_FAB2_LIB.BASEBOARD_FAB2(SCH_1):PAGE104_I103@MSTR_DISCRETE.RES(CHIPS)':
 C_PATH='@baseboard_fab2_lib.baseboard_fab2(sch_1):page104_i103@mstr_discrete.re~
s(chips)',
 P_PATH='@baseboard_fab2_lib.baseboard_fab2(sch_1):page104_i103@mstr_discrete.re~
s(chips)',
 PATH='I103',
 DRAWING='@BASEBOARD_FAB2_LIB.BASEBOARD_FAB2(SCH_1):PAGE104',
 WATTAGE='1/16W',
 TOLERANCE='5%',
 SEC_TYPE='0402',
 MATERIAL='CHIP',
 NO_XNET_CONNECTION='1',
 PHYS_PAGE='104',
 XY='(550,1800)',
 ROT='0',
 VER='1',
 VALUE='0.0',
 PACK_TYPE='0402',
 PART_NUMBER='G21497-005',
 LOCATION='R7D39',
 ROOM='CLOCK_CPU1_OSC',
 SEC='1',
 CDS_LIB='mstr_discrete',
 CDS_PART_NAME='RES_0402-0.0,5%,1/16W,CHIP,G21A',
 PRIM_FILE='./archive_libs/mstr_discrete/res/chips/chips.prt';

PART_NAME
 R7D40 'RES_0402-0.0,5%,1/16W,EMPTY,G2A':
 ROOM='CLOCK_CPU1_OSC';

SECTION_NUMBER 1
 '@BASEBOARD_FAB2_LIB.BASEBOARD_FAB2(SCH_1):PAGE104_I94@MSTR_DISCRETE.RES(CHIPS)':
 C_PATH='@baseboard_fab2_lib.baseboard_fab2(sch_1):page104_i94@mstr_discrete.res~
(chips)',
 P_PATH='@baseboard_fab2_lib.baseboard_fab2(sch_1):page104_i94@mstr_discrete.res~
(chips)',
 PATH='I94',
 DRAWING='@BASEBOARD_FAB2_LIB.BASEBOARD_FAB2(SCH_1):PAGE104',
 WATTAGE='1/16W',
 TOLERANCE='5%',
 SEC_TYPE='0402',
 MATERIAL='EMPTY',
 PHYS_PAGE='104',
 XY='(550,2000)',
 ROT='0',
 VER='1',
 VALUE='0.0',
 PACK_TYPE='0402',
 PART_NUMBER='G21497-005',
 LOCATION='R7D40',
 ROOM='CLOCK_CPU1_OSC',
 SEC='1',
 CDS_LIB='mstr_discrete',
 CDS_PART_NAME='RES_0402-0.0,5%,1/16W,EMPTY,G2A',
 PRIM_FILE='./archive_libs/mstr_discrete/res/chips/chips.prt';

PART_NAME
 R7D41 'RES_0402-0.0,5%,1/16W,CHIP,G21A':;

SECTION_NUMBER 1
 '@BASEBOARD_FAB2_LIB.BASEBOARD_FAB2(SCH_1):PAGE93_I114@MSTR_DISCRETE.RES(CHIPS)':
 C_PATH='@baseboard_fab2_lib.baseboard_fab2(sch_1):page93_i114@mstr_discrete.res~
(chips)',
 P_PATH='@baseboard_fab2_lib.baseboard_fab2(sch_1):page93_i114@mstr_discrete.res~
(chips)',
 PATH='I114',
 DRAWING='@BASEBOARD_FAB2_LIB.BASEBOARD_FAB2(SCH_1):PAGE93',
 WATTAGE='1/16W',
 TOLERANCE='5%',
 SEC_TYPE='0402',
 MATERIAL='CHIP',
 PHYS_PAGE='93',
 XY='(1875,2575)',
 ROT='0',
 VER='1',
 VALUE='0.0',
 PACK_TYPE='0402',
 PART_NUMBER='G21497-005',
 LOCATION='R7D41',
 SEC='1',
 CDS_LIB='mstr_discrete',
 CDS_PART_NAME='RES_0402-0.0,5%,1/16W,CHIP,G21A',
 PRIM_FILE='./archive_libs/mstr_discrete/res/chips/chips.prt';

PART_NAME
 R7D42 'RES_0402-4.75K,1%,1/16W,CHIP,GA':
 ROOM='CPLD';

SECTION_NUMBER 1
 '@BASEBOARD_FAB2_LIB.BASEBOARD_FAB2(SCH_1):PAGE191_I193@MSTR_DISCRETE.RES(CHIPS)':
 C_PATH='@baseboard_fab2_lib.baseboard_fab2(sch_1):page191_i193@mstr_discrete.re~
s(chips)',
 P_PATH='@baseboard_fab2_lib.baseboard_fab2(sch_1):page191_i193@mstr_discrete.re~
s(chips)',
 PATH='I193',
 DRAWING='@BASEBOARD_FAB2_LIB.BASEBOARD_FAB2(SCH_1):PAGE191',
 WATTAGE='1/16W',
 TOLERANCE='1%',
 SEC_TYPE='0402',
 MATERIAL='CHIP',
 PHYS_PAGE='191',
 XY='(-7225,2675)',
 ROT='0',
 VER='2',
 VALUE='4.75K',
 PACK_TYPE='0402',
 PART_NUMBER='G21796-072',
 LOCATION='R7D42',
 ROOM='CPLD',
 SEC='1',
 CDS_LIB='mstr_discrete',
 CDS_PART_NAME='RES_0402-4.75K,1%,1/16W,CHIP,GA',
 PRIM_FILE='./archive_libs/mstr_discrete/res/chips/chips.prt';

PART_NAME
 R7D43 'RES_0402-0.0,5%,1/16W,EMPTY,G2A':;

SECTION_NUMBER 1
 '@BASEBOARD_FAB2_LIB.BASEBOARD_FAB2(SCH_1):PAGE93_I110@MSTR_DISCRETE.RES(CHIPS)':
 C_PATH='@baseboard_fab2_lib.baseboard_fab2(sch_1):page93_i110@mstr_discrete.res~
(chips)',
 P_PATH='@baseboard_fab2_lib.baseboard_fab2(sch_1):page93_i110@mstr_discrete.res~
(chips)',
 PATH='I110',
 DRAWING='@BASEBOARD_FAB2_LIB.BASEBOARD_FAB2(SCH_1):PAGE93',
 WATTAGE='1/16W',
 TOLERANCE='5%',
 SEC_TYPE='0402',
 MATERIAL='EMPTY',
 PHYS_PAGE='93',
 XY='(2400,2225)',
 ROT='0',
 VER='2',
 VALUE='0.0',
 PACK_TYPE='0402',
 PART_NUMBER='G21497-005',
 LOCATION='R7D43',
 SEC='1',
 CDS_LIB='mstr_discrete',
 CDS_PART_NAME='RES_0402-0.0,5%,1/16W,EMPTY,G2A',
 PRIM_FILE='./archive_libs/mstr_discrete/res/chips/chips.prt';

PART_NAME
 R7D44 'RES_0402-4.75K,1%,1/16W,CHIP,GA':
 ROOM='SB_PU_PD';

SECTION_NUMBER 1
 '@BASEBOARD_FAB2_LIB.BASEBOARD_FAB2(SCH_1):PAGE133_I356@MSTR_DISCRETE.RES(CHIPS)':
 C_PATH='@baseboard_fab2_lib.baseboard_fab2(sch_1):page133_i356@mstr_discrete.re~
s(chips)',
 P_PATH='@baseboard_fab2_lib.baseboard_fab2(sch_1):page133_i356@mstr_discrete.re~
s(chips)',
 PATH='I356',
 DRAWING='@BASEBOARD_FAB2_LIB.BASEBOARD_FAB2(SCH_1):PAGE133',
 WATTAGE='1/16W',
 TOLERANCE='1%',
 SEC_TYPE='0402',
 MATERIAL='CHIP',
 PHYS_PAGE='133',
 XY='(-375,3725)',
 ROT='0',
 VER='1',
 VALUE='4.75K',
 PACK_TYPE='0402',
 PART_NUMBER='G21796-072',
 LOCATION='R7D44',
 ROOM='SB_PU_PD',
 SEC='1',
 CDS_LIB='mstr_discrete',
 CDS_PART_NAME='RES_0402-4.75K,1%,1/16W,CHIP,GA',
 PRIM_FILE='./archive_libs/mstr_discrete/res/chips/chips.prt';

PART_NAME
 R7E2 'RES_0402-75,1.0%,1/16W,CHIP,G2A':
 ROOM='PROC_SIDEBAND';

SECTION_NUMBER 1
 '@BASEBOARD_FAB2_LIB.BASEBOARD_FAB2(SCH_1):PAGE92_I19@MSTR_DISCRETE.RES(CHIPS)':
 C_PATH='@baseboard_fab2_lib.baseboard_fab2(sch_1):page92_i19@mstr_discrete.res(~
chips)',
 P_PATH='@baseboard_fab2_lib.baseboard_fab2(sch_1):page92_i19@mstr_discrete.res(~
chips)',
 PATH='I19',
 DRAWING='@BASEBOARD_FAB2_LIB.BASEBOARD_FAB2(SCH_1):PAGE92',
 WATTAGE='1/16W',
 TOLERANCE='1.0%',
 SEC_TYPE='0402',
 MATERIAL='CHIP',
 BOM_COST='PROC_SIDEBAND',
 PHYS_PAGE='92',
 XY='(-2850,2325)',
 ROT='0',
 VER='2',
 VALUE='75',
 PACK_TYPE='0402',
 PART_NUMBER='G21796-267',
 LOCATION='R7E2',
 ROOM='PROC_SIDEBAND',
 SEC='1',
 CDS_LIB='mstr_discrete',
 CDS_PART_NAME='RES_0402-75,1.0%,1/16W,CHIP,G2A',
 PRIM_FILE='./archive_libs/mstr_discrete/res/chips/chips.prt';

PART_NAME
 R7E5 'RES_0402-10.0K,1%,1/16W,CHIP,GA':
 ROOM='CPLD';

SECTION_NUMBER 1
 '@BASEBOARD_FAB2_LIB.BASEBOARD_FAB2(SCH_1):PAGE192_I38@MSTR_DISCRETE.RES(CHIPS)':
 C_PATH='@baseboard_fab2_lib.baseboard_fab2(sch_1):page192_i38@mstr_discrete.res~
(chips)',
 P_PATH='@baseboard_fab2_lib.baseboard_fab2(sch_1):page192_i38@mstr_discrete.res~
(chips)',
 PATH='I38',
 DRAWING='@BASEBOARD_FAB2_LIB.BASEBOARD_FAB2(SCH_1):PAGE192',
 WATTAGE='1/16W',
 TOLERANCE='1%',
 MATERIAL='CHIP',
 BOM_COST='CPLD',
 PHYS_PAGE='192',
 XY='(-6550,4400)',
 ROT='0',
 VER='2',
 VALUE='10.0K',
 PACK_TYPE='0402',
 PART_NUMBER='G21796-016',
 LOCATION='R7E5',
 ROOM='CPLD',
 CDS_LIB='mstr_discrete',
 CDS_PART_NAME='RES_0402-10.0K,1%,1/16W,CHIP,GA',
 PRIM_FILE='./archive_libs/mstr_discrete/res/chips/chips.prt';

PART_NAME
 R7E6 'RES_0402-10.0K,1%,1/16W,CHIP,GA':
 ROOM='CPLD';

SECTION_NUMBER 1
 '@BASEBOARD_FAB2_LIB.BASEBOARD_FAB2(SCH_1):PAGE192_I33@MSTR_DISCRETE.RES(CHIPS)':
 C_PATH='@baseboard_fab2_lib.baseboard_fab2(sch_1):page192_i33@mstr_discrete.res~
(chips)',
 P_PATH='@baseboard_fab2_lib.baseboard_fab2(sch_1):page192_i33@mstr_discrete.res~
(chips)',
 PATH='I33',
 DRAWING='@BASEBOARD_FAB2_LIB.BASEBOARD_FAB2(SCH_1):PAGE192',
 WATTAGE='1/16W',
 TOLERANCE='1%',
 SEC_TYPE='0402',
 MATERIAL='CHIP',
 BOM_COST='CPLD',
 PHYS_PAGE='192',
 XY='(-6150,4400)',
 ROT='0',
 VER='2',
 VALUE='10.0K',
 PACK_TYPE='0402',
 PART_NUMBER='G21796-016',
 LOCATION='R7E6',
 ROOM='CPLD',
 SEC='1',
 CDS_LIB='mstr_discrete',
 CDS_PART_NAME='RES_0402-10.0K,1%,1/16W,CHIP,GA',
 PRIM_FILE='./archive_libs/mstr_discrete/res/chips/chips.prt';

PART_NAME
 R7E7 'RES_0402-4.75K,1%,1/16W,CHIP,GA':
 ROOM='PROC_SIDEBAND';

SECTION_NUMBER 1
 '@BASEBOARD_FAB2_LIB.BASEBOARD_FAB2(SCH_1):PAGE95_I106@MSTR_DISCRETE.RES(CHIPS)':
 C_PATH='@baseboard_fab2_lib.baseboard_fab2(sch_1):page95_i106@mstr_discrete.res~
(chips)',
 P_PATH='@baseboard_fab2_lib.baseboard_fab2(sch_1):page95_i106@mstr_discrete.res~
(chips)',
 PATH='I106',
 DRAWING='@BASEBOARD_FAB2_LIB.BASEBOARD_FAB2(SCH_1):PAGE95',
 WATTAGE='1/16W',
 TOLERANCE='1%',
 SEC_TYPE='0402',
 MATERIAL='CHIP',
 PHYS_PAGE='95',
 XY='(2150,1800)',
 ROT='0',
 VER='2',
 VALUE='4.75K',
 PACK_TYPE='0402',
 PART_NUMBER='G21796-072',
 LOCATION='R7E7',
 ROOM='PROC_SIDEBAND',
 SEC='1',
 CDS_LIB='mstr_discrete',
 CDS_PART_NAME='RES_0402-4.75K,1%,1/16W,CHIP,GA',
 PRIM_FILE='./archive_libs/mstr_discrete/res/chips/chips.prt';

PART_NAME
 R7E9 'RES_0402-0.0,5%,1/16W,CHIP,G21A':
 ROOM='PROC_SIDEBAND';

SECTION_NUMBER 1
 '@BASEBOARD_FAB2_LIB.BASEBOARD_FAB2(SCH_1):PAGE95_I108@MSTR_DISCRETE.RES(CHIPS)':
 C_PATH='@baseboard_fab2_lib.baseboard_fab2(sch_1):page95_i108@mstr_discrete.res~
(chips)',
 P_PATH='@baseboard_fab2_lib.baseboard_fab2(sch_1):page95_i108@mstr_discrete.res~
(chips)',
 PATH='I108',
 DRAWING='@BASEBOARD_FAB2_LIB.BASEBOARD_FAB2(SCH_1):PAGE95',
 WATTAGE='1/16W',
 TOLERANCE='5%',
 SEC_TYPE='0402',
 MATERIAL='CHIP',
 BOM_COST='PROC_SIDEBAND',
 PHYS_PAGE='95',
 XY='(1325,1250)',
 ROT='0',
 VER='1',
 VALUE='0.0',
 PACK_TYPE='0402',
 PART_NUMBER='G21497-005',
 LOCATION='R7E9',
 ROOM='PROC_SIDEBAND',
 SEC='1',
 CDS_LIB='mstr_discrete',
 CDS_PART_NAME='RES_0402-0.0,5%,1/16W,CHIP,G21A',
 PRIM_FILE='./archive_libs/mstr_discrete/res/chips/chips.prt';

PART_NAME
 R7E10 'RES_0402-4.75K,1%,1/16W,CHIP,GA':
 ROOM='HOT_EVENTS';

SECTION_NUMBER 1
 '@BASEBOARD_FAB2_LIB.BASEBOARD_FAB2(SCH_1):PAGE95_I62@MSTR_DISCRETE.RES(CHIPS)':
 C_PATH='@baseboard_fab2_lib.baseboard_fab2(sch_1):page95_i62@mstr_discrete.res(~
chips)',
 P_PATH='@baseboard_fab2_lib.baseboard_fab2(sch_1):page95_i62@mstr_discrete.res(~
chips)',
 PATH='I62',
 DRAWING='@BASEBOARD_FAB2_LIB.BASEBOARD_FAB2(SCH_1):PAGE95',
 WATTAGE='1/16W',
 TOLERANCE='1%',
 MATERIAL='CHIP',
 BOM_COST='PROC_SIDEBAND',
 PHYS_PAGE='95',
 XY='(2475,4800)',
 ROT='2',
 VER='2',
 VALUE='4.75K',
 PACK_TYPE='0402',
 PART_NUMBER='G21796-072',
 LOCATION='R7E10',
 ROOM='HOT_EVENTS',
 CDS_LIB='mstr_discrete',
 CDS_PART_NAME='RES_0402-4.75K,1%,1/16W,CHIP,GA',
 PRIM_FILE='./archive_libs/mstr_discrete/res/chips/chips.prt';

PART_NAME
 R7E11 'RES_0402-4.75K,1%,1/16W,CHIP,GA':
 ROOM='HOT_EVENTS';

SECTION_NUMBER 1
 '@BASEBOARD_FAB2_LIB.BASEBOARD_FAB2(SCH_1):PAGE95_I72@MSTR_DISCRETE.RES(CHIPS)':
 C_PATH='@baseboard_fab2_lib.baseboard_fab2(sch_1):page95_i72@mstr_discrete.res(~
chips)',
 P_PATH='@baseboard_fab2_lib.baseboard_fab2(sch_1):page95_i72@mstr_discrete.res(~
chips)',
 PATH='I72',
 DRAWING='@BASEBOARD_FAB2_LIB.BASEBOARD_FAB2(SCH_1):PAGE95',
 WATTAGE='1/16W',
 TOLERANCE='1%',
 MATERIAL='CHIP',
 BOM_COST='PROC_SIDEBAND',
 PHYS_PAGE='95',
 XY='(2550,3375)',
 ROT='2',
 VER='2',
 VALUE='4.75K',
 PACK_TYPE='0402',
 PART_NUMBER='G21796-072',
 LOCATION='R7E11',
 ROOM='HOT_EVENTS',
 CDS_LIB='mstr_discrete',
 CDS_PART_NAME='RES_0402-4.75K,1%,1/16W,CHIP,GA',
 PRIM_FILE='./archive_libs/mstr_discrete/res/chips/chips.prt';

PART_NAME
 R7E12 'RES_0402-1.00K,1%,1/16W,CHIP,GA':
 ROOM='P5V_STBY_VR',
 REUSE_ID='21';

SECTION_NUMBER 1
 '@BASEBOARD_FAB2_LIB.BASEBOARD_FAB2(SCH_1):PAGE241_I11@MSTR_DISCRETE.RES(CHIPS)':
 C_PATH='@baseboard_fab2_lib.baseboard_fab2(sch_1):page241_i11@mstr_discrete.res~
(chips)',
 P_PATH='@baseboard_fab2_lib.baseboard_fab2(sch_1):page241_i11@mstr_discrete.res~
(chips)',
 PATH='I11',
 DRAWING='@BASEBOARD_FAB2_LIB.BASEBOARD_FAB2(SCH_1):PAGE241',
 WATTAGE='1/16W',
 TOLERANCE='1%',
 SEC_TYPE='0402',
 MATERIAL='CHIP',
 BOM_COST='P5V_STBY_VR',
 PHYS_PAGE='241',
 REUSE_ID='21',
 XY='(1225,4850)',
 ROT='0',
 VER='2',
 VALUE='1.00K',
 PACK_TYPE='0402',
 PART_NUMBER='G21796-026',
 LOCATION='R7E12',
 ROOM='P5V_STBY_VR',
 SEC='1',
 CDS_LIB='mstr_discrete',
 CDS_PART_NAME='RES_0402-1.00K,1%,1/16W,CHIP,GA',
 PRIM_FILE='./archive_libs/mstr_discrete/res/chips/chips.prt';

PART_NAME
 R7E13 'RES_0402-0.0,5%,1/16W,CHIP,G21A':
 ROOM='P5V_STBY_VR';

SECTION_NUMBER 1
 '@BASEBOARD_FAB2_LIB.BASEBOARD_FAB2(SCH_1):PAGE241_I58@MSTR_DISCRETE.RES(CHIPS)':
 C_PATH='@baseboard_fab2_lib.baseboard_fab2(sch_1):page241_i58@mstr_discrete.res~
(chips)',
 P_PATH='@baseboard_fab2_lib.baseboard_fab2(sch_1):page241_i58@mstr_discrete.res~
(chips)',
 PATH='I58',
 DRAWING='@BASEBOARD_FAB2_LIB.BASEBOARD_FAB2(SCH_1):PAGE241',
 SPOF='TRUE',
 WATTAGE='1/16W',
 TOLERANCE='5%',
 SEC_TYPE='0402',
 MATERIAL='CHIP',
 BOM_COST='P5V_STBY_VR',
 PHYS_PAGE='241',
 XY='(1575,1550)',
 ROT='0',
 VER='1',
 VALUE='0.0',
 PACK_TYPE='0402',
 PART_NUMBER='G21497-005',
 LOCATION='R7E13',
 ROOM='P5V_STBY_VR',
 SEC='1',
 CDS_LIB='mstr_discrete',
 CDS_PART_NAME='RES_0402-0.0,5%,1/16W,CHIP,G21A',
 PRIM_FILE='./archive_libs/mstr_discrete/res/chips/chips.prt';

PART_NAME
 R7E14 'RES_0402-75K,1%,1/16W,CHIP,G21A':
 ROOM='P5V_STBY_VR',
 REUSE_ID='8';

SECTION_NUMBER 1
 '@BASEBOARD_FAB2_LIB.BASEBOARD_FAB2(SCH_1):PAGE241_I18@MSTR_DISCRETE.RES(CHIPS)':
 C_PATH='@baseboard_fab2_lib.baseboard_fab2(sch_1):page241_i18@mstr_discrete.res~
(chips)',
 P_PATH='@baseboard_fab2_lib.baseboard_fab2(sch_1):page241_i18@mstr_discrete.res~
(chips)',
 PATH='I18',
 DRAWING='@BASEBOARD_FAB2_LIB.BASEBOARD_FAB2(SCH_1):PAGE241',
 WATTAGE='1/16W',
 TOLERANCE='1%',
 SEC_TYPE='0402',
 MATERIAL='CHIP',
 BOM_COST='P5V_STBY_VR',
 PHYS_PAGE='241',
 REUSE_ID='8',
 XY='(-825,2600)',
 ROT='0',
 VER='2',
 VALUE='75K',
 PACK_TYPE='0402',
 PART_NUMBER='G21796-224',
 LOCATION='R7E14',
 ROOM='P5V_STBY_VR',
 SEC='1',
 CDS_LIB='mstr_discrete',
 CDS_PART_NAME='RES_0402-75K,1%,1/16W,CHIP,G21A',
 PRIM_FILE='./archive_libs/mstr_discrete/res/chips/chips.prt';

PART_NAME
 R7E15 'RES_0402-22.1,1.0%,1/16W,CHIP,A':
 ROOM='P5V_STBY_VR';

SECTION_NUMBER 1
 '@BASEBOARD_FAB2_LIB.BASEBOARD_FAB2(SCH_1):PAGE241_I89@MSTR_DISCRETE.RES(CHIPS)':
 C_PATH='@baseboard_fab2_lib.baseboard_fab2(sch_1):page241_i89@mstr_discrete.res~
(chips)',
 P_PATH='@baseboard_fab2_lib.baseboard_fab2(sch_1):page241_i89@mstr_discrete.res~
(chips)',
 PATH='I89',
 DRAWING='@BASEBOARD_FAB2_LIB.BASEBOARD_FAB2(SCH_1):PAGE241',
 WATTAGE='1/16W',
 TOLERANCE='1.0%',
 SEC_TYPE='0402',
 MATERIAL='CHIP',
 PHYS_PAGE='241',
 XY='(2250,4625)',
 ROT='0',
 VER='1',
 VALUE='22.1',
 PACK_TYPE='0402',
 PART_NUMBER='G21796-250',
 LOCATION='R7E15',
 ROOM='P5V_STBY_VR',
 SEC='1',
 CDS_LIB='mstr_discrete',
 CDS_PART_NAME='RES_0402-22.1,1.0%,1/16W,CHIP,A',
 PRIM_FILE='./archive_libs/mstr_discrete/res/chips/chips.prt';

PART_NAME
 R7E16 'RES_0402-1.37K,1%,1/16W,CHIP,GA':
 ROOM='P5V_STBY_VR',
 REUSE_ID='7';

SECTION_NUMBER 1
 '@BASEBOARD_FAB2_LIB.BASEBOARD_FAB2(SCH_1):PAGE241_I51@MSTR_DISCRETE.RES(CHIPS)':
 C_PATH='@baseboard_fab2_lib.baseboard_fab2(sch_1):page241_i51@mstr_discrete.res~
(chips)',
 P_PATH='@baseboard_fab2_lib.baseboard_fab2(sch_1):page241_i51@mstr_discrete.res~
(chips)',
 PATH='I51',
 DRAWING='@BASEBOARD_FAB2_LIB.BASEBOARD_FAB2(SCH_1):PAGE241',
 SPOF='TRUE',
 WATTAGE='1/16W',
 TOLERANCE='1%',
 SEC_TYPE='0402',
 MATERIAL='CHIP',
 BOM_COST='P5V_STBY_VR',
 PHYS_PAGE='241',
 REUSE_ID='7',
 XY='(1750,2900)',
 ROT='0',
 VER='2',
 VALUE='1.37K',
 PACK_TYPE='0402',
 PART_NUMBER='G21796-095',
 LOCATION='R7E16',
 ROOM='P5V_STBY_VR',
 SEC='1',
 CDS_LIB='mstr_discrete',
 CDS_PART_NAME='RES_0402-1.37K,1%,1/16W,CHIP,GA',
 PRIM_FILE='./archive_libs/mstr_discrete/res/chips/chips.prt';

PART_NAME
 R7E17 'RES_0402-0.0,5%,1/16W,CHIP,G21A':
 ROOM='P5V_STBY_VR',
 NO_XNET_CONNECTION='1';

SECTION_NUMBER 1
 '@BASEBOARD_FAB2_LIB.BASEBOARD_FAB2(SCH_1):PAGE241_I37@MSTR_DISCRETE.RES(CHIPS)':
 C_PATH='@baseboard_fab2_lib.baseboard_fab2(sch_1):page241_i37@mstr_discrete.res~
(chips)',
 P_PATH='@baseboard_fab2_lib.baseboard_fab2(sch_1):page241_i37@mstr_discrete.res~
(chips)',
 PATH='I37',
 DRAWING='@BASEBOARD_FAB2_LIB.BASEBOARD_FAB2(SCH_1):PAGE241',
 WATTAGE='1/16W',
 TOLERANCE='5%',
 SEC_TYPE='0402',
 MATERIAL='CHIP',
 BOM_COST='P5V_STBY_VR',
 NO_XNET_CONNECTION='1',
 PHYS_PAGE='241',
 XY='(-1400,4200)',
 ROT='0',
 VER='2',
 VALUE='0.0',
 PACK_TYPE='0402',
 PART_NUMBER='G21497-005',
 LOCATION='R7E17',
 ROOM='P5V_STBY_VR',
 SEC='1',
 CDS_LIB='mstr_discrete',
 CDS_PART_NAME='RES_0402-0.0,5%,1/16W,CHIP,G21A',
 PRIM_FILE='./archive_libs/mstr_discrete/res/chips/chips.prt';

PART_NAME
 R7E18 'RES_0402-4.75K,1%,1/16W,CHIP,GA':
 ROOM='CPLD';

SECTION_NUMBER 1
 '@BASEBOARD_FAB2_LIB.BASEBOARD_FAB2(SCH_1):PAGE192_I55@MSTR_DISCRETE.RES(CHIPS)':
 C_PATH='@baseboard_fab2_lib.baseboard_fab2(sch_1):page192_i55@mstr_discrete.res~
(chips)',
 P_PATH='@baseboard_fab2_lib.baseboard_fab2(sch_1):page192_i55@mstr_discrete.res~
(chips)',
 PATH='I55',
 DRAWING='@BASEBOARD_FAB2_LIB.BASEBOARD_FAB2(SCH_1):PAGE192',
 POP='NOPOP',
 WATTAGE='1/16W',
 TOLERANCE='1%',
 SEC_TYPE='0402',
 MATERIAL='CHIP',
 BOM_COST='CPLD',
 PHYS_PAGE='192',
 XY='(-7350,4400)',
 ROT='0',
 VER='2',
 VALUE='4.75K',
 PACK_TYPE='0402',
 PART_NUMBER='G21796-072',
 LOCATION='R7E18',
 ROOM='CPLD',
 SEC='1',
 CDS_LIB='mstr_discrete',
 CDS_PART_NAME='RES_0402-4.75K,1%,1/16W,CHIP,GA',
 PRIM_FILE='./archive_libs/mstr_discrete/res/chips/chips.prt';

PART_NAME
 R7E19 'RES_0402-1.00K,1%,1/16W,EMPTY,A':
 ROOM='CPLD';

SECTION_NUMBER 1
 '@BASEBOARD_FAB2_LIB.BASEBOARD_FAB2(SCH_1):PAGE192_I57@MSTR_DISCRETE.RES(CHIPS)':
 C_PATH='@baseboard_fab2_lib.baseboard_fab2(sch_1):page192_i57@mstr_discrete.res~
(chips)',
 P_PATH='@baseboard_fab2_lib.baseboard_fab2(sch_1):page192_i57@mstr_discrete.res~
(chips)',
 PATH='I57',
 DRAWING='@BASEBOARD_FAB2_LIB.BASEBOARD_FAB2(SCH_1):PAGE192',
 WATTAGE='1/16W',
 TOLERANCE='1%',
 SEC_TYPE='0402',
 MATERIAL='EMPTY',
 BOM_COST='CPLD',
 PHYS_PAGE='192',
 XY='(-7750,4400)',
 ROT='0',
 VER='2',
 VALUE='1.00K',
 PACK_TYPE='0402',
 PART_NUMBER='G21796-026',
 LOCATION='R7E19',
 ROOM='CPLD',
 SEC='1',
 CDS_LIB='mstr_discrete',
 CDS_PART_NAME='RES_0402-1.00K,1%,1/16W,EMPTY,A',
 PRIM_FILE='./archive_libs/mstr_discrete/res/chips/chips.prt';

PART_NAME
 R7E20 'RES_0402-1.00K,1%,1/16W,CHIP,GA':
 ROOM='CPLD';

SECTION_NUMBER 1
 '@BASEBOARD_FAB2_LIB.BASEBOARD_FAB2(SCH_1):PAGE192_I59@MSTR_DISCRETE.RES(CHIPS)':
 C_PATH='@baseboard_fab2_lib.baseboard_fab2(sch_1):page192_i59@mstr_discrete.res~
(chips)',
 P_PATH='@baseboard_fab2_lib.baseboard_fab2(sch_1):page192_i59@mstr_discrete.res~
(chips)',
 PATH='I59',
 DRAWING='@BASEBOARD_FAB2_LIB.BASEBOARD_FAB2(SCH_1):PAGE192',
 WATTAGE='1/16W',
 TOLERANCE='1%',
 SEC_TYPE='0402',
 MATERIAL='CHIP',
 BOM_COST='CPLD',
 PHYS_PAGE='192',
 XY='(-7750,3500)',
 ROT='0',
 VER='2',
 VALUE='1.00K',
 PACK_TYPE='0402',
 PART_NUMBER='G21796-026',
 LOCATION='R7E20',
 ROOM='CPLD',
 SEC='1',
 CDS_LIB='mstr_discrete',
 CDS_PART_NAME='RES_0402-1.00K,1%,1/16W,CHIP,GA',
 PRIM_FILE='./archive_libs/mstr_discrete/res/chips/chips.prt';

PART_NAME
 R7E21 'RES_0402-4.75K,1%,1/16W,CHIP,GA':
 ROOM='IO_SLOT';

SECTION_NUMBER 1
 '@BASEBOARD_FAB2_LIB.BASEBOARD_FAB2(SCH_1):PAGE108_I343@MSTR_DISCRETE.RES(CHIPS)':
 C_PATH='@baseboard_fab2_lib.baseboard_fab2(sch_1):page108_i343@mstr_discrete.re~
s(chips)',
 P_PATH='@baseboard_fab2_lib.baseboard_fab2(sch_1):page108_i343@mstr_discrete.re~
s(chips)',
 PATH='I343',
 DRAWING='@BASEBOARD_FAB2_LIB.BASEBOARD_FAB2(SCH_1):PAGE108',
 WATTAGE='1/16W',
 TOLERANCE='1%',
 SEC_TYPE='0402',
 MATERIAL='CHIP',
 PHYS_PAGE='108',
 XY='(2350,4200)',
 ROT='0',
 VER='2',
 VALUE='4.75K',
 PACK_TYPE='0402',
 PART_NUMBER='G21796-072',
 LOCATION='R7E21',
 ROOM='IO_SLOT',
 SEC='1',
 CDS_LIB='mstr_discrete',
 CDS_PART_NAME='RES_0402-4.75K,1%,1/16W,CHIP,GA',
 PRIM_FILE='./archive_libs/mstr_discrete/res/chips/chips.prt';

PART_NAME
 R7E22 'RES_0402-0.0,5%,1/16W,CHIP,G21A':
 ROOM='IO_SLOT';

SECTION_NUMBER 1
 '@BASEBOARD_FAB2_LIB.BASEBOARD_FAB2(SCH_1):PAGE108_I341@MSTR_DISCRETE.RES(CHIPS)':
 C_PATH='@baseboard_fab2_lib.baseboard_fab2(sch_1):page108_i341@mstr_discrete.re~
s(chips)',
 P_PATH='@baseboard_fab2_lib.baseboard_fab2(sch_1):page108_i341@mstr_discrete.re~
s(chips)',
 PATH='I341',
 DRAWING='@BASEBOARD_FAB2_LIB.BASEBOARD_FAB2(SCH_1):PAGE108',
 WATTAGE='1/16W',
 TOLERANCE='5%',
 SEC_TYPE='0402',
 MATERIAL='CHIP',
 PHYS_PAGE='108',
 XY='(2600,3775)',
 ROT='0',
 VER='1',
 VALUE='0.0',
 PACK_TYPE='0402',
 PART_NUMBER='G21497-005',
 LOCATION='R7E22',
 ROOM='IO_SLOT',
 SEC='1',
 CDS_LIB='mstr_discrete',
 CDS_PART_NAME='RES_0402-0.0,5%,1/16W,CHIP,G21A',
 PRIM_FILE='./archive_libs/mstr_discrete/res/chips/chips.prt';

PART_NAME
 R7F1 'RES_0402-10.0K,1%,1/16W,CHIP,GA':
 ROOM='P5V_STBY_VR',
 REUSE_ID='9';

SECTION_NUMBER 1
 '@BASEBOARD_FAB2_LIB.BASEBOARD_FAB2(SCH_1):PAGE241_I50@MSTR_DISCRETE.RES(CHIPS)':
 C_PATH='@baseboard_fab2_lib.baseboard_fab2(sch_1):page241_i50@mstr_discrete.res~
(chips)',
 P_PATH='@baseboard_fab2_lib.baseboard_fab2(sch_1):page241_i50@mstr_discrete.res~
(chips)',
 PATH='I50',
 DRAWING='@BASEBOARD_FAB2_LIB.BASEBOARD_FAB2(SCH_1):PAGE241',
 SPOF='TRUE',
 WATTAGE='1/16W',
 TOLERANCE='1%',
 SEC_TYPE='0402',
 MATERIAL='CHIP',
 BOM_COST='P5V_STBY_VR',
 PHYS_PAGE='241',
 REUSE_ID='9',
 XY='(1750,3425)',
 ROT='0',
 VER='2',
 VALUE='10.0K',
 PACK_TYPE='0402',
 PART_NUMBER='G21796-016',
 LOCATION='R7F1',
 ROOM='P5V_STBY_VR',
 SEC='1',
 CDS_LIB='mstr_discrete',
 CDS_PART_NAME='RES_0402-10.0K,1%,1/16W,CHIP,GA',
 PRIM_FILE='./archive_libs/mstr_discrete/res/chips/chips.prt';

PART_NAME
 R7F3 'RES_0402-33.2,1%,1/16W,CHIP,G2A':
 ROOM='SB_SPI',
 NO_XNET_CONNECTION='1';

SECTION_NUMBER 1
 '@BASEBOARD_FAB2_LIB.BASEBOARD_FAB2(SCH_1):PAGE153_I109@MSTR_DISCRETE.RES(CHIPS)':
 C_PATH='@baseboard_fab2_lib.baseboard_fab2(sch_1):page153_i109@mstr_discrete.re~
s(chips)',
 P_PATH='@baseboard_fab2_lib.baseboard_fab2(sch_1):page153_i109@mstr_discrete.re~
s(chips)',
 PATH='I109',
 DRAWING='@BASEBOARD_FAB2_LIB.BASEBOARD_FAB2(SCH_1):PAGE153',
 WATTAGE='1/16W',
 TOLERANCE='1%',
 SEC_TYPE='0402',
 MATERIAL='CHIP',
 BOM_COST='MIO_BIOS_MEM',
 NO_XNET_CONNECTION='1',
 PHYS_PAGE='153',
 XY='(-6475,3075)',
 ROT='0',
 VER='1',
 VALUE='33.2',
 PACK_TYPE='0402',
 PART_NUMBER='G21796-074',
 LOCATION='R7F3',
 ROOM='SB_SPI',
 SEC='1',
 CDS_LIB='mstr_discrete',
 CDS_PART_NAME='RES_0402-33.2,1%,1/16W,CHIP,G2A',
 PRIM_FILE='./archive_libs/mstr_discrete/res/chips/chips.prt';

PART_NAME
 R7F4 'RES_0402-33.2,1%,1/16W,CHIP,G2A':
 ROOM='SB_SPI';

SECTION_NUMBER 1
 '@BASEBOARD_FAB2_LIB.BASEBOARD_FAB2(SCH_1):PAGE153_I98@MSTR_DISCRETE.RES(CHIPS)':
 C_PATH='@baseboard_fab2_lib.baseboard_fab2(sch_1):page153_i98@mstr_discrete.res~
(chips)',
 P_PATH='@baseboard_fab2_lib.baseboard_fab2(sch_1):page153_i98@mstr_discrete.res~
(chips)',
 PATH='I98',
 DRAWING='@BASEBOARD_FAB2_LIB.BASEBOARD_FAB2(SCH_1):PAGE153',
 WATTAGE='1/16W',
 TOLERANCE='1%',
 SEC_TYPE='0402',
 MATERIAL='CHIP',
 BOM_COST='MIO_BIOS_MEM',
 PHYS_PAGE='153',
 XY='(-6275,3975)',
 ROT='0',
 VER='1',
 VALUE='33.2',
 PACK_TYPE='0402',
 PART_NUMBER='G21796-074',
 LOCATION='R7F4',
 ROOM='SB_SPI',
 SEC='1',
 CDS_LIB='mstr_discrete',
 CDS_PART_NAME='RES_0402-33.2,1%,1/16W,CHIP,G2A',
 PRIM_FILE='./archive_libs/mstr_discrete/res/chips/chips.prt';

PART_NAME
 R7F5 'RES_0402-4.75K,1%,1/16W,CHIP,GA':
 ROOM='SB_SPI',
 NO_XNET_CONNECTION='1';

SECTION_NUMBER 1
 '@BASEBOARD_FAB2_LIB.BASEBOARD_FAB2(SCH_1):PAGE153_I94@MSTR_DISCRETE.RES(CHIPS)':
 C_PATH='@baseboard_fab2_lib.baseboard_fab2(sch_1):page153_i94@mstr_discrete.res~
(chips)',
 P_PATH='@baseboard_fab2_lib.baseboard_fab2(sch_1):page153_i94@mstr_discrete.res~
(chips)',
 PATH='I94',
 DRAWING='@BASEBOARD_FAB2_LIB.BASEBOARD_FAB2(SCH_1):PAGE153',
 WATTAGE='1/16W',
 TOLERANCE='1%',
 SEC_TYPE='0402',
 MATERIAL='CHIP',
 BOM_COST='MIO_BIOS_MEM',
 NO_XNET_CONNECTION='1',
 PHYS_PAGE='153',
 XY='(-6250,4425)',
 ROT='2',
 VER='2',
 VALUE='4.75K',
 PACK_TYPE='0402',
 PART_NUMBER='G21796-072',
 LOCATION='R7F5',
 ROOM='SB_SPI',
 SEC='1',
 CDS_LIB='mstr_discrete',
 CDS_PART_NAME='RES_0402-4.75K,1%,1/16W,CHIP,GA',
 PRIM_FILE='./archive_libs/mstr_discrete/res/chips/chips.prt';

PART_NAME
 R7F6 'RES_0402-4.75K,1%,1/16W,EMPTY,A':
 ROOM='SB_SPI',
 NO_XNET_CONNECTION='1';

SECTION_NUMBER 1
 '@BASEBOARD_FAB2_LIB.BASEBOARD_FAB2(SCH_1):PAGE153_I90@MSTR_DISCRETE.RES(CHIPS)':
 C_PATH='@baseboard_fab2_lib.baseboard_fab2(sch_1):page153_i90@mstr_discrete.res~
(chips)',
 P_PATH='@baseboard_fab2_lib.baseboard_fab2(sch_1):page153_i90@mstr_discrete.res~
(chips)',
 PATH='I90',
 DRAWING='@BASEBOARD_FAB2_LIB.BASEBOARD_FAB2(SCH_1):PAGE153',
 WATTAGE='1/16W',
 TOLERANCE='1%',
 SEC_TYPE='0402',
 MATERIAL='EMPTY',
 BOM_COST='MIO_BIOS_MEM',
 NO_XNET_CONNECTION='1',
 PHYS_PAGE='153',
 XY='(-5950,4425)',
 ROT='2',
 VER='2',
 VALUE='4.75K',
 PACK_TYPE='0402',
 PART_NUMBER='G21796-072',
 LOCATION='R7F6',
 ROOM='SB_SPI',
 SEC='1',
 CDS_LIB='mstr_discrete',
 CDS_PART_NAME='RES_0402-4.75K,1%,1/16W,EMPTY,A',
 PRIM_FILE='./archive_libs/mstr_discrete/res/chips/chips.prt';

PART_NAME
 R7F7 'RES_0402-2.2,5%,1/16W,EMPTY,G2A':
 ROOM='PVPP_KLM_VR',
 REUSE_ID='29';

SECTION_NUMBER 1
 '@BASEBOARD_FAB2_LIB.BASEBOARD_FAB2(SCH_1):PAGE231_I174@MSTR_DISCRETE.RES(CHIPS)':
 C_PATH='@baseboard_fab2_lib.baseboard_fab2(sch_1):page231_i174@mstr_discrete.re~
s(chips)',
 P_PATH='@baseboard_fab2_lib.baseboard_fab2(sch_1):page231_i174@mstr_discrete.re~
s(chips)',
 PATH='I174',
 DRAWING='@BASEBOARD_FAB2_LIB.BASEBOARD_FAB2(SCH_1):PAGE231',
 WATTAGE='1/16W',
 TOLERANCE='5%',
 MATERIAL='EMPTY',
 BOM_COST='PVPP_KLM_VR',
 PHYS_PAGE='231',
 REUSE_ID='29',
 XY='(-2300,3600)',
 ROT='0',
 VER='2',
 VALUE='2.2',
 PACK_TYPE='0402',
 PART_NUMBER='G21497-016',
 LOCATION='R7F7',
 ROOM='PVPP_KLM_VR',
 CDS_LIB='mstr_discrete',
 CDS_PART_NAME='RES_0402-2.2,5%,1/16W,EMPTY,G2A',
 PRIM_FILE='./archive_libs/mstr_discrete/res/chips/chips.prt';

PART_NAME
 R7F8 'RES_0603-0,5.0%,1/10W,CHIP,G22A':
 ROOM='NIC_SPRV';

SECTION_NUMBER 1
 '@BASEBOARD_FAB2_LIB.BASEBOARD_FAB2(SCH_1):PAGE231_I229@MSTR_DISCRETE.RES(CHIPS)':
 C_PATH='@baseboard_fab2_lib.baseboard_fab2(sch_1):page231_i229@mstr_discrete.re~
s(chips)',
 P_PATH='@baseboard_fab2_lib.baseboard_fab2(sch_1):page231_i229@mstr_discrete.re~
s(chips)',
 PATH='I229',
 DRAWING='@BASEBOARD_FAB2_LIB.BASEBOARD_FAB2(SCH_1):PAGE231',
 WATTAGE='1/10W',
 TOLERANCE='5.0%',
 SEC_TYPE='0603',
 MATERIAL='CHIP',
 BOM_COST='NT_GBE_BASE',
 PHYS_PAGE='231',
 XY='(-3800,4450)',
 ROT='0',
 VER='1',
 VALUE='0',
 PACK_TYPE='0603',
 PART_NUMBER='G22178-002',
 LOCATION='R7F8',
 ROOM='NIC_SPRV',
 SEC='1',
 CDS_LIB='mstr_discrete',
 CDS_PART_NAME='RES_0603-0,5.0%,1/10W,CHIP,G22A',
 PRIM_FILE='./archive_libs/mstr_discrete/res/chips/chips.prt';

PART_NAME
 R7F9 'RES_0402-0.0,5%,1/16W,CHIP,G21A':
 ROOM='PVCCIN_CPU0_VR';

SECTION_NUMBER 1
 '@BASEBOARD_FAB2_LIB.BASEBOARD_FAB2(SCH_1):PAGE231_I220@MSTR_DISCRETE.RES(CHIPS)':
 C_PATH='@baseboard_fab2_lib.baseboard_fab2(sch_1):page231_i220@mstr_discrete.re~
s(chips)',
 P_PATH='@baseboard_fab2_lib.baseboard_fab2(sch_1):page231_i220@mstr_discrete.re~
s(chips)',
 PATH='I220',
 DRAWING='@BASEBOARD_FAB2_LIB.BASEBOARD_FAB2(SCH_1):PAGE231',
 WATTAGE='1/16W',
 TOLERANCE='5%',
 SEC_TYPE='0402',
 MATERIAL='CHIP',
 PHYS_PAGE='231',
 XY='(-5775,3075)',
 ROT='0',
 VER='1',
 VALUE='0.0',
 PACK_TYPE='0402',
 PART_NUMBER='G21497-005',
 LOCATION='R7F9',
 ROOM='PVCCIN_CPU0_VR',
 SEC='1',
 CDS_LIB='mstr_discrete',
 CDS_PART_NAME='RES_0402-0.0,5%,1/16W,CHIP,G21A',
 PRIM_FILE='./archive_libs/mstr_discrete/res/chips/chips.prt';

PART_NAME
 R7F10 'RES_0603-120.0,1%,1/10W,CHIP,GA':
 ROOM='PVPP_KLM_VR',
 REUSE_ID='34';

SECTION_NUMBER 1
 '@BASEBOARD_FAB2_LIB.BASEBOARD_FAB2(SCH_1):PAGE231_I177@MSTR_DISCRETE.RES(CHIPS)':
 C_PATH='@baseboard_fab2_lib.baseboard_fab2(sch_1):page231_i177@mstr_discrete.re~
s(chips)',
 P_PATH='@baseboard_fab2_lib.baseboard_fab2(sch_1):page231_i177@mstr_discrete.re~
s(chips)',
 PATH='I177',
 DRAWING='@BASEBOARD_FAB2_LIB.BASEBOARD_FAB2(SCH_1):PAGE231',
 WATTAGE='1/10W',
 TOLERANCE='1%',
 SEC_TYPE='0603',
 MATERIAL='CHIP',
 BOM_COST='PVPP_KLM_VR',
 PHYS_PAGE='231',
 REUSE_ID='34',
 XY='(-1725,3925)',
 ROT='0',
 VER='2',
 VALUE='120.0',
 PACK_TYPE='0603',
 PART_NUMBER='G22026-003',
 LOCATION='R7F10',
 ROOM='PVPP_KLM_VR',
 SEC='1',
 CDS_LIB='mstr_discrete',
 CDS_PART_NAME='RES_0603-120.0,1%,1/10W,CHIP,GA',
 PRIM_FILE='./archive_libs/mstr_discrete/res/chips/chips.prt';

PART_NAME
 R7F11 'RES_0402-6.19K,1%,1/16W,CHIP,GA':
 ROOM='IO_SLOT';

SECTION_NUMBER 1
 '@BASEBOARD_FAB2_LIB.BASEBOARD_FAB2(SCH_1):PAGE231_I230@MSTR_DISCRETE.RES(CHIPS)':
 C_PATH='@baseboard_fab2_lib.baseboard_fab2(sch_1):page231_i230@mstr_discrete.re~
s(chips)',
 P_PATH='@baseboard_fab2_lib.baseboard_fab2(sch_1):page231_i230@mstr_discrete.re~
s(chips)',
 PATH='I230',
 DRAWING='@BASEBOARD_FAB2_LIB.BASEBOARD_FAB2(SCH_1):PAGE231',
 WATTAGE='1/16W',
 TOLERANCE='1%',
 SEC_TYPE='0402',
 MATERIAL='CHIP',
 BOM_COST='IO_SLOT',
 PHYS_PAGE='231',
 XY='(-1000,1550)',
 ROT='0',
 VER='2',
 VALUE='6.19K',
 PACK_TYPE='0402',
 PART_NUMBER='G21796-161',
 LOCATION='R7F11',
 ROOM='IO_SLOT',
 SEC='1',
 CDS_LIB='mstr_discrete',
 CDS_PART_NAME='RES_0402-6.19K,1%,1/16W,CHIP,GA',
 PRIM_FILE='./archive_libs/mstr_discrete/res/chips/chips.prt';

PART_NAME
 R7F12 'RES_0402-0.0,5%,1/16W,CHIP,G21A':
 ROOM='PVPP_KLM_VR';

SECTION_NUMBER 1
 '@BASEBOARD_FAB2_LIB.BASEBOARD_FAB2(SCH_1):PAGE231_I168@MSTR_DISCRETE.RES(CHIPS)':
 C_PATH='@baseboard_fab2_lib.baseboard_fab2(sch_1):page231_i168@mstr_discrete.re~
s(chips)',
 P_PATH='@baseboard_fab2_lib.baseboard_fab2(sch_1):page231_i168@mstr_discrete.re~
s(chips)',
 PATH='I168',
 DRAWING='@BASEBOARD_FAB2_LIB.BASEBOARD_FAB2(SCH_1):PAGE231',
 SPOF='TRUE',
 WATTAGE='1/16W',
 TOLERANCE='5%',
 SEC_TYPE='0402',
 MATERIAL='CHIP',
 PHYS_PAGE='231',
 XY='(-1000,3175)',
 ROT='5',
 VER='1',
 VALUE='0.0',
 PACK_TYPE='0402',
 PART_NUMBER='G21497-005',
 LOCATION='R7F12',
 ROOM='PVPP_KLM_VR',
 SEC='1',
 CDS_LIB='mstr_discrete',
 CDS_PART_NAME='RES_0402-0.0,5%,1/16W,CHIP,G21A',
 PRIM_FILE='./archive_libs/mstr_discrete/res/chips/chips.prt';

PART_NAME
 R7F13 'RES_0402-20.0K,1%,1/16W,CHIP,GA':
 ROOM='PVPP_KLM_VR',
 REUSE_ID='9';

SECTION_NUMBER 1
 '@BASEBOARD_FAB2_LIB.BASEBOARD_FAB2(SCH_1):PAGE231_I167@MSTR_DISCRETE.RES(CHIPS)':
 C_PATH='@baseboard_fab2_lib.baseboard_fab2(sch_1):page231_i167@mstr_discrete.re~
s(chips)',
 P_PATH='@baseboard_fab2_lib.baseboard_fab2(sch_1):page231_i167@mstr_discrete.re~
s(chips)',
 PATH='I167',
 DRAWING='@BASEBOARD_FAB2_LIB.BASEBOARD_FAB2(SCH_1):PAGE231',
 SPOF='TRUE',
 WATTAGE='1/16W',
 TOLERANCE='1%',
 MATERIAL='CHIP',
 BOM_COST='PVPP_KLM_VR',
 PHYS_PAGE='231',
 REUSE_ID='9',
 XY='(-1000,2250)',
 ROT='0',
 VER='2',
 VALUE='20.0K',
 PACK_TYPE='0402',
 PART_NUMBER='G21796-040',
 LOCATION='R7F13',
 ROOM='PVPP_KLM_VR',
 CDS_LIB='mstr_discrete',
 CDS_PART_NAME='RES_0402-20.0K,1%,1/16W,CHIP,GA',
 PRIM_FILE='./archive_libs/mstr_discrete/res/chips/chips.prt';

PART_NAME
 R7F14 'RES_0402-10.0K,1%,1/16W,CHIP,GA':
 ROOM='PVPP_KLM_VR';

SECTION_NUMBER 1
 '@BASEBOARD_FAB2_LIB.BASEBOARD_FAB2(SCH_1):PAGE231_I136@MSTR_DISCRETE.RES(CHIPS)':
 C_PATH='@baseboard_fab2_lib.baseboard_fab2(sch_1):page231_i136@mstr_discrete.re~
s(chips)',
 P_PATH='@baseboard_fab2_lib.baseboard_fab2(sch_1):page231_i136@mstr_discrete.re~
s(chips)',
 PATH='I136',
 DRAWING='@BASEBOARD_FAB2_LIB.BASEBOARD_FAB2(SCH_1):PAGE231',
 BOM='SYSB_CPLD',
 WATTAGE='1/16W',
 TOLERANCE='1%',
 MATERIAL='CHIP',
 BOM_COST='PVPP_KLM_VR',
 PHYS_PAGE='231',
 XY='(-6625,2450)',
 ROT='0',
 VER='2',
 VALUE='10.0K',
 PACK_TYPE='0402',
 PART_NUMBER='G21796-016',
 LOCATION='R7F14',
 ROOM='PVPP_KLM_VR',
 CDS_LIB='mstr_discrete',
 CDS_PART_NAME='RES_0402-10.0K,1%,1/16W,CHIP,GA',
 PRIM_FILE='./archive_libs/mstr_discrete/res/chips/chips.prt';

PART_NAME
 R7F15 'RES_0402-7.87K,1.0%,1/16W,CHIPA':
 ROOM='PVPP_KLM_VR';

SECTION_NUMBER 1
 '@BASEBOARD_FAB2_LIB.BASEBOARD_FAB2(SCH_1):PAGE231_I134@MSTR_DISCRETE.RES(CHIPS)':
 C_PATH='@baseboard_fab2_lib.baseboard_fab2(sch_1):page231_i134@mstr_discrete.re~
s(chips)',
 P_PATH='@baseboard_fab2_lib.baseboard_fab2(sch_1):page231_i134@mstr_discrete.re~
s(chips)',
 PATH='I134',
 DRAWING='@BASEBOARD_FAB2_LIB.BASEBOARD_FAB2(SCH_1):PAGE231',
 NEW_VALUE='3.9K',
 CONFIG='64.39015.6DL',
 WATTAGE='1/16W',
 TOLERANCE='1.0%',
 MATERIAL='CHIP',
 BOM_COST='PVPP_KLM_VR',
 PHYS_PAGE='231',
 XY='(-4400,1900)',
 ROT='2',
 VER='2',
 VALUE='7.87K',
 PACK_TYPE='0402',
 PART_NUMBER='G21796-242',
 LOCATION='R7F15',
 ROOM='PVPP_KLM_VR',
 CDS_LIB='mstr_discrete',
 CDS_PART_NAME='RES_0402-7.87K,1.0%,1/16W,CHIPA',
 PRIM_FILE='./archive_libs/mstr_discrete/res/chips/chips.prt';

PART_NAME
 R7F16 'RES_0402-22.1,1.0%,1/16W,CHIP,A':
 ROOM='PVPP_KLM_VR';

SECTION_NUMBER 1
 '@BASEBOARD_FAB2_LIB.BASEBOARD_FAB2(SCH_1):PAGE231_I208@MSTR_DISCRETE.RES(CHIPS)':
 C_PATH='@baseboard_fab2_lib.baseboard_fab2(sch_1):page231_i208@mstr_discrete.re~
s(chips)',
 P_PATH='@baseboard_fab2_lib.baseboard_fab2(sch_1):page231_i208@mstr_discrete.re~
s(chips)',
 PATH='I208',
 DRAWING='@BASEBOARD_FAB2_LIB.BASEBOARD_FAB2(SCH_1):PAGE231',
 WATTAGE='1/16W',
 TOLERANCE='1.0%',
 SEC_TYPE='0402',
 MATERIAL='CHIP',
 PHYS_PAGE='231',
 XY='(-3000,1225)',
 ROT='0',
 VER='1',
 VALUE='22.1',
 PACK_TYPE='0402',
 PART_NUMBER='G21796-250',
 LOCATION='R7F16',
 ROOM='PVPP_KLM_VR',
 SEC='1',
 CDS_LIB='mstr_discrete',
 CDS_PART_NAME='RES_0402-22.1,1.0%,1/16W,CHIP,A',
 PRIM_FILE='./archive_libs/mstr_discrete/res/chips/chips.prt';

PART_NAME
 R7F17 'RES_0402-1.0K,0.1%,1/16W,CHIP,A':
 ROOM='PVPP_KLM_VR',
 REUSE_ID='29';

SECTION_NUMBER 1
 '@BASEBOARD_FAB2_LIB.BASEBOARD_FAB2(SCH_1):PAGE231_I218@MSTR_DISCRETE.RES(CHIPS)':
 C_PATH='@baseboard_fab2_lib.baseboard_fab2(sch_1):page231_i218@mstr_discrete.re~
s(chips)',
 P_PATH='@baseboard_fab2_lib.baseboard_fab2(sch_1):page231_i218@mstr_discrete.re~
s(chips)',
 PATH='I218',
 DRAWING='@BASEBOARD_FAB2_LIB.BASEBOARD_FAB2(SCH_1):PAGE231',
 SPOF='TRUE',
 WATTAGE='1/16W',
 TOLERANCE='0.1%',
 SEC_TYPE='0402',
 MATERIAL='CHIP',
 BOM_COST='PVPP_KLM_VR',
 PHYS_PAGE='231',
 REUSE_ID='29',
 XY='(-675,2800)',
 ROT='0',
 VER='2',
 VALUE='1.0K',
 PACK_TYPE='0402',
 PART_NUMBER='G85996-004',
 LOCATION='R7F17',
 ROOM='PVPP_KLM_VR',
 SEC='1',
 CDS_LIB='mstr_discrete',
 CDS_PART_NAME='RES_0402-1.0K,0.1%,1/16W,CHIP,A',
 PRIM_FILE='./archive_libs/mstr_discrete/res/chips/chips.prt';

PART_NAME
 R7F18 'RES_0402-7.87K,1.0%,1/16W,CHIPA':
 ROOM='PVPP_KLM_VR',
 REUSE_ID='13';

SECTION_NUMBER 1
 '@BASEBOARD_FAB2_LIB.BASEBOARD_FAB2(SCH_1):PAGE231_I201@MSTR_DISCRETE.RES(CHIPS)':
 C_PATH='@baseboard_fab2_lib.baseboard_fab2(sch_1):page231_i201@mstr_discrete.re~
s(chips)',
 P_PATH='@baseboard_fab2_lib.baseboard_fab2(sch_1):page231_i201@mstr_discrete.re~
s(chips)',
 PATH='I201',
 DRAWING='@BASEBOARD_FAB2_LIB.BASEBOARD_FAB2(SCH_1):PAGE231',
 WATTAGE='1/16W',
 TOLERANCE='1.0%',
 SEC_TYPE='0402',
 MATERIAL='CHIP',
 BOM_COST='PVPP_KLM_VR',
 PHYS_PAGE='231',
 REUSE_ID='13',
 XY='(-1800,2700)',
 ROT='0',
 VER='1',
 VALUE='7.87K',
 PACK_TYPE='0402',
 PART_NUMBER='G21796-242',
 LOCATION='R7F18',
 ROOM='PVPP_KLM_VR',
 SEC='1',
 CDS_LIB='mstr_discrete',
 CDS_PART_NAME='RES_0402-7.87K,1.0%,1/16W,CHIPA',
 PRIM_FILE='./archive_libs/mstr_discrete/res/chips/chips.prt';

PART_NAME
 R7F19 'RES_0402-1.00K,1%,1/16W,CHIP,GA':
 ROOM='PVPP_KLM_VR',
 REUSE_ID='21';

SECTION_NUMBER 1
 '@BASEBOARD_FAB2_LIB.BASEBOARD_FAB2(SCH_1):PAGE231_I143@MSTR_DISCRETE.RES(CHIPS)':
 C_PATH='@baseboard_fab2_lib.baseboard_fab2(sch_1):page231_i143@mstr_discrete.re~
s(chips)',
 P_PATH='@baseboard_fab2_lib.baseboard_fab2(sch_1):page231_i143@mstr_discrete.re~
s(chips)',
 PATH='I143',
 DRAWING='@BASEBOARD_FAB2_LIB.BASEBOARD_FAB2(SCH_1):PAGE231',
 WATTAGE='1/16W',
 TOLERANCE='1%',
 SEC_TYPE='0402',
 MATERIAL='CHIP',
 BOM_COST='PVPP_KLM_VR',
 PHYS_PAGE='231',
 REUSE_ID='21',
 XY='(-3875,1500)',
 ROT='0',
 VER='2',
 VALUE='1.00K',
 PACK_TYPE='0402',
 PART_NUMBER='G21796-026',
 LOCATION='R7F19',
 ROOM='PVPP_KLM_VR',
 SEC='1',
 CDS_LIB='mstr_discrete',
 CDS_PART_NAME='RES_0402-1.00K,1%,1/16W,CHIP,GA',
 PRIM_FILE='./archive_libs/mstr_discrete/res/chips/chips.prt';

PART_NAME
 R7F20 'RES_0402-100.0K,1%,1/16W,EMPTYA':
 ROOM='BMC';

SECTION_NUMBER 1
 '@BASEBOARD_FAB2_LIB.BASEBOARD_FAB2(SCH_1):PAGE215_I29@MSTR_DISCRETE.RES(CHIPS)':
 C_PATH='@baseboard_fab2_lib.baseboard_fab2(sch_1):page215_i29@mstr_discrete.res~
(chips)',
 P_PATH='@baseboard_fab2_lib.baseboard_fab2(sch_1):page215_i29@mstr_discrete.res~
(chips)',
 PATH='I29',
 DRAWING='@BASEBOARD_FAB2_LIB.BASEBOARD_FAB2(SCH_1):PAGE215',
 WATTAGE='1/16W',
 TOLERANCE='1%',
 SEC_TYPE='0402',
 MATERIAL='EMPTY',
 BOM_COST='SM_CONTROLLER',
 PHYS_PAGE='215',
 XY='(975,3325)',
 ROT='0',
 VER='2',
 VALUE='100.0K',
 PACK_TYPE='0402',
 PART_NUMBER='G21796-010',
 LOCATION='R7F20',
 ROOM='BMC',
 SEC='1',
 CDS_LIB='mstr_discrete',
 CDS_PART_NAME='RES_0402-100.0K,1%,1/16W,EMPTYA',
 PRIM_FILE='./archive_libs/mstr_discrete/res/chips/chips.prt';

PART_NAME
 R7F21 'RES_0402-0.0,5%,1/16W,CHIP,G21A':
 ROOM='PVCCIN_CPU0_VR';

SECTION_NUMBER 1
 '@BASEBOARD_FAB2_LIB.BASEBOARD_FAB2(SCH_1):PAGE215_I13@MSTR_DISCRETE.RES(CHIPS)':
 C_PATH='@baseboard_fab2_lib.baseboard_fab2(sch_1):page215_i13@mstr_discrete.res~
(chips)',
 P_PATH='@baseboard_fab2_lib.baseboard_fab2(sch_1):page215_i13@mstr_discrete.res~
(chips)',
 PATH='I13',
 DRAWING='@BASEBOARD_FAB2_LIB.BASEBOARD_FAB2(SCH_1):PAGE215',
 WATTAGE='1/16W',
 TOLERANCE='5%',
 SEC_TYPE='0402',
 MATERIAL='CHIP',
 PHYS_PAGE='215',
 XY='(-425,1300)',
 ROT='0',
 VER='1',
 VALUE='0.0',
 PACK_TYPE='0402',
 PART_NUMBER='G21497-005',
 LOCATION='R7F21',
 ROOM='PVCCIN_CPU0_VR',
 SEC='1',
 CDS_LIB='mstr_discrete',
 CDS_PART_NAME='RES_0402-0.0,5%,1/16W,CHIP,G21A',
 PRIM_FILE='./archive_libs/mstr_discrete/res/chips/chips.prt';

PART_NAME
 R7F22 'RES_0402-1.00K,1%,1/16W,CHIP,GA':
 ROOM='VDDQ_ABC_PWR_VR';

SECTION_NUMBER 1
 '@BASEBOARD_FAB2_LIB.BASEBOARD_FAB2(SCH_1):PAGE215_I51@MSTR_DISCRETE.RES(CHIPS)':
 C_PATH='@baseboard_fab2_lib.baseboard_fab2(sch_1):page215_i51@mstr_discrete.res~
(chips)',
 P_PATH='@baseboard_fab2_lib.baseboard_fab2(sch_1):page215_i51@mstr_discrete.res~
(chips)',
 PATH='I51',
 DRAWING='@BASEBOARD_FAB2_LIB.BASEBOARD_FAB2(SCH_1):PAGE215',
 WATTAGE='1/16W',
 TOLERANCE='1%',
 SEC_TYPE='0402',
 MATERIAL='CHIP',
 PHYS_PAGE='215',
 XY='(3300,2900)',
 ROT='0',
 VER='2',
 VALUE='1.00K',
 PACK_TYPE='0402',
 PART_NUMBER='G21796-026',
 LOCATION='R7F22',
 ROOM='VDDQ_ABC_PWR_VR',
 SEC='1',
 CDS_LIB='mstr_discrete',
 CDS_PART_NAME='RES_0402-1.00K,1%,1/16W,CHIP,GA',
 PRIM_FILE='./archive_libs/mstr_discrete/res/chips/chips.prt';

PART_NAME
 R7F23 'RES_0402-33.2,1%,1/16W,CHIP,G2A':;

SECTION_NUMBER 1
 '@BASEBOARD_FAB2_LIB.BASEBOARD_FAB2(SCH_1):PAGE215_I53@MSTR_DISCRETE.RES(CHIPS)':
 C_PATH='@baseboard_fab2_lib.baseboard_fab2(sch_1):page215_i53@mstr_discrete.res~
(chips)',
 P_PATH='@baseboard_fab2_lib.baseboard_fab2(sch_1):page215_i53@mstr_discrete.res~
(chips)',
 PATH='I53',
 DRAWING='@BASEBOARD_FAB2_LIB.BASEBOARD_FAB2(SCH_1):PAGE215',
 WATTAGE='1/16W',
 TOLERANCE='1%',
 SEC_TYPE='0402',
 MATERIAL='CHIP',
 PHYS_PAGE='215',
 XY='(3975,2250)',
 ROT='0',
 VER='1',
 VALUE='33.2',
 PACK_TYPE='0402',
 PART_NUMBER='G21796-074',
 LOCATION='R7F23',
 SEC='1',
 CDS_LIB='mstr_discrete',
 CDS_PART_NAME='RES_0402-33.2,1%,1/16W,CHIP,G2A',
 PRIM_FILE='./archive_libs/mstr_discrete/res/chips/chips.prt';

PART_NAME
 R7F24 'RES_0402-22.1,1.0%,1/16W,CHIP,A':
 ROOM='VDDQ_ABC_PWR_VR';

SECTION_NUMBER 1
 '@BASEBOARD_FAB2_LIB.BASEBOARD_FAB2(SCH_1):PAGE215_I56@MSTR_DISCRETE.RES(CHIPS)':
 C_PATH='@baseboard_fab2_lib.baseboard_fab2(sch_1):page215_i56@mstr_discrete.res~
(chips)',
 P_PATH='@baseboard_fab2_lib.baseboard_fab2(sch_1):page215_i56@mstr_discrete.res~
(chips)',
 PATH='I56',
 DRAWING='@BASEBOARD_FAB2_LIB.BASEBOARD_FAB2(SCH_1):PAGE215',
 POP='NOPOP',
 WATTAGE='1/16W',
 TOLERANCE='1.0%',
 SEC_TYPE='0402',
 MATERIAL='CHIP',
 PHYS_PAGE='215',
 XY='(4050,2350)',
 ROT='0',
 VER='1',
 VALUE='22.1',
 PACK_TYPE='0402',
 PART_NUMBER='G21796-250',
 LOCATION='R7F24',
 ROOM='VDDQ_ABC_PWR_VR',
 SEC='1',
 CDS_LIB='mstr_discrete',
 CDS_PART_NAME='RES_0402-22.1,1.0%,1/16W,CHIP,A',
 PRIM_FILE='./archive_libs/mstr_discrete/res/chips/chips.prt';

PART_NAME
 R7F27 'RES_0402-1.00K,1%,1/16W,CHIP,GA':
 ROOM='VDDQ_ABC_PWR_VR';

SECTION_NUMBER 1
 '@BASEBOARD_FAB2_LIB.BASEBOARD_FAB2(SCH_1):PAGE215_I50@MSTR_DISCRETE.RES(CHIPS)':
 C_PATH='@baseboard_fab2_lib.baseboard_fab2(sch_1):page215_i50@mstr_discrete.res~
(chips)',
 P_PATH='@baseboard_fab2_lib.baseboard_fab2(sch_1):page215_i50@mstr_discrete.res~
(chips)',
 PATH='I50',
 DRAWING='@BASEBOARD_FAB2_LIB.BASEBOARD_FAB2(SCH_1):PAGE215',
 WATTAGE='1/16W',
 TOLERANCE='1%',
 SEC_TYPE='0402',
 MATERIAL='CHIP',
 PHYS_PAGE='215',
 XY='(2950,2900)',
 ROT='0',
 VER='2',
 VALUE='1.00K',
 PACK_TYPE='0402',
 PART_NUMBER='G21796-026',
 LOCATION='R7F27',
 ROOM='VDDQ_ABC_PWR_VR',
 SEC='1',
 CDS_LIB='mstr_discrete',
 CDS_PART_NAME='RES_0402-1.00K,1%,1/16W,CHIP,GA',
 PRIM_FILE='./archive_libs/mstr_discrete/res/chips/chips.prt';

PART_NAME
 R7F28 'RES_0402-10.0K,1%,1/16W,CHIP,GA':
 ROOM='SB_SPI',
 NO_XNET_CONNECTION='1';

SECTION_NUMBER 1
 '@BASEBOARD_FAB2_LIB.BASEBOARD_FAB2(SCH_1):PAGE153_I168@MSTR_DISCRETE.RES(CHIPS)':
 C_PATH='@baseboard_fab2_lib.baseboard_fab2(sch_1):page153_i168@mstr_discrete.re~
s(chips)',
 P_PATH='@baseboard_fab2_lib.baseboard_fab2(sch_1):page153_i168@mstr_discrete.re~
s(chips)',
 PATH='I168',
 DRAWING='@BASEBOARD_FAB2_LIB.BASEBOARD_FAB2(SCH_1):PAGE153',
 WATTAGE='1/16W',
 TOLERANCE='1%',
 SEC_TYPE='0402',
 MATERIAL='CHIP',
 BOM_COST='MIO_BIOS_MEM',
 NO_XNET_CONNECTION='1',
 PHYS_PAGE='153',
 XY='(-1750,3925)',
 ROT='0',
 VER='2',
 VALUE='10.0K',
 PACK_TYPE='0402',
 PART_NUMBER='G21796-016',
 LOCATION='R7F28',
 ROOM='SB_SPI',
 SEC='1',
 CDS_LIB='mstr_discrete',
 CDS_PART_NAME='RES_0402-10.0K,1%,1/16W,CHIP,GA',
 PRIM_FILE='./archive_libs/mstr_discrete/res/chips/chips.prt';

PART_NAME
 R7F29 'RES_0402-33.2,1%,1/16W,CHIP,G2A':
 ROOM='SB_SPI';

SECTION_NUMBER 1
 '@BASEBOARD_FAB2_LIB.BASEBOARD_FAB2(SCH_1):PAGE153_I181@MSTR_DISCRETE.RES(CHIPS)':
 C_PATH='@baseboard_fab2_lib.baseboard_fab2(sch_1):page153_i181@mstr_discrete.re~
s(chips)',
 P_PATH='@baseboard_fab2_lib.baseboard_fab2(sch_1):page153_i181@mstr_discrete.re~
s(chips)',
 PATH='I181',
 DRAWING='@BASEBOARD_FAB2_LIB.BASEBOARD_FAB2(SCH_1):PAGE153',
 WATTAGE='1/16W',
 TOLERANCE='1%',
 SEC_TYPE='0402',
 MATERIAL='CHIP',
 BOM_COST='MIO_BIOS_MEM',
 PHYS_PAGE='153',
 XY='(-6525,3925)',
 ROT='0',
 VER='1',
 VALUE='33.2',
 PACK_TYPE='0402',
 PART_NUMBER='G21796-074',
 LOCATION='R7F29',
 ROOM='SB_SPI',
 SEC='1',
 CDS_LIB='mstr_discrete',
 CDS_PART_NAME='RES_0402-33.2,1%,1/16W,CHIP,G2A',
 PRIM_FILE='./archive_libs/mstr_discrete/res/chips/chips.prt';

PART_NAME
 R7F30 'RES_0402-10.0K,1%,1/16W,EMPTY,A':
 ROOM='SB_SPI';

SECTION_NUMBER 1
 '@BASEBOARD_FAB2_LIB.BASEBOARD_FAB2(SCH_1):PAGE153_I170@MSTR_DISCRETE.RES(CHIPS)':
 C_PATH='@baseboard_fab2_lib.baseboard_fab2(sch_1):page153_i170@mstr_discrete.re~
s(chips)',
 P_PATH='@baseboard_fab2_lib.baseboard_fab2(sch_1):page153_i170@mstr_discrete.re~
s(chips)',
 PATH='I170',
 DRAWING='@BASEBOARD_FAB2_LIB.BASEBOARD_FAB2(SCH_1):PAGE153',
 WATTAGE='1/16W',
 TOLERANCE='1%',
 SEC_TYPE='0402',
 MATERIAL='EMPTY',
 BOM_COST='MIO_BIOS_MEM',
 PHYS_PAGE='153',
 XY='(-1750,3550)',
 ROT='0',
 VER='2',
 VALUE='10.0K',
 PACK_TYPE='0402',
 PART_NUMBER='G21796-016',
 LOCATION='R7F30',
 ROOM='SB_SPI',
 SEC='1',
 CDS_LIB='mstr_discrete',
 CDS_PART_NAME='RES_0402-10.0K,1%,1/16W,EMPTY,A',
 PRIM_FILE='./archive_libs/mstr_discrete/res/chips/chips.prt';

PART_NAME
 R7F32 'RES_0402-10.0K,1%,1/16W,CHIP,GA':
 ROOM='SB_SPI',
 NO_XNET_CONNECTION='1';

SECTION_NUMBER 1
 '@BASEBOARD_FAB2_LIB.BASEBOARD_FAB2(SCH_1):PAGE153_I140@MSTR_DISCRETE.RES(CHIPS)':
 C_PATH='@baseboard_fab2_lib.baseboard_fab2(sch_1):page153_i140@mstr_discrete.re~
s(chips)',
 P_PATH='@baseboard_fab2_lib.baseboard_fab2(sch_1):page153_i140@mstr_discrete.re~
s(chips)',
 PATH='I140',
 DRAWING='@BASEBOARD_FAB2_LIB.BASEBOARD_FAB2(SCH_1):PAGE153',
 WATTAGE='1/16W',
 TOLERANCE='1%',
 SEC_TYPE='0402',
 MATERIAL='CHIP',
 BOM_COST='MIO_BIOS_MEM',
 NO_XNET_CONNECTION='1',
 PHYS_PAGE='153',
 XY='(-1450,4425)',
 ROT='0',
 VER='1',
 VALUE='10.0K',
 PACK_TYPE='0402',
 PART_NUMBER='G21796-016',
 LOCATION='R7F32',
 ROOM='SB_SPI',
 SEC='1',
 CDS_LIB='mstr_discrete',
 CDS_PART_NAME='RES_0402-10.0K,1%,1/16W,CHIP,GA',
 PRIM_FILE='./archive_libs/mstr_discrete/res/chips/chips.prt';

PART_NAME
 R7F33 'RES_0402-4.75K,1%,1/16W,CHIP,GA':
 ROOM='CPU_FANS';

SECTION_NUMBER 1
 '@BASEBOARD_FAB2_LIB.BASEBOARD_FAB2(SCH_1):PAGE161_I65@MSTR_DISCRETE.RES(CHIPS)':
 C_PATH='@baseboard_fab2_lib.baseboard_fab2(sch_1):page161_i65@mstr_discrete.res~
(chips)',
 P_PATH='@baseboard_fab2_lib.baseboard_fab2(sch_1):page161_i65@mstr_discrete.res~
(chips)',
 PATH='I65',
 DRAWING='@BASEBOARD_FAB2_LIB.BASEBOARD_FAB2(SCH_1):PAGE161',
 WATTAGE='1/16W',
 TOLERANCE='1%',
 SEC_TYPE='0402',
 MATERIAL='CHIP',
 BOM_COST='SM_THERM',
 PHYS_PAGE='161',
 XY='(-2325,1300)',
 ROT='2',
 VER='2',
 VALUE='4.75K',
 PACK_TYPE='0402',
 PART_NUMBER='G21796-072',
 LOCATION='R7F33',
 ROOM='CPU_FANS',
 SEC='1',
 CDS_LIB='mstr_discrete',
 CDS_PART_NAME='RES_0402-4.75K,1%,1/16W,CHIP,GA',
 PRIM_FILE='./archive_libs/mstr_discrete/res/chips/chips.prt';

PART_NAME
 R7F35 'RES_0402-0.0,5%,1/16W,CHIP,G21A':
 ROOM='PVPP_KLM_VR';

SECTION_NUMBER 1
 '@BASEBOARD_FAB2_LIB.BASEBOARD_FAB2(SCH_1):PAGE231_I170@MSTR_DISCRETE.RES(CHIPS)':
 C_PATH='@baseboard_fab2_lib.baseboard_fab2(sch_1):page231_i170@mstr_discrete.re~
s(chips)',
 P_PATH='@baseboard_fab2_lib.baseboard_fab2(sch_1):page231_i170@mstr_discrete.re~
s(chips)',
 PATH='I170',
 DRAWING='@BASEBOARD_FAB2_LIB.BASEBOARD_FAB2(SCH_1):PAGE231',
 WATTAGE='1/16W',
 TOLERANCE='5%',
 MATERIAL='CHIP',
 PHYS_PAGE='231',
 XY='(-950,725)',
 ROT='0',
 VER='1',
 VALUE='0.0',
 PACK_TYPE='0402',
 PART_NUMBER='G21497-005',
 LOCATION='R7F35',
 ROOM='PVPP_KLM_VR',
 CDS_LIB='mstr_discrete',
 CDS_PART_NAME='RES_0402-0.0,5%,1/16W,CHIP,G21A',
 PRIM_FILE='./archive_libs/mstr_discrete/res/chips/chips.prt';

PART_NAME
 R7F36 'RES_0402-2.26K,1.0%,1/16W,CHIPA':
 ROOM='SMBUS';

SECTION_NUMBER 1
 '@BASEBOARD_FAB2_LIB.BASEBOARD_FAB2(SCH_1):PAGE215_I75@MSTR_DISCRETE.RES(CHIPS)':
 C_PATH='@baseboard_fab2_lib.baseboard_fab2(sch_1):page215_i75@mstr_discrete.res~
(chips)',
 P_PATH='@baseboard_fab2_lib.baseboard_fab2(sch_1):page215_i75@mstr_discrete.res~
(chips)',
 PATH='I75',
 DRAWING='@BASEBOARD_FAB2_LIB.BASEBOARD_FAB2(SCH_1):PAGE215',
 SKU='B',
 WATTAGE='1/16W',
 TOLERANCE='1.0%',
 SEC_TYPE='0402',
 MATERIAL='CHIP',
 BOM_COST='SM_CONTROLLER',
 PHYS_PAGE='215',
 XY='(4300,2900)',
 ROT='0',
 VER='2',
 VALUE='2.26K',
 PACK_TYPE='0402',
 PART_NUMBER='G21796-311',
 LOCATION='R7F36',
 ROOM='SMBUS',
 SEC='1',
 CDS_LIB='mstr_discrete',
 CDS_PART_NAME='RES_0402-2.26K,1.0%,1/16W,CHIPA',
 PRIM_FILE='./archive_libs/mstr_discrete/res/chips/chips.prt';

PART_NAME
 R7F37 'RES_0402-33.2,1%,1/16W,CHIP,G2A':
 ROOM='SB_SPI';

SECTION_NUMBER 1
 '@BASEBOARD_FAB2_LIB.BASEBOARD_FAB2(SCH_1):PAGE153_I108@MSTR_DISCRETE.RES(CHIPS)':
 C_PATH='@baseboard_fab2_lib.baseboard_fab2(sch_1):page153_i108@mstr_discrete.re~
s(chips)',
 P_PATH='@baseboard_fab2_lib.baseboard_fab2(sch_1):page153_i108@mstr_discrete.re~
s(chips)',
 PATH='I108',
 DRAWING='@BASEBOARD_FAB2_LIB.BASEBOARD_FAB2(SCH_1):PAGE153',
 WATTAGE='1/16W',
 TOLERANCE='1%',
 SEC_TYPE='0402',
 MATERIAL='CHIP',
 BOM_COST='MIO_BIOS_MEM',
 PHYS_PAGE='153',
 XY='(-6500,3350)',
 ROT='0',
 VER='1',
 VALUE='33.2',
 PACK_TYPE='0402',
 PART_NUMBER='G21796-074',
 LOCATION='R7F37',
 ROOM='SB_SPI',
 SEC='1',
 CDS_LIB='mstr_discrete',
 CDS_PART_NAME='RES_0402-33.2,1%,1/16W,CHIP,G2A',
 PRIM_FILE='./archive_libs/mstr_discrete/res/chips/chips.prt';

PART_NAME
 R7G2 'RES_0402-0.0,5%,1/16W,CHIP,G21A':
 ROOM='VDDQ_ABC_PWR_VR';

SECTION_NUMBER 1
 '@BASEBOARD_FAB2_LIB.BASEBOARD_FAB2(SCH_1):PAGE215_I41@MSTR_DISCRETE.RES(CHIPS)':
 C_PATH='@baseboard_fab2_lib.baseboard_fab2(sch_1):page215_i41@mstr_discrete.res~
(chips)',
 P_PATH='@baseboard_fab2_lib.baseboard_fab2(sch_1):page215_i41@mstr_discrete.res~
(chips)',
 PATH='I41',
 DRAWING='@BASEBOARD_FAB2_LIB.BASEBOARD_FAB2(SCH_1):PAGE215',
 WATTAGE='1/16W',
 TOLERANCE='5%',
 SEC_TYPE='0402',
 MATERIAL='CHIP',
 PHYS_PAGE='215',
 XY='(3625,1500)',
 ROT='0',
 VER='1',
 VALUE='0.0',
 PACK_TYPE='0402',
 PART_NUMBER='G21497-005',
 LOCATION='R7G2',
 ROOM='VDDQ_ABC_PWR_VR',
 SEC='1',
 CDS_LIB='mstr_discrete',
 CDS_PART_NAME='RES_0402-0.0,5%,1/16W,CHIP,G21A',
 PRIM_FILE='./archive_libs/mstr_discrete/res/chips/chips.prt';

PART_NAME
 R7G4 'RES_0402-0.0,5%,1/16W,CHIP,G21A':
 ROOM='VDDQ_ABC_PWR_VR';

SECTION_NUMBER 1
 '@BASEBOARD_FAB2_LIB.BASEBOARD_FAB2(SCH_1):PAGE215_I49@MSTR_DISCRETE.RES(CHIPS)':
 C_PATH='@baseboard_fab2_lib.baseboard_fab2(sch_1):page215_i49@mstr_discrete.res~
(chips)',
 P_PATH='@baseboard_fab2_lib.baseboard_fab2(sch_1):page215_i49@mstr_discrete.res~
(chips)',
 PATH='I49',
 DRAWING='@BASEBOARD_FAB2_LIB.BASEBOARD_FAB2(SCH_1):PAGE215',
 WATTAGE='1/16W',
 TOLERANCE='5%',
 SEC_TYPE='0402',
 MATERIAL='CHIP',
 PHYS_PAGE='215',
 XY='(3475,2200)',
 ROT='0',
 VER='1',
 VALUE='0.0',
 PACK_TYPE='0402',
 PART_NUMBER='G21497-005',
 LOCATION='R7G4',
 ROOM='VDDQ_ABC_PWR_VR',
 SEC='1',
 CDS_LIB='mstr_discrete',
 CDS_PART_NAME='RES_0402-0.0,5%,1/16W,CHIP,G21A',
 PRIM_FILE='./archive_libs/mstr_discrete/res/chips/chips.prt';

PART_NAME
 R7G7 'RES_0402-4.75K,1%,1/16W,CHIP,GA':
 ROOM='PROC_SIDEBAND';

SECTION_NUMBER 1
 '@BASEBOARD_FAB2_LIB.BASEBOARD_FAB2(SCH_1):PAGE94_I51@MSTR_DISCRETE.RES(CHIPS)':
 C_PATH='@baseboard_fab2_lib.baseboard_fab2(sch_1):page94_i51@mstr_discrete.res(~
chips)',
 P_PATH='@baseboard_fab2_lib.baseboard_fab2(sch_1):page94_i51@mstr_discrete.res(~
chips)',
 PATH='I51',
 DRAWING='@BASEBOARD_FAB2_LIB.BASEBOARD_FAB2(SCH_1):PAGE94',
 WATTAGE='1/16W',
 TOLERANCE='1%',
 MATERIAL='CHIP',
 BOM_COST='PROC_SIDEBAND',
 PHYS_PAGE='94',
 XY='(-2150,2375)',
 ROT='2',
 VER='2',
 VALUE='4.75K',
 PACK_TYPE='0402',
 PART_NUMBER='G21796-072',
 LOCATION='R7G7',
 ROOM='PROC_SIDEBAND',
 CDS_LIB='mstr_discrete',
 CDS_PART_NAME='RES_0402-4.75K,1%,1/16W,CHIP,GA',
 PRIM_FILE='./archive_libs/mstr_discrete/res/chips/chips.prt';

PART_NAME
 R7G8 'RES_0402-2.26K,1.0%,1/16W,CHIPA':
 ROOM='SMBUS';

SECTION_NUMBER 1
 '@BASEBOARD_FAB2_LIB.BASEBOARD_FAB2(SCH_1):PAGE215_I72@MSTR_DISCRETE.RES(CHIPS)':
 C_PATH='@baseboard_fab2_lib.baseboard_fab2(sch_1):page215_i72@mstr_discrete.res~
(chips)',
 P_PATH='@baseboard_fab2_lib.baseboard_fab2(sch_1):page215_i72@mstr_discrete.res~
(chips)',
 PATH='I72',
 DRAWING='@BASEBOARD_FAB2_LIB.BASEBOARD_FAB2(SCH_1):PAGE215',
 POP='NOPOP',
 SKU='B',
 WATTAGE='1/16W',
 TOLERANCE='1.0%',
 SEC_TYPE='0402',
 MATERIAL='CHIP',
 BOM_COST='SM_CONTROLLER',
 PHYS_PAGE='215',
 XY='(1050,-50)',
 ROT='0',
 VER='2',
 VALUE='2.26K',
 PACK_TYPE='0402',
 PART_NUMBER='G21796-311',
 LOCATION='R7G8',
 ROOM='SMBUS',
 SEC='1',
 CDS_LIB='mstr_discrete',
 CDS_PART_NAME='RES_0402-2.26K,1.0%,1/16W,CHIPA',
 PRIM_FILE='./archive_libs/mstr_discrete/res/chips/chips.prt';

PART_NAME
 R7G9 'RES_0402-10.0,1%,1/16W,CHIP,G2A':
 ROOM='VDDQ_ABC_PWR_VR',
 NO_XNET_CONNECTION='1';

SECTION_NUMBER 1
 '@BASEBOARD_FAB2_LIB.BASEBOARD_FAB2(SCH_1):PAGE215_I12@MSTR_DISCRETE.RES(CHIPS)':
 C_PATH='@baseboard_fab2_lib.baseboard_fab2(sch_1):page215_i12@mstr_discrete.res~
(chips)',
 P_PATH='@baseboard_fab2_lib.baseboard_fab2(sch_1):page215_i12@mstr_discrete.res~
(chips)',
 PATH='I12',
 DRAWING='@BASEBOARD_FAB2_LIB.BASEBOARD_FAB2(SCH_1):PAGE215',
 WATTAGE='1/16W',
 TOLERANCE='1%',
 SEC_TYPE='0402',
 MATERIAL='CHIP',
 NO_XNET_CONNECTION='1',
 PHYS_PAGE='215',
 XY='(-575,1025)',
 ROT='0',
 VER='1',
 VALUE='10.0',
 PACK_TYPE='0402',
 PART_NUMBER='G21796-066',
 LOCATION='R7G9',
 ROOM='VDDQ_ABC_PWR_VR',
 SEC='1',
 CDS_LIB='mstr_discrete',
 CDS_PART_NAME='RES_0402-10.0,1%,1/16W,CHIP,G2A',
 PRIM_FILE='./archive_libs/mstr_discrete/res/chips/chips.prt';

PART_NAME
 R7G10 'RES_0402-2.26K,1.0%,1/16W,CHIPA':
 ROOM='SMBUS';

SECTION_NUMBER 1
 '@BASEBOARD_FAB2_LIB.BASEBOARD_FAB2(SCH_1):PAGE215_I73@MSTR_DISCRETE.RES(CHIPS)':
 C_PATH='@baseboard_fab2_lib.baseboard_fab2(sch_1):page215_i73@mstr_discrete.res~
(chips)',
 P_PATH='@baseboard_fab2_lib.baseboard_fab2(sch_1):page215_i73@mstr_discrete.res~
(chips)',
 PATH='I73',
 DRAWING='@BASEBOARD_FAB2_LIB.BASEBOARD_FAB2(SCH_1):PAGE215',
 SKU='B',
 WATTAGE='1/16W',
 TOLERANCE='1.0%',
 SEC_TYPE='0402',
 MATERIAL='CHIP',
 BOM_COST='SM_CONTROLLER',
 PHYS_PAGE='215',
 XY='(1400,-50)',
 ROT='0',
 VER='2',
 VALUE='2.26K',
 PACK_TYPE='0402',
 PART_NUMBER='G21796-311',
 LOCATION='R7G10',
 ROOM='SMBUS',
 SEC='1',
 CDS_LIB='mstr_discrete',
 CDS_PART_NAME='RES_0402-2.26K,1.0%,1/16W,CHIPA',
 PRIM_FILE='./archive_libs/mstr_discrete/res/chips/chips.prt';

PART_NAME
 R7G14 'RES_0402-0.0,5%,1/16W,CHIP,G21A':
 ROOM='BMC_DEBUG_HEADER';

SECTION_NUMBER 1
 '@BASEBOARD_FAB2_LIB.BASEBOARD_FAB2(SCH_1):PAGE189_I38@MSTR_DISCRETE.RES(CHIPS)':
 C_PATH='@baseboard_fab2_lib.baseboard_fab2(sch_1):page189_i38@mstr_discrete.res~
(chips)',
 P_PATH='@baseboard_fab2_lib.baseboard_fab2(sch_1):page189_i38@mstr_discrete.res~
(chips)',
 PATH='I38',
 DRAWING='@BASEBOARD_FAB2_LIB.BASEBOARD_FAB2(SCH_1):PAGE189',
 WATTAGE='1/16W',
 TOLERANCE='5%',
 SEC_TYPE='0402',
 MATERIAL='CHIP',
 BOM_COST='DEBUG',
 PHYS_PAGE='189',
 XY='(-125,4050)',
 ROT='0',
 VER='1',
 VALUE='0.0',
 PACK_TYPE='0402',
 PART_NUMBER='G21497-005',
 LOCATION='R7G14',
 ROOM='BMC_DEBUG_HEADER',
 SEC='1',
 CDS_LIB='mstr_discrete',
 CDS_PART_NAME='RES_0402-0.0,5%,1/16W,CHIP,G21A',
 PRIM_FILE='./archive_libs/mstr_discrete/res/chips/chips.prt';

PART_NAME
 R7G15 'RES_0402-0.0,5%,1/16W,EMPTY,G2A':
 ROOM='BMC_DEBUG_HEADER';

SECTION_NUMBER 1
 '@BASEBOARD_FAB2_LIB.BASEBOARD_FAB2(SCH_1):PAGE189_I36@MSTR_DISCRETE.RES(CHIPS)':
 C_PATH='@baseboard_fab2_lib.baseboard_fab2(sch_1):page189_i36@mstr_discrete.res~
(chips)',
 P_PATH='@baseboard_fab2_lib.baseboard_fab2(sch_1):page189_i36@mstr_discrete.res~
(chips)',
 PATH='I36',
 DRAWING='@BASEBOARD_FAB2_LIB.BASEBOARD_FAB2(SCH_1):PAGE189',
 WATTAGE='1/16W',
 TOLERANCE='5%',
 SEC_TYPE='0402',
 MATERIAL='EMPTY',
 BOM_COST='DEBUG',
 PHYS_PAGE='189',
 XY='(-2100,2075)',
 ROT='0',
 VER='1',
 VALUE='0.0',
 PACK_TYPE='0402',
 PART_NUMBER='G21497-005',
 LOCATION='R7G15',
 ROOM='BMC_DEBUG_HEADER',
 SEC='1',
 CDS_LIB='mstr_discrete',
 CDS_PART_NAME='RES_0402-0.0,5%,1/16W,EMPTY,G2A',
 PRIM_FILE='./archive_libs/mstr_discrete/res/chips/chips.prt';

PART_NAME
 R7G16 'RES_0402-0.0,5%,1/16W,EMPTY,G2A':
 ROOM='BMC_DEBUG_HEADER';

SECTION_NUMBER 1
 '@BASEBOARD_FAB2_LIB.BASEBOARD_FAB2(SCH_1):PAGE189_I27@MSTR_DISCRETE.RES(CHIPS)':
 C_PATH='@baseboard_fab2_lib.baseboard_fab2(sch_1):page189_i27@mstr_discrete.res~
(chips)',
 P_PATH='@baseboard_fab2_lib.baseboard_fab2(sch_1):page189_i27@mstr_discrete.res~
(chips)',
 PATH='I27',
 DRAWING='@BASEBOARD_FAB2_LIB.BASEBOARD_FAB2(SCH_1):PAGE189',
 WATTAGE='1/16W',
 TOLERANCE='5%',
 SEC_TYPE='0402',
 MATERIAL='EMPTY',
 BOM_COST='DEBUG',
 PHYS_PAGE='189',
 XY='(-2100,2250)',
 ROT='0',
 VER='1',
 VALUE='0.0',
 PACK_TYPE='0402',
 PART_NUMBER='G21497-005',
 LOCATION='R7G16',
 ROOM='BMC_DEBUG_HEADER',
 SEC='1',
 CDS_LIB='mstr_discrete',
 CDS_PART_NAME='RES_0402-0.0,5%,1/16W,EMPTY,G2A',
 PRIM_FILE='./archive_libs/mstr_discrete/res/chips/chips.prt';

PART_NAME
 R7G17 'RES_0402-0.0,5%,1/16W,CHIP,G21A':
 ROOM='BMC_DEBUG_HEADER';

SECTION_NUMBER 1
 '@BASEBOARD_FAB2_LIB.BASEBOARD_FAB2(SCH_1):PAGE189_I37@MSTR_DISCRETE.RES(CHIPS)':
 C_PATH='@baseboard_fab2_lib.baseboard_fab2(sch_1):page189_i37@mstr_discrete.res~
(chips)',
 P_PATH='@baseboard_fab2_lib.baseboard_fab2(sch_1):page189_i37@mstr_discrete.res~
(chips)',
 PATH='I37',
 DRAWING='@BASEBOARD_FAB2_LIB.BASEBOARD_FAB2(SCH_1):PAGE189',
 WATTAGE='1/16W',
 TOLERANCE='5%',
 SEC_TYPE='0402',
 MATERIAL='CHIP',
 BOM_COST='DEBUG',
 PHYS_PAGE='189',
 XY='(-2100,1900)',
 ROT='0',
 VER='1',
 VALUE='0.0',
 PACK_TYPE='0402',
 PART_NUMBER='G21497-005',
 LOCATION='R7G17',
 ROOM='BMC_DEBUG_HEADER',
 SEC='1',
 CDS_LIB='mstr_discrete',
 CDS_PART_NAME='RES_0402-0.0,5%,1/16W,CHIP,G21A',
 PRIM_FILE='./archive_libs/mstr_discrete/res/chips/chips.prt';

PART_NAME
 R7G18 'RES_0402-0.0,5%,1/16W,EMPTY,G2A':
 ROOM='BMC_DEBUG_HEADER';

SECTION_NUMBER 1
 '@BASEBOARD_FAB2_LIB.BASEBOARD_FAB2(SCH_1):PAGE189_I13@MSTR_DISCRETE.RES(CHIPS)':
 C_PATH='@baseboard_fab2_lib.baseboard_fab2(sch_1):page189_i13@mstr_discrete.res~
(chips)',
 P_PATH='@baseboard_fab2_lib.baseboard_fab2(sch_1):page189_i13@mstr_discrete.res~
(chips)',
 PATH='I13',
 DRAWING='@BASEBOARD_FAB2_LIB.BASEBOARD_FAB2(SCH_1):PAGE189',
 WATTAGE='1/16W',
 TOLERANCE='5%',
 SEC_TYPE='0402',
 MATERIAL='EMPTY',
 BOM_COST='DEBUG',
 PHYS_PAGE='189',
 XY='(-2100,4225)',
 ROT='0',
 VER='1',
 VALUE='0.0',
 PACK_TYPE='0402',
 PART_NUMBER='G21497-005',
 LOCATION='R7G18',
 ROOM='BMC_DEBUG_HEADER',
 SEC='1',
 CDS_LIB='mstr_discrete',
 CDS_PART_NAME='RES_0402-0.0,5%,1/16W,EMPTY,G2A',
 PRIM_FILE='./archive_libs/mstr_discrete/res/chips/chips.prt';

PART_NAME
 R7G19 'RES_0402-0.0,5%,1/16W,EMPTY,G2A':
 ROOM='BMC_DEBUG_HEADER';

SECTION_NUMBER 1
 '@BASEBOARD_FAB2_LIB.BASEBOARD_FAB2(SCH_1):PAGE189_I8@MSTR_DISCRETE.RES(CHIPS)':
 C_PATH='@baseboard_fab2_lib.baseboard_fab2(sch_1):page189_i8@mstr_discrete.res(~
chips)',
 P_PATH='@baseboard_fab2_lib.baseboard_fab2(sch_1):page189_i8@mstr_discrete.res(~
chips)',
 PATH='I8',
 DRAWING='@BASEBOARD_FAB2_LIB.BASEBOARD_FAB2(SCH_1):PAGE189',
 WATTAGE='1/16W',
 TOLERANCE='5%',
 SEC_TYPE='0402',
 MATERIAL='EMPTY',
 BOM_COST='DEBUG',
 PHYS_PAGE='189',
 XY='(-2100,4400)',
 ROT='0',
 VER='1',
 VALUE='0.0',
 PACK_TYPE='0402',
 PART_NUMBER='G21497-005',
 LOCATION='R7G19',
 ROOM='BMC_DEBUG_HEADER',
 SEC='1',
 CDS_LIB='mstr_discrete',
 CDS_PART_NAME='RES_0402-0.0,5%,1/16W,EMPTY,G2A',
 PRIM_FILE='./archive_libs/mstr_discrete/res/chips/chips.prt';

PART_NAME
 R7G21 'RES_0402-0.0,5%,1/16W,CHIP,G21A':
 ROOM='BMC_DEBUG_HEADER';

SECTION_NUMBER 1
 '@BASEBOARD_FAB2_LIB.BASEBOARD_FAB2(SCH_1):PAGE189_I63@MSTR_DISCRETE.RES(CHIPS)':
 C_PATH='@baseboard_fab2_lib.baseboard_fab2(sch_1):page189_i63@mstr_discrete.res~
(chips)',
 P_PATH='@baseboard_fab2_lib.baseboard_fab2(sch_1):page189_i63@mstr_discrete.res~
(chips)',
 PATH='I63',
 DRAWING='@BASEBOARD_FAB2_LIB.BASEBOARD_FAB2(SCH_1):PAGE189',
 WATTAGE='1/16W',
 TOLERANCE='5%',
 SEC_TYPE='0402',
 MATERIAL='CHIP',
 BOM_COST='DEBUG',
 PHYS_PAGE='189',
 XY='(2050,3225)',
 ROT='0',
 VER='1',
 VALUE='0.0',
 PACK_TYPE='0402',
 PART_NUMBER='G21497-005',
 LOCATION='R7G21',
 ROOM='BMC_DEBUG_HEADER',
 SEC='1',
 CDS_LIB='mstr_discrete',
 CDS_PART_NAME='RES_0402-0.0,5%,1/16W,CHIP,G21A',
 PRIM_FILE='./archive_libs/mstr_discrete/res/chips/chips.prt';

PART_NAME
 R7G22 'RES_0402-10.0K,1%,1/16W,CHIP,GA':
 ROOM='BMC_DEBUG_HEADER';

SECTION_NUMBER 1
 '@BASEBOARD_FAB2_LIB.BASEBOARD_FAB2(SCH_1):PAGE189_I53@MSTR_DISCRETE.RES(CHIPS)':
 C_PATH='@baseboard_fab2_lib.baseboard_fab2(sch_1):page189_i53@mstr_discrete.res~
(chips)',
 P_PATH='@baseboard_fab2_lib.baseboard_fab2(sch_1):page189_i53@mstr_discrete.res~
(chips)',
 PATH='I53',
 DRAWING='@BASEBOARD_FAB2_LIB.BASEBOARD_FAB2(SCH_1):PAGE189',
 WATTAGE='1/16W',
 TOLERANCE='1%',
 MATERIAL='CHIP',
 PHYS_PAGE='189',
 XY='(2600,3500)',
 ROT='0',
 VER='2',
 VALUE='10.0K',
 PACK_TYPE='0402',
 PART_NUMBER='G21796-016',
 LOCATION='R7G22',
 ROOM='BMC_DEBUG_HEADER',
 CDS_LIB='mstr_discrete',
 CDS_PART_NAME='RES_0402-10.0K,1%,1/16W,CHIP,GA',
 PRIM_FILE='./archive_libs/mstr_discrete/res/chips/chips.prt';

PART_NAME
 R7G23 'RES_0402-10.0K,1%,1/16W,CHIP,GA':
 ROOM='BMC_DEBUG_HEADER';

SECTION_NUMBER 1
 '@BASEBOARD_FAB2_LIB.BASEBOARD_FAB2(SCH_1):PAGE189_I51@MSTR_DISCRETE.RES(CHIPS)':
 C_PATH='@baseboard_fab2_lib.baseboard_fab2(sch_1):page189_i51@mstr_discrete.res~
(chips)',
 P_PATH='@baseboard_fab2_lib.baseboard_fab2(sch_1):page189_i51@mstr_discrete.res~
(chips)',
 PATH='I51',
 DRAWING='@BASEBOARD_FAB2_LIB.BASEBOARD_FAB2(SCH_1):PAGE189',
 WATTAGE='1/16W',
 TOLERANCE='1%',
 MATERIAL='CHIP',
 PHYS_PAGE='189',
 XY='(2900,3500)',
 ROT='0',
 VER='2',
 VALUE='10.0K',
 PACK_TYPE='0402',
 PART_NUMBER='G21796-016',
 LOCATION='R7G23',
 ROOM='BMC_DEBUG_HEADER',
 CDS_LIB='mstr_discrete',
 CDS_PART_NAME='RES_0402-10.0K,1%,1/16W,CHIP,GA',
 PRIM_FILE='./archive_libs/mstr_discrete/res/chips/chips.prt';

PART_NAME
 R7G24 'RES_0402-150.0,1%,1/16W,CHIP,GA':
 ROOM='VDDQ_ABC_PWR_VR';

SECTION_NUMBER 1
 '@BASEBOARD_FAB2_LIB.BASEBOARD_FAB2(SCH_1):PAGE215_I28@MSTR_DISCRETE.RES(CHIPS)':
 C_PATH='@baseboard_fab2_lib.baseboard_fab2(sch_1):page215_i28@mstr_discrete.res~
(chips)',
 P_PATH='@baseboard_fab2_lib.baseboard_fab2(sch_1):page215_i28@mstr_discrete.res~
(chips)',
 PATH='I28',
 DRAWING='@BASEBOARD_FAB2_LIB.BASEBOARD_FAB2(SCH_1):PAGE215',
 WATTAGE='1/16W',
 TOLERANCE='1%',
 SEC_TYPE='0402',
 MATERIAL='CHIP',
 PHYS_PAGE='215',
 XY='(675,2800)',
 ROT='0',
 VER='1',
 VALUE='150.0',
 PACK_TYPE='0402',
 PART_NUMBER='G21796-009',
 LOCATION='R7G24',
 ROOM='VDDQ_ABC_PWR_VR',
 SEC='1',
 CDS_LIB='mstr_discrete',
 CDS_PART_NAME='RES_0402-150.0,1%,1/16W,CHIP,GA',
 PRIM_FILE='./archive_libs/mstr_discrete/res/chips/chips.prt';

PART_NAME
 R7G25 'RES_0402-68.1K,1%,1/16W,EMPTY,A':;

SECTION_NUMBER 1
 '@BASEBOARD_FAB2_LIB.BASEBOARD_FAB2(SCH_1):PAGE216_I104@MSTR_DISCRETE.RES(CHIPS)':
 C_PATH='@baseboard_fab2_lib.baseboard_fab2(sch_1):page216_i104@mstr_discrete.re~
s(chips)',
 P_PATH='@baseboard_fab2_lib.baseboard_fab2(sch_1):page216_i104@mstr_discrete.re~
s(chips)',
 PATH='I104',
 DRAWING='@BASEBOARD_FAB2_LIB.BASEBOARD_FAB2(SCH_1):PAGE216',
 WATTAGE='1/16W',
 TOLERANCE='1%',
 SEC_TYPE='0402',
 MATERIAL='EMPTY',
 PHYS_PAGE='216',
 XY='(4575,2450)',
 ROT='0',
 VER='2',
 VALUE='68.1K',
 PACK_TYPE='0402',
 PART_NUMBER='G21796-187',
 LOCATION='R7G25',
 SEC='1',
 CDS_LIB='mstr_discrete',
 CDS_PART_NAME='RES_0402-68.1K,1%,1/16W,EMPTY,A',
 PRIM_FILE='./archive_libs/mstr_discrete/res/chips/chips.prt';

PART_NAME
 R7G26 'RES_0402-10.0K,1%,1/16W,CHIP,GA':
 ROOM='SB';

SECTION_NUMBER 1
 '@BASEBOARD_FAB2_LIB.BASEBOARD_FAB2(SCH_1):PAGE136_I101@MSTR_DISCRETE.RES(CHIPS)':
 C_PATH='@baseboard_fab2_lib.baseboard_fab2(sch_1):page136_i101@mstr_discrete.re~
s(chips)',
 P_PATH='@baseboard_fab2_lib.baseboard_fab2(sch_1):page136_i101@mstr_discrete.re~
s(chips)',
 PATH='I101',
 DRAWING='@BASEBOARD_FAB2_LIB.BASEBOARD_FAB2(SCH_1):PAGE136',
 WATTAGE='1/16W',
 TOLERANCE='1%',
 SEC_TYPE='0402',
 MATERIAL='CHIP',
 PHYS_PAGE='136',
 XY='(-2250,4800)',
 ROT='0',
 VER='2',
 VALUE='10.0K',
 PACK_TYPE='0402',
 PART_NUMBER='G21796-016',
 LOCATION='R7G26',
 ROOM='SB',
 SEC='1',
 CDS_LIB='mstr_discrete',
 CDS_PART_NAME='RES_0402-10.0K,1%,1/16W,CHIP,GA',
 PRIM_FILE='./archive_libs/mstr_discrete/res/chips/chips.prt';

PART_NAME
 R7G27 'RES_0402-1.00K,1%,1/16W,CHIP,GA':
 ROOM='SB';

SECTION_NUMBER 1
 '@BASEBOARD_FAB2_LIB.BASEBOARD_FAB2(SCH_1):PAGE136_I155@MSTR_DISCRETE.RES(CHIPS)':
 C_PATH='@baseboard_fab2_lib.baseboard_fab2(sch_1):page136_i155@mstr_discrete.re~
s(chips)',
 P_PATH='@baseboard_fab2_lib.baseboard_fab2(sch_1):page136_i155@mstr_discrete.re~
s(chips)',
 PATH='I155',
 DRAWING='@BASEBOARD_FAB2_LIB.BASEBOARD_FAB2(SCH_1):PAGE136',
 WATTAGE='1/16W',
 TOLERANCE='1%',
 SEC_TYPE='0402',
 MATERIAL='CHIP',
 BOM_COST='SB',
 PHYS_PAGE='136',
 XY='(-600,4800)',
 ROT='2',
 VER='2',
 VALUE='1.00K',
 PACK_TYPE='0402',
 PART_NUMBER='G21796-026',
 LOCATION='R7G27',
 ROOM='SB',
 SEC='1',
 CDS_LIB='mstr_discrete',
 CDS_PART_NAME='RES_0402-1.00K,1%,1/16W,CHIP,GA',
 PRIM_FILE='./archive_libs/mstr_discrete/res/chips/chips.prt';

PART_NAME
 R7G28 'RES_0402-1.00K,1%,1/16W,CHIP,GA':
 ROOM='SB';

SECTION_NUMBER 1
 '@BASEBOARD_FAB2_LIB.BASEBOARD_FAB2(SCH_1):PAGE136_I102@MSTR_DISCRETE.RES(CHIPS)':
 C_PATH='@baseboard_fab2_lib.baseboard_fab2(sch_1):page136_i102@mstr_discrete.re~
s(chips)',
 P_PATH='@baseboard_fab2_lib.baseboard_fab2(sch_1):page136_i102@mstr_discrete.re~
s(chips)',
 PATH='I102',
 DRAWING='@BASEBOARD_FAB2_LIB.BASEBOARD_FAB2(SCH_1):PAGE136',
 WATTAGE='1/16W',
 TOLERANCE='1%',
 SEC_TYPE='0402',
 MATERIAL='CHIP',
 BOM_COST='SB',
 PHYS_PAGE='136',
 XY='(-2450,3825)',
 ROT='0',
 VER='2',
 VALUE='1.00K',
 PACK_TYPE='0402',
 PART_NUMBER='G21796-026',
 LOCATION='R7G28',
 ROOM='SB',
 SEC='1',
 CDS_LIB='mstr_discrete',
 CDS_PART_NAME='RES_0402-1.00K,1%,1/16W,CHIP,GA',
 PRIM_FILE='./archive_libs/mstr_discrete/res/chips/chips.prt';

PART_NAME
 R7G29 'RES_0402-1.00K,1%,1/16W,CHIP,GA':
 ROOM='SB';

SECTION_NUMBER 1
 '@BASEBOARD_FAB2_LIB.BASEBOARD_FAB2(SCH_1):PAGE136_I148@MSTR_DISCRETE.RES(CHIPS)':
 C_PATH='@baseboard_fab2_lib.baseboard_fab2(sch_1):page136_i148@mstr_discrete.re~
s(chips)',
 P_PATH='@baseboard_fab2_lib.baseboard_fab2(sch_1):page136_i148@mstr_discrete.re~
s(chips)',
 PATH='I148',
 DRAWING='@BASEBOARD_FAB2_LIB.BASEBOARD_FAB2(SCH_1):PAGE136',
 WATTAGE='1/16W',
 TOLERANCE='1%',
 SEC_TYPE='0402',
 MATERIAL='CHIP',
 BOM_COST='SB',
 PHYS_PAGE='136',
 XY='(-3100,3850)',
 ROT='0',
 VER='2',
 VALUE='1.00K',
 PACK_TYPE='0402',
 PART_NUMBER='G21796-026',
 LOCATION='R7G29',
 ROOM='SB',
 SEC='1',
 CDS_LIB='mstr_discrete',
 CDS_PART_NAME='RES_0402-1.00K,1%,1/16W,CHIP,GA',
 PRIM_FILE='./archive_libs/mstr_discrete/res/chips/chips.prt';

PART_NAME
 R7G30 'RES_0402-68.1K,1%,1/16W,EMPTY,A':;

SECTION_NUMBER 1
 '@BASEBOARD_FAB2_LIB.BASEBOARD_FAB2(SCH_1):PAGE216_I106@MSTR_DISCRETE.RES(CHIPS)':
 C_PATH='@baseboard_fab2_lib.baseboard_fab2(sch_1):page216_i106@mstr_discrete.re~
s(chips)',
 P_PATH='@baseboard_fab2_lib.baseboard_fab2(sch_1):page216_i106@mstr_discrete.re~
s(chips)',
 PATH='I106',
 DRAWING='@BASEBOARD_FAB2_LIB.BASEBOARD_FAB2(SCH_1):PAGE216',
 BOM_SS='NOPOP',
 WATTAGE='1/16W',
 TOLERANCE='1%',
 SEC_TYPE='0402',
 MATERIAL='EMPTY',
 PHYS_PAGE='216',
 XY='(4675,50)',
 ROT='0',
 VER='2',
 VALUE='68.1K',
 PACK_TYPE='0402',
 PART_NUMBER='G21796-187',
 LOCATION='R7G30',
 SEC='1',
 CDS_LIB='mstr_discrete',
 CDS_PART_NAME='RES_0402-68.1K,1%,1/16W,EMPTY,A',
 PRIM_FILE='./archive_libs/mstr_discrete/res/chips/chips.prt';

PART_NAME
 R7G31 'RES_0402-1.00K,1%,1/16W,CHIP,GA':
 ROOM='SB';

SECTION_NUMBER 1
 '@BASEBOARD_FAB2_LIB.BASEBOARD_FAB2(SCH_1):PAGE136_I139@MSTR_DISCRETE.RES(CHIPS)':
 C_PATH='@baseboard_fab2_lib.baseboard_fab2(sch_1):page136_i139@mstr_discrete.re~
s(chips)',
 P_PATH='@baseboard_fab2_lib.baseboard_fab2(sch_1):page136_i139@mstr_discrete.re~
s(chips)',
 PATH='I139',
 DRAWING='@BASEBOARD_FAB2_LIB.BASEBOARD_FAB2(SCH_1):PAGE136',
 WATTAGE='1/16W',
 TOLERANCE='1%',
 SEC_TYPE='0402',
 MATERIAL='CHIP',
 BOM_COST='SB',
 PHYS_PAGE='136',
 XY='(-400,4800)',
 ROT='0',
 VER='2',
 VALUE='1.00K',
 PACK_TYPE='0402',
 PART_NUMBER='G21796-026',
 LOCATION='R7G31',
 ROOM='SB',
 SEC='1',
 CDS_LIB='mstr_discrete',
 CDS_PART_NAME='RES_0402-1.00K,1%,1/16W,CHIP,GA',
 PRIM_FILE='./archive_libs/mstr_discrete/res/chips/chips.prt';

PART_NAME
 R7G114 'RES_0402-0.0,5%,1/16W,CHIP,G21A':
 ROOM='BMC_DEBUG_HEADER';

SECTION_NUMBER 1
 '@BASEBOARD_FAB2_LIB.BASEBOARD_FAB2(SCH_1):PAGE189_I76@MSTR_DISCRETE.RES(CHIPS)':
 C_PATH='@baseboard_fab2_lib.baseboard_fab2(sch_1):page189_i76@mstr_discrete.res~
(chips)',
 P_PATH='@baseboard_fab2_lib.baseboard_fab2(sch_1):page189_i76@mstr_discrete.res~
(chips)',
 PATH='I76',
 DRAWING='@BASEBOARD_FAB2_LIB.BASEBOARD_FAB2(SCH_1):PAGE189',
 WATTAGE='1/16W',
 TOLERANCE='5%',
 MATERIAL='CHIP',
 BOM_COST='DEBUG',
 PHYS_PAGE='189',
 XY='(-100,3800)',
 ROT='0',
 VER='1',
 VALUE='0.0',
 PACK_TYPE='0402',
 PART_NUMBER='G21497-005',
 LOCATION='R7G114',
 ROOM='BMC_DEBUG_HEADER',
 CDS_LIB='mstr_discrete',
 CDS_PART_NAME='RES_0402-0.0,5%,1/16W,CHIP,G21A',
 PRIM_FILE='./archive_libs/mstr_discrete/res/chips/chips.prt';

PART_NAME
 R7L2 'RES_0402-100.0,1%,1/16W,EMPTY,A':
 ROOM='VDDQ_KLM_PWR_VR';

SECTION_NUMBER 1
 '@BASEBOARD_FAB2_LIB.BASEBOARD_FAB2(SCH_1):PAGE228_I74@MSTR_DISCRETE.RES(CHIPS)':
 C_PATH='@baseboard_fab2_lib.baseboard_fab2(sch_1):page228_i74@mstr_discrete.res~
(chips)',
 P_PATH='@baseboard_fab2_lib.baseboard_fab2(sch_1):page228_i74@mstr_discrete.res~
(chips)',
 PATH='I74',
 DRAWING='@BASEBOARD_FAB2_LIB.BASEBOARD_FAB2(SCH_1):PAGE228',
 WATTAGE='1/16W',
 TOLERANCE='1%',
 SEC_TYPE='0402',
 MATERIAL='EMPTY',
 PHYS_PAGE='228',
 XY='(-375,1925)',
 ROT='0',
 VER='2',
 VALUE='100.0',
 PACK_TYPE='0402',
 PART_NUMBER='G21796-017',
 LOCATION='R7L2',
 ROOM='VDDQ_KLM_PWR_VR',
 SEC='1',
 CDS_LIB='mstr_discrete',
 CDS_PART_NAME='RES_0402-100.0,1%,1/16W,EMPTY,A',
 PRIM_FILE='./archive_libs/mstr_discrete/res/chips/chips.prt';

PART_NAME
 R7M1 'RES_0402-665,1.0%,1/16W,CHIP,GA':
 ROOM='MEM';

SECTION_NUMBER 1
 '@BASEBOARD_FAB2_LIB.BASEBOARD_FAB2(SCH_1):PAGE99_I109@MSTR_DISCRETE.RES(CHIPS)':
 C_PATH='@baseboard_fab2_lib.baseboard_fab2(sch_1):page99_i109@mstr_discrete.res~
(chips)',
 P_PATH='@baseboard_fab2_lib.baseboard_fab2(sch_1):page99_i109@mstr_discrete.res~
(chips)',
 PATH='I109',
 DRAWING='@BASEBOARD_FAB2_LIB.BASEBOARD_FAB2(SCH_1):PAGE99',
 WATTAGE='1/16W',
 TOLERANCE='1.0%',
 SEC_TYPE='0402',
 MATERIAL='CHIP',
 BOM_COST='SM_CONTROLLER',
 PHYS_PAGE='99',
 XY='(875,1250)',
 ROT='0',
 VER='2',
 VALUE='665',
 PACK_TYPE='0402',
 PART_NUMBER='G21796-235',
 LOCATION='R7M1',
 ROOM='MEM',
 SEC='1',
 CDS_LIB='mstr_discrete',
 CDS_PART_NAME='RES_0402-665,1.0%,1/16W,CHIP,GA',
 PRIM_FILE='./archive_libs/mstr_discrete/res/chips/chips.prt';

PART_NAME
 R7M2 'RES_0402-240,1.0%,1/16W,CHIP,GA':
 ROOM='MEM',
 SIGNAL_MODEL='DEFAULT_RESISTOR_750OHM_2_1';

SECTION_NUMBER 1
 '@BASEBOARD_FAB2_LIB.BASEBOARD_FAB2(SCH_1):PAGE99_I79@MSTR_DISCRETE.RES(CHIPS)':
 C_PATH='@baseboard_fab2_lib.baseboard_fab2(sch_1):page99_i79@mstr_discrete.res(~
chips)',
 P_PATH='@baseboard_fab2_lib.baseboard_fab2(sch_1):page99_i79@mstr_discrete.res(~
chips)',
 PATH='I79',
 DRAWING='@BASEBOARD_FAB2_LIB.BASEBOARD_FAB2(SCH_1):PAGE99',
 CD_SEC='1',
 WATTAGE='1/16W',
 TOLERANCE='1.0%',
 MATERIAL='CHIP',
 BOM_COST='SM_CONTROLLER',
 PHYS_PAGE='99',
 XY='(-1100,1250)',
 ROT='2',
 VER='2',
 VALUE='240',
 PACK_TYPE='0402',
 PART_NUMBER='G21796-294',
 LOCATION='R7M2',
 SIGNAL_MODEL='DEFAULT_RESISTOR_750OHM_2_1',
 ROOM='MEM',
 CDS_LIB='mstr_discrete',
 CDS_PART_NAME='RES_0402-240,1.0%,1/16W,CHIP,GA',
 PRIM_FILE='./archive_libs/mstr_discrete/res/chips/chips.prt';

PART_NAME
 R7M3 'RES_0402-10.0,1%,1/16W,CHIP,G2A':
 ROOM='MEM';

SECTION_NUMBER 1
 '@BASEBOARD_FAB2_LIB.BASEBOARD_FAB2(SCH_1):PAGE99_I98@MSTR_DISCRETE.RES(CHIPS)':
 C_PATH='@baseboard_fab2_lib.baseboard_fab2(sch_1):page99_i98@mstr_discrete.res(~
chips)',
 P_PATH='@baseboard_fab2_lib.baseboard_fab2(sch_1):page99_i98@mstr_discrete.res(~
chips)',
 PATH='I98',
 DRAWING='@BASEBOARD_FAB2_LIB.BASEBOARD_FAB2(SCH_1):PAGE99',
 WATTAGE='1/16W',
 TOLERANCE='1%',
 MATERIAL='CHIP',
 BOM_COST='SM_CONTROLLER',
 PHYS_PAGE='99',
 XY='(-1575,950)',
 ROT='0',
 VER='1',
 VALUE='10.0',
 PACK_TYPE='0402',
 PART_NUMBER='G21796-066',
 LOCATION='R7M3',
 ROOM='MEM',
 CDS_LIB='mstr_discrete',
 CDS_PART_NAME='RES_0402-10.0,1%,1/16W,CHIP,G2A',
 PRIM_FILE='./archive_libs/mstr_discrete/res/chips/chips.prt';

PART_NAME
 R7M4 'RES_0402-20.0,1%,1/16W,CHIP,G2A':
 ROOM='MEM';

SECTION_NUMBER 1
 '@BASEBOARD_FAB2_LIB.BASEBOARD_FAB2(SCH_1):PAGE99_I56@MSTR_DISCRETE.RES(CHIPS)':
 C_PATH='@baseboard_fab2_lib.baseboard_fab2(sch_1):page99_i56@mstr_discrete.res(~
chips)',
 P_PATH='@baseboard_fab2_lib.baseboard_fab2(sch_1):page99_i56@mstr_discrete.res(~
chips)',
 PATH='I56',
 DRAWING='@BASEBOARD_FAB2_LIB.BASEBOARD_FAB2(SCH_1):PAGE99',
 WATTAGE='1/16W',
 TOLERANCE='1%',
 MATERIAL='CHIP',
 PHYS_PAGE='99',
 XY='(1600,950)',
 ROT='0',
 VER='1',
 VALUE='20.0',
 PACK_TYPE='0402',
 PART_NUMBER='G21796-173',
 LOCATION='R7M4',
 ROOM='MEM',
 CDS_LIB='mstr_discrete',
 CDS_PART_NAME='RES_0402-20.0,1%,1/16W,CHIP,G2A',
 PRIM_FILE='./archive_libs/mstr_discrete/res/chips/chips.prt';

PART_NAME
 R7M5 'RES_0402-20.0,1%,1/16W,CHIP,G2A':
 ROOM='MEM';

SECTION_NUMBER 1
 '@BASEBOARD_FAB2_LIB.BASEBOARD_FAB2(SCH_1):PAGE99_I55@MSTR_DISCRETE.RES(CHIPS)':
 C_PATH='@baseboard_fab2_lib.baseboard_fab2(sch_1):page99_i55@mstr_discrete.res(~
chips)',
 P_PATH='@baseboard_fab2_lib.baseboard_fab2(sch_1):page99_i55@mstr_discrete.res(~
chips)',
 PATH='I55',
 DRAWING='@BASEBOARD_FAB2_LIB.BASEBOARD_FAB2(SCH_1):PAGE99',
 WATTAGE='1/16W',
 TOLERANCE='1%',
 MATERIAL='CHIP',
 PHYS_PAGE='99',
 XY='(1600,900)',
 ROT='0',
 VER='1',
 VALUE='20.0',
 PACK_TYPE='0402',
 PART_NUMBER='G21796-173',
 LOCATION='R7M5',
 ROOM='MEM',
 CDS_LIB='mstr_discrete',
 CDS_PART_NAME='RES_0402-20.0,1%,1/16W,CHIP,G2A',
 PRIM_FILE='./archive_libs/mstr_discrete/res/chips/chips.prt';

PART_NAME
 R7M6 'RES_0402-665,1.0%,1/16W,CHIP,GA':
 ROOM='MEM';

SECTION_NUMBER 1
 '@BASEBOARD_FAB2_LIB.BASEBOARD_FAB2(SCH_1):PAGE99_I107@MSTR_DISCRETE.RES(CHIPS)':
 C_PATH='@baseboard_fab2_lib.baseboard_fab2(sch_1):page99_i107@mstr_discrete.res~
(chips)',
 P_PATH='@baseboard_fab2_lib.baseboard_fab2(sch_1):page99_i107@mstr_discrete.res~
(chips)',
 PATH='I107',
 DRAWING='@BASEBOARD_FAB2_LIB.BASEBOARD_FAB2(SCH_1):PAGE99',
 WATTAGE='1/16W',
 TOLERANCE='1.0%',
 SEC_TYPE='0402',
 MATERIAL='CHIP',
 BOM_COST='SM_CONTROLLER',
 PHYS_PAGE='99',
 XY='(1225,1250)',
 ROT='0',
 VER='2',
 VALUE='665',
 PACK_TYPE='0402',
 PART_NUMBER='G21796-235',
 LOCATION='R7M6',
 ROOM='MEM',
 SEC='1',
 CDS_LIB='mstr_discrete',
 CDS_PART_NAME='RES_0402-665,1.0%,1/16W,CHIP,GA',
 PRIM_FILE='./archive_libs/mstr_discrete/res/chips/chips.prt';

PART_NAME
 R7M7 'RES_0402-240,1.0%,1/16W,CHIP,GA':
 ROOM='MEM',
 SIGNAL_MODEL='DEFAULT_RESISTOR_750OHM_2_1';

SECTION_NUMBER 1
 '@BASEBOARD_FAB2_LIB.BASEBOARD_FAB2(SCH_1):PAGE99_I77@MSTR_DISCRETE.RES(CHIPS)':
 C_PATH='@baseboard_fab2_lib.baseboard_fab2(sch_1):page99_i77@mstr_discrete.res(~
chips)',
 P_PATH='@baseboard_fab2_lib.baseboard_fab2(sch_1):page99_i77@mstr_discrete.res(~
chips)',
 PATH='I77',
 DRAWING='@BASEBOARD_FAB2_LIB.BASEBOARD_FAB2(SCH_1):PAGE99',
 CD_SEC='1',
 WATTAGE='1/16W',
 TOLERANCE='1.0%',
 MATERIAL='CHIP',
 BOM_COST='SM_CONTROLLER',
 PHYS_PAGE='99',
 XY='(-725,1250)',
 ROT='2',
 VER='2',
 VALUE='240',
 PACK_TYPE='0402',
 PART_NUMBER='G21796-294',
 LOCATION='R7M7',
 SIGNAL_MODEL='DEFAULT_RESISTOR_750OHM_2_1',
 ROOM='MEM',
 CDS_LIB='mstr_discrete',
 CDS_PART_NAME='RES_0402-240,1.0%,1/16W,CHIP,GA',
 PRIM_FILE='./archive_libs/mstr_discrete/res/chips/chips.prt';

PART_NAME
 R7M8 'RES_0402-10.0,1%,1/16W,CHIP,G2A':
 ROOM='MEM';

SECTION_NUMBER 1
 '@BASEBOARD_FAB2_LIB.BASEBOARD_FAB2(SCH_1):PAGE99_I112@MSTR_DISCRETE.RES(CHIPS)':
 C_PATH='@baseboard_fab2_lib.baseboard_fab2(sch_1):page99_i112@mstr_discrete.res~
(chips)',
 P_PATH='@baseboard_fab2_lib.baseboard_fab2(sch_1):page99_i112@mstr_discrete.res~
(chips)',
 PATH='I112',
 DRAWING='@BASEBOARD_FAB2_LIB.BASEBOARD_FAB2(SCH_1):PAGE99',
 WATTAGE='1/16W',
 TOLERANCE='1%',
 MATERIAL='CHIP',
 BOM_COST='SM_CONTROLLER',
 PHYS_PAGE='99',
 XY='(-1200,900)',
 ROT='0',
 VER='1',
 VALUE='10.0',
 PACK_TYPE='0402',
 PART_NUMBER='G21796-066',
 LOCATION='R7M8',
 ROOM='MEM',
 CDS_LIB='mstr_discrete',
 CDS_PART_NAME='RES_0402-10.0,1%,1/16W,CHIP,G2A',
 PRIM_FILE='./archive_libs/mstr_discrete/res/chips/chips.prt';

PART_NAME
 R7M9 'RES_0402-64.9,1.0%,1/16W,CHIP,A':
 ROOM='PROC_RSTS_PGOODS';

SECTION_NUMBER 1
 '@BASEBOARD_FAB2_LIB.BASEBOARD_FAB2(SCH_1):PAGE96_I28@MSTR_DISCRETE.RES(CHIPS)':
 C_PATH='@baseboard_fab2_lib.baseboard_fab2(sch_1):page96_i28@mstr_discrete.res(~
chips)',
 P_PATH='@baseboard_fab2_lib.baseboard_fab2(sch_1):page96_i28@mstr_discrete.res(~
chips)',
 PATH='I28',
 DRAWING='@BASEBOARD_FAB2_LIB.BASEBOARD_FAB2(SCH_1):PAGE96',
 WATTAGE='1/16W',
 TOLERANCE='1.0%',
 MATERIAL='CHIP',
 BOM_COST='PROC_SIDEBAND',
 PHYS_PAGE='96',
 XY='(975,2150)',
 ROT='0',
 VER='2',
 VALUE='64.9',
 PACK_TYPE='0402',
 PART_NUMBER='G21796-298',
 LOCATION='R7M9',
 ROOM='PROC_RSTS_PGOODS',
 CDS_LIB='mstr_discrete',
 CDS_PART_NAME='RES_0402-64.9,1.0%,1/16W,CHIP,A',
 PRIM_FILE='./archive_libs/mstr_discrete/res/chips/chips.prt';

PART_NAME
 R7P1 'RES_0402-42.2,1.0%,1/16W,EMPTYA':
 ROOM='DB1200Z';

SECTION_NUMBER 1
 '@BASEBOARD_FAB2_LIB.BASEBOARD_FAB2(SCH_1):PAGE103_I133@MSTR_DISCRETE.RES(CHIPS)':
 C_PATH='@baseboard_fab2_lib.baseboard_fab2(sch_1):page103_i133@mstr_discrete.re~
s(chips)',
 P_PATH='@baseboard_fab2_lib.baseboard_fab2(sch_1):page103_i133@mstr_discrete.re~
s(chips)',
 PATH='I133',
 DRAWING='@BASEBOARD_FAB2_LIB.BASEBOARD_FAB2(SCH_1):PAGE103',
 WATTAGE='1/16W',
 TOLERANCE='1.0%',
 SEC_TYPE='0402',
 MATERIAL='EMPTY',
 BOM_COST='SYS_CLOCK',
 PHYS_PAGE='103',
 XY='(-3325,2775)',
 ROT='0',
 VER='1',
 VALUE='42.2',
 PACK_TYPE='0402',
 PART_NUMBER='G21796-259',
 LOCATION='R7P1',
 ROOM='DB1200Z',
 SEC='1',
 CDS_LIB='mstr_discrete',
 CDS_PART_NAME='RES_0402-42.2,1.0%,1/16W,EMPTYA',
 PRIM_FILE='./archive_libs/mstr_discrete/res/chips/chips.prt';

PART_NAME
 R7P2 'RES_0402-42.2,1.0%,1/16W,EMPTYA':
 ROOM='DB1200Z';

SECTION_NUMBER 1
 '@BASEBOARD_FAB2_LIB.BASEBOARD_FAB2(SCH_1):PAGE103_I135@MSTR_DISCRETE.RES(CHIPS)':
 C_PATH='@baseboard_fab2_lib.baseboard_fab2(sch_1):page103_i135@mstr_discrete.re~
s(chips)',
 P_PATH='@baseboard_fab2_lib.baseboard_fab2(sch_1):page103_i135@mstr_discrete.re~
s(chips)',
 PATH='I135',
 DRAWING='@BASEBOARD_FAB2_LIB.BASEBOARD_FAB2(SCH_1):PAGE103',
 WATTAGE='1/16W',
 TOLERANCE='1.0%',
 SEC_TYPE='0402',
 MATERIAL='EMPTY',
 BOM_COST='SYS_CLOCK',
 PHYS_PAGE='103',
 XY='(-3325,2450)',
 ROT='0',
 VER='1',
 VALUE='42.2',
 PACK_TYPE='0402',
 PART_NUMBER='G21796-259',
 LOCATION='R7P2',
 ROOM='DB1200Z',
 SEC='1',
 CDS_LIB='mstr_discrete',
 CDS_PART_NAME='RES_0402-42.2,1.0%,1/16W,EMPTYA',
 PRIM_FILE='./archive_libs/mstr_discrete/res/chips/chips.prt';

PART_NAME
 R7P3 'RES_0402-42.2,1.0%,1/16W,EMPTYA':
 ROOM='DB1200Z';

SECTION_NUMBER 1
 '@BASEBOARD_FAB2_LIB.BASEBOARD_FAB2(SCH_1):PAGE103_I129@MSTR_DISCRETE.RES(CHIPS)':
 C_PATH='@baseboard_fab2_lib.baseboard_fab2(sch_1):page103_i129@mstr_discrete.re~
s(chips)',
 P_PATH='@baseboard_fab2_lib.baseboard_fab2(sch_1):page103_i129@mstr_discrete.re~
s(chips)',
 PATH='I129',
 DRAWING='@BASEBOARD_FAB2_LIB.BASEBOARD_FAB2(SCH_1):PAGE103',
 WATTAGE='1/16W',
 TOLERANCE='1.0%',
 SEC_TYPE='0402',
 MATERIAL='EMPTY',
 BOM_COST='SYS_CLOCK',
 PHYS_PAGE='103',
 XY='(-3325,3425)',
 ROT='0',
 VER='1',
 VALUE='42.2',
 PACK_TYPE='0402',
 PART_NUMBER='G21796-259',
 LOCATION='R7P3',
 ROOM='DB1200Z',
 SEC='1',
 CDS_LIB='mstr_discrete',
 CDS_PART_NAME='RES_0402-42.2,1.0%,1/16W,EMPTYA',
 PRIM_FILE='./archive_libs/mstr_discrete/res/chips/chips.prt';

PART_NAME
 R7P4 'RES_0402-42.2,1.0%,1/16W,EMPTYA':
 ROOM='DB1200Z';

SECTION_NUMBER 1
 '@BASEBOARD_FAB2_LIB.BASEBOARD_FAB2(SCH_1):PAGE103_I131@MSTR_DISCRETE.RES(CHIPS)':
 C_PATH='@baseboard_fab2_lib.baseboard_fab2(sch_1):page103_i131@mstr_discrete.re~
s(chips)',
 P_PATH='@baseboard_fab2_lib.baseboard_fab2(sch_1):page103_i131@mstr_discrete.re~
s(chips)',
 PATH='I131',
 DRAWING='@BASEBOARD_FAB2_LIB.BASEBOARD_FAB2(SCH_1):PAGE103',
 WATTAGE='1/16W',
 TOLERANCE='1.0%',
 SEC_TYPE='0402',
 MATERIAL='EMPTY',
 BOM_COST='SYS_CLOCK',
 PHYS_PAGE='103',
 XY='(-3325,3100)',
 ROT='0',
 VER='1',
 VALUE='42.2',
 PACK_TYPE='0402',
 PART_NUMBER='G21796-259',
 LOCATION='R7P4',
 ROOM='DB1200Z',
 SEC='1',
 CDS_LIB='mstr_discrete',
 CDS_PART_NAME='RES_0402-42.2,1.0%,1/16W,EMPTYA',
 PRIM_FILE='./archive_libs/mstr_discrete/res/chips/chips.prt';

PART_NAME
 R7P5 'RES_0402-150.0,1%,1/16W,CHIP,GA':
 ROOM='PROC_SIDEBAND';

SECTION_NUMBER 1
 '@BASEBOARD_FAB2_LIB.BASEBOARD_FAB2(SCH_1):PAGE152_I61@MSTR_DISCRETE.RES(CHIPS)':
 C_PATH='@baseboard_fab2_lib.baseboard_fab2(sch_1):page152_i61@mstr_discrete.res~
(chips)',
 P_PATH='@baseboard_fab2_lib.baseboard_fab2(sch_1):page152_i61@mstr_discrete.res~
(chips)',
 PATH='I61',
 DRAWING='@BASEBOARD_FAB2_LIB.BASEBOARD_FAB2(SCH_1):PAGE152',
 WATTAGE='1/16W',
 TOLERANCE='1%',
 SEC_TYPE='0402',
 MATERIAL='CHIP',
 BOM_COST='PROC_SIDEBAND',
 PHYS_PAGE='152',
 XY='(-8250,3275)',
 ROT='0',
 VER='2',
 VALUE='150.0',
 PACK_TYPE='0402',
 PART_NUMBER='G21796-009',
 LOCATION='R7P5',
 ROOM='PROC_SIDEBAND',
 SEC='1',
 CDS_LIB='mstr_discrete',
 CDS_PART_NAME='RES_0402-150.0,1%,1/16W,CHIP,GA',
 PRIM_FILE='./archive_libs/mstr_discrete/res/chips/chips.prt';

PART_NAME
 R7P6 'RES_0402-42.2,1.0%,1/16W,EMPTYA':
 ROOM='DB1200Z';

SECTION_NUMBER 1
 '@BASEBOARD_FAB2_LIB.BASEBOARD_FAB2(SCH_1):PAGE103_I125@MSTR_DISCRETE.RES(CHIPS)':
 C_PATH='@baseboard_fab2_lib.baseboard_fab2(sch_1):page103_i125@mstr_discrete.re~
s(chips)',
 P_PATH='@baseboard_fab2_lib.baseboard_fab2(sch_1):page103_i125@mstr_discrete.re~
s(chips)',
 PATH='I125',
 DRAWING='@BASEBOARD_FAB2_LIB.BASEBOARD_FAB2(SCH_1):PAGE103',
 WATTAGE='1/16W',
 TOLERANCE='1.0%',
 SEC_TYPE='0402',
 MATERIAL='EMPTY',
 BOM_COST='SYS_CLOCK',
 PHYS_PAGE='103',
 XY='(-3325,4075)',
 ROT='0',
 VER='1',
 VALUE='42.2',
 PACK_TYPE='0402',
 PART_NUMBER='G21796-259',
 LOCATION='R7P6',
 ROOM='DB1200Z',
 SEC='1',
 CDS_LIB='mstr_discrete',
 CDS_PART_NAME='RES_0402-42.2,1.0%,1/16W,EMPTYA',
 PRIM_FILE='./archive_libs/mstr_discrete/res/chips/chips.prt';

PART_NAME
 R7P7 'RES_0402-42.2,1.0%,1/16W,EMPTYA':
 ROOM='DB1200Z';

SECTION_NUMBER 1
 '@BASEBOARD_FAB2_LIB.BASEBOARD_FAB2(SCH_1):PAGE103_I127@MSTR_DISCRETE.RES(CHIPS)':
 C_PATH='@baseboard_fab2_lib.baseboard_fab2(sch_1):page103_i127@mstr_discrete.re~
s(chips)',
 P_PATH='@baseboard_fab2_lib.baseboard_fab2(sch_1):page103_i127@mstr_discrete.re~
s(chips)',
 PATH='I127',
 DRAWING='@BASEBOARD_FAB2_LIB.BASEBOARD_FAB2(SCH_1):PAGE103',
 WATTAGE='1/16W',
 TOLERANCE='1.0%',
 MATERIAL='EMPTY',
 BOM_COST='SYS_CLOCK',
 PHYS_PAGE='103',
 XY='(-3325,3750)',
 ROT='0',
 VER='1',
 VALUE='42.2',
 PACK_TYPE='0402',
 PART_NUMBER='G21796-259',
 LOCATION='R7P7',
 ROOM='DB1200Z',
 CDS_LIB='mstr_discrete',
 CDS_PART_NAME='RES_0402-42.2,1.0%,1/16W,EMPTYA',
 PRIM_FILE='./archive_libs/mstr_discrete/res/chips/chips.prt';

PART_NAME
 R7P8 'RES_0402-49.9,1%,1/16W,CHIP,G2A':
 ROOM='CPU1';

SECTION_NUMBER 1
 '@BASEBOARD_FAB2_LIB.BASEBOARD_FAB2(SCH_1):PAGE55_I123@MSTR_DISCRETE.RES(CHIPS)':
 C_PATH='@baseboard_fab2_lib.baseboard_fab2(sch_1):page55_i123@mstr_discrete.res~
(chips)',
 P_PATH='@baseboard_fab2_lib.baseboard_fab2(sch_1):page55_i123@mstr_discrete.res~
(chips)',
 PATH='I123',
 DRAWING='@BASEBOARD_FAB2_LIB.BASEBOARD_FAB2(SCH_1):PAGE55',
 WATTAGE='1/16W',
 TOLERANCE='1%',
 SEC_TYPE='0402',
 MATERIAL='CHIP',
 BOM_COST='PROC_SOCKET',
 PHYS_PAGE='55',
 XY='(6600,1425)',
 ROT='2',
 VER='2',
 VALUE='49.9',
 PACK_TYPE='0402',
 PART_NUMBER='G21796-047',
 LOCATION='R7P8',
 ROOM='CPU1',
 SEC='1',
 CDS_LIB='mstr_discrete',
 CDS_PART_NAME='RES_0402-49.9,1%,1/16W,CHIP,G2A',
 PRIM_FILE='./archive_libs/mstr_discrete/res/chips/chips.prt';

PART_NAME
 R7P9 'RES_0402-42.2,1.0%,1/16W,EMPTYA':
 ROOM='DB1200Z';

SECTION_NUMBER 1
 '@BASEBOARD_FAB2_LIB.BASEBOARD_FAB2(SCH_1):PAGE103_I121@MSTR_DISCRETE.RES(CHIPS)':
 C_PATH='@baseboard_fab2_lib.baseboard_fab2(sch_1):page103_i121@mstr_discrete.re~
s(chips)',
 P_PATH='@baseboard_fab2_lib.baseboard_fab2(sch_1):page103_i121@mstr_discrete.re~
s(chips)',
 PATH='I121',
 DRAWING='@BASEBOARD_FAB2_LIB.BASEBOARD_FAB2(SCH_1):PAGE103',
 WATTAGE='1/16W',
 TOLERANCE='1.0%',
 SEC_TYPE='0402',
 MATERIAL='EMPTY',
 BOM_COST='SYS_CLOCK',
 PHYS_PAGE='103',
 XY='(-3325,4800)',
 ROT='0',
 VER='1',
 VALUE='42.2',
 PACK_TYPE='0402',
 PART_NUMBER='G21796-259',
 LOCATION='R7P9',
 ROOM='DB1200Z',
 SEC='1',
 CDS_LIB='mstr_discrete',
 CDS_PART_NAME='RES_0402-42.2,1.0%,1/16W,EMPTYA',
 PRIM_FILE='./archive_libs/mstr_discrete/res/chips/chips.prt';

PART_NAME
 R7P10 'RES_0402-49.9,1%,1/16W,CHIP,G2A':
 ROOM='CPU1';

SECTION_NUMBER 1
 '@BASEBOARD_FAB2_LIB.BASEBOARD_FAB2(SCH_1):PAGE55_I124@MSTR_DISCRETE.RES(CHIPS)':
 C_PATH='@baseboard_fab2_lib.baseboard_fab2(sch_1):page55_i124@mstr_discrete.res~
(chips)',
 P_PATH='@baseboard_fab2_lib.baseboard_fab2(sch_1):page55_i124@mstr_discrete.res~
(chips)',
 PATH='I124',
 DRAWING='@BASEBOARD_FAB2_LIB.BASEBOARD_FAB2(SCH_1):PAGE55',
 WATTAGE='1/16W',
 TOLERANCE='1%',
 SEC_TYPE='0402',
 MATERIAL='CHIP',
 BOM_COST='PROC_SOCKET',
 PHYS_PAGE='55',
 XY='(6825,1425)',
 ROT='2',
 VER='2',
 VALUE='49.9',
 PACK_TYPE='0402',
 PART_NUMBER='G21796-047',
 LOCATION='R7P10',
 ROOM='CPU1',
 SEC='1',
 CDS_LIB='mstr_discrete',
 CDS_PART_NAME='RES_0402-49.9,1%,1/16W,CHIP,G2A',
 PRIM_FILE='./archive_libs/mstr_discrete/res/chips/chips.prt';

PART_NAME
 R7P11 'RES_0402-49.9,1%,1/16W,CHIP,G2A':
 ROOM='CPU1';

SECTION_NUMBER 1
 '@BASEBOARD_FAB2_LIB.BASEBOARD_FAB2(SCH_1):PAGE55_I126@MSTR_DISCRETE.RES(CHIPS)':
 C_PATH='@baseboard_fab2_lib.baseboard_fab2(sch_1):page55_i126@mstr_discrete.res~
(chips)',
 P_PATH='@baseboard_fab2_lib.baseboard_fab2(sch_1):page55_i126@mstr_discrete.res~
(chips)',
 PATH='I126',
 DRAWING='@BASEBOARD_FAB2_LIB.BASEBOARD_FAB2(SCH_1):PAGE55',
 WATTAGE='1/16W',
 TOLERANCE='1%',
 SEC_TYPE='0402',
 MATERIAL='CHIP',
 BOM_COST='PROC_SOCKET',
 PHYS_PAGE='55',
 XY='(7275,1425)',
 ROT='2',
 VER='2',
 VALUE='49.9',
 PACK_TYPE='0402',
 PART_NUMBER='G21796-047',
 LOCATION='R7P11',
 ROOM='CPU1',
 SEC='1',
 CDS_LIB='mstr_discrete',
 CDS_PART_NAME='RES_0402-49.9,1%,1/16W,CHIP,G2A',
 PRIM_FILE='./archive_libs/mstr_discrete/res/chips/chips.prt';

PART_NAME
 R7P12 'RES_0402-42.2,1.0%,1/16W,EMPTYA':
 ROOM='DB1200Z';

SECTION_NUMBER 1
 '@BASEBOARD_FAB2_LIB.BASEBOARD_FAB2(SCH_1):PAGE103_I123@MSTR_DISCRETE.RES(CHIPS)':
 C_PATH='@baseboard_fab2_lib.baseboard_fab2(sch_1):page103_i123@mstr_discrete.re~
s(chips)',
 P_PATH='@baseboard_fab2_lib.baseboard_fab2(sch_1):page103_i123@mstr_discrete.re~
s(chips)',
 PATH='I123',
 DRAWING='@BASEBOARD_FAB2_LIB.BASEBOARD_FAB2(SCH_1):PAGE103',
 WATTAGE='1/16W',
 TOLERANCE='1.0%',
 SEC_TYPE='0402',
 MATERIAL='EMPTY',
 BOM_COST='SYS_CLOCK',
 PHYS_PAGE='103',
 XY='(-3300,4425)',
 ROT='0',
 VER='1',
 VALUE='42.2',
 PACK_TYPE='0402',
 PART_NUMBER='G21796-259',
 LOCATION='R7P12',
 ROOM='DB1200Z',
 SEC='1',
 CDS_LIB='mstr_discrete',
 CDS_PART_NAME='RES_0402-42.2,1.0%,1/16W,EMPTYA',
 PRIM_FILE='./archive_libs/mstr_discrete/res/chips/chips.prt';

PART_NAME
 R7P13 'RES_0402-10.0K,1%,1/16W,CHIP,GA':
 ROOM='CPU1';

SECTION_NUMBER 1
 '@BASEBOARD_FAB2_LIB.BASEBOARD_FAB2(SCH_1):PAGE97_I81@MSTR_DISCRETE.RES(CHIPS)':
 C_PATH='@baseboard_fab2_lib.baseboard_fab2(sch_1):page97_i81@mstr_discrete.res(~
chips)',
 P_PATH='@baseboard_fab2_lib.baseboard_fab2(sch_1):page97_i81@mstr_discrete.res(~
chips)',
 PATH='I81',
 DRAWING='@BASEBOARD_FAB2_LIB.BASEBOARD_FAB2(SCH_1):PAGE97',
 WATTAGE='1/16W',
 TOLERANCE='1%',
 SEC_TYPE='0402',
 MATERIAL='CHIP',
 PHYS_PAGE='97',
 XY='(-2375,2825)',
 ROT='0',
 VER='1',
 VALUE='10.0K',
 PACK_TYPE='0402',
 PART_NUMBER='G21796-016',
 LOCATION='R7P13',
 ROOM='CPU1',
 SEC='1',
 CDS_LIB='mstr_discrete',
 CDS_PART_NAME='RES_0402-10.0K,1%,1/16W,CHIP,GA',
 PRIM_FILE='./archive_libs/mstr_discrete/res/chips/chips.prt';

PART_NAME
 R7P14 'RES_0402-240,1.0%,1/16W,CHIP,GA':
 ROOM='PROC_SIDEBAND';

SECTION_NUMBER 1
 '@BASEBOARD_FAB2_LIB.BASEBOARD_FAB2(SCH_1):PAGE90_I100@MSTR_DISCRETE.RES(CHIPS)':
 C_PATH='@baseboard_fab2_lib.baseboard_fab2(sch_1):page90_i100@mstr_discrete.res~
(chips)',
 P_PATH='@baseboard_fab2_lib.baseboard_fab2(sch_1):page90_i100@mstr_discrete.res~
(chips)',
 PATH='I100',
 DRAWING='@BASEBOARD_FAB2_LIB.BASEBOARD_FAB2(SCH_1):PAGE90',
 WATTAGE='1/16W',
 TOLERANCE='1.0%',
 SEC_TYPE='0402',
 MATERIAL='CHIP',
 BOM_COST='PROC',
 PHYS_PAGE='90',
 XY='(-425,850)',
 ROT='0',
 VER='1',
 VALUE='240',
 PACK_TYPE='0402',
 PART_NUMBER='G21796-294',
 LOCATION='R7P14',
 ROOM='PROC_SIDEBAND',
 SEC='1',
 CDS_LIB='mstr_discrete',
 CDS_PART_NAME='RES_0402-240,1.0%,1/16W,CHIP,GA',
 PRIM_FILE='./archive_libs/mstr_discrete/res/chips/chips.prt';

PART_NAME
 R7P15 'RES_0402-240,1.0%,1/16W,EMPTY,A':
 ROOM='PROC_SIDEBAND';

SECTION_NUMBER 1
 '@BASEBOARD_FAB2_LIB.BASEBOARD_FAB2(SCH_1):PAGE90_I74@MSTR_DISCRETE.RES(CHIPS)':
 C_PATH='@baseboard_fab2_lib.baseboard_fab2(sch_1):page90_i74@mstr_discrete.res(~
chips)',
 P_PATH='@baseboard_fab2_lib.baseboard_fab2(sch_1):page90_i74@mstr_discrete.res(~
chips)',
 PATH='I74',
 DRAWING='@BASEBOARD_FAB2_LIB.BASEBOARD_FAB2(SCH_1):PAGE90',
 WATTAGE='1/16W',
 TOLERANCE='1.0%',
 SEC_TYPE='0402',
 MATERIAL='EMPTY',
 BOM_COST='PROC',
 PHYS_PAGE='90',
 XY='(-425,650)',
 ROT='0',
 VER='1',
 VALUE='240',
 PACK_TYPE='0402',
 PART_NUMBER='G21796-294',
 LOCATION='R7P15',
 ROOM='PROC_SIDEBAND',
 SEC='1',
 CDS_LIB='mstr_discrete',
 CDS_PART_NAME='RES_0402-240,1.0%,1/16W,EMPTY,A',
 PRIM_FILE='./archive_libs/mstr_discrete/res/chips/chips.prt';

PART_NAME
 R7P16 'RES_0402-90.9,1%,1/16W,CHIP,G2A':
 ROOM='CPU1';

SECTION_NUMBER 1
 '@BASEBOARD_FAB2_LIB.BASEBOARD_FAB2(SCH_1):PAGE55_I119@MSTR_DISCRETE.RES(CHIPS)':
 C_PATH='@baseboard_fab2_lib.baseboard_fab2(sch_1):page55_i119@mstr_discrete.res~
(chips)',
 P_PATH='@baseboard_fab2_lib.baseboard_fab2(sch_1):page55_i119@mstr_discrete.res~
(chips)',
 PATH='I119',
 DRAWING='@BASEBOARD_FAB2_LIB.BASEBOARD_FAB2(SCH_1):PAGE55',
 WATTAGE='1/16W',
 TOLERANCE='1%',
 SEC_TYPE='0402',
 MATERIAL='CHIP',
 BOM_COST='PROC_SOCKET',
 PHYS_PAGE='55',
 XY='(7025,2600)',
 ROT='2',
 VER='2',
 VALUE='90.9',
 PACK_TYPE='0402',
 PART_NUMBER='G21796-365',
 LOCATION='R7P16',
 ROOM='CPU1',
 SEC='1',
 CDS_LIB='mstr_discrete',
 CDS_PART_NAME='RES_0402-90.9,1%,1/16W,CHIP,G2A',
 PRIM_FILE='./archive_libs/mstr_discrete/res/chips/chips.prt';

PART_NAME
 R7P17 'RES_0402-90.9,1%,1/16W,CHIP,G2A':
 ROOM='CPU1';

SECTION_NUMBER 1
 '@BASEBOARD_FAB2_LIB.BASEBOARD_FAB2(SCH_1):PAGE55_I140@MSTR_DISCRETE.RES(CHIPS)':
 C_PATH='@baseboard_fab2_lib.baseboard_fab2(sch_1):page55_i140@mstr_discrete.res~
(chips)',
 P_PATH='@baseboard_fab2_lib.baseboard_fab2(sch_1):page55_i140@mstr_discrete.res~
(chips)',
 PATH='I140',
 DRAWING='@BASEBOARD_FAB2_LIB.BASEBOARD_FAB2(SCH_1):PAGE55',
 WATTAGE='1/16W',
 TOLERANCE='1%',
 SEC_TYPE='0402',
 MATERIAL='CHIP',
 BOM_COST='PROC_SOCKET',
 PHYS_PAGE='55',
 XY='(6800,2650)',
 ROT='2',
 VER='2',
 VALUE='90.9',
 PACK_TYPE='0402',
 PART_NUMBER='G21796-365',
 LOCATION='R7P17',
 ROOM='CPU1',
 SEC='1',
 CDS_LIB='mstr_discrete',
 CDS_PART_NAME='RES_0402-90.9,1%,1/16W,CHIP,G2A',
 PRIM_FILE='./archive_libs/mstr_discrete/res/chips/chips.prt';

PART_NAME
 R7P18 'RES_0402-150.0,1%,1/16W,CHIP,GA':
 ROOM='PROC_SIDEBAND';

SECTION_NUMBER 1
 '@BASEBOARD_FAB2_LIB.BASEBOARD_FAB2(SCH_1):PAGE92_I100@MSTR_DISCRETE.RES(CHIPS)':
 C_PATH='@baseboard_fab2_lib.baseboard_fab2(sch_1):page92_i100@mstr_discrete.res~
(chips)',
 P_PATH='@baseboard_fab2_lib.baseboard_fab2(sch_1):page92_i100@mstr_discrete.res~
(chips)',
 PATH='I100',
 DRAWING='@BASEBOARD_FAB2_LIB.BASEBOARD_FAB2(SCH_1):PAGE92',
 WATTAGE='1/16W',
 TOLERANCE='1%',
 SEC_TYPE='0402',
 MATERIAL='CHIP',
 BOM_COST='PROC',
 PHYS_PAGE='92',
 XY='(-4350,4600)',
 ROT='0',
 VER='2',
 VALUE='150.0',
 PACK_TYPE='0402',
 PART_NUMBER='G21796-009',
 LOCATION='R7P18',
 ROOM='PROC_SIDEBAND',
 SEC='1',
 CDS_LIB='mstr_discrete',
 CDS_PART_NAME='RES_0402-150.0,1%,1/16W,CHIP,GA',
 PRIM_FILE='./archive_libs/mstr_discrete/res/chips/chips.prt';

PART_NAME
 R7P19 'RES_0402-100.0,1%,1/16W,CHIP,GA':
 ROOM='CPU1';

SECTION_NUMBER 1
 '@BASEBOARD_FAB2_LIB.BASEBOARD_FAB2(SCH_1):PAGE55_I115@MSTR_DISCRETE.RES(CHIPS)':
 C_PATH='@baseboard_fab2_lib.baseboard_fab2(sch_1):page55_i115@mstr_discrete.res~
(chips)',
 P_PATH='@baseboard_fab2_lib.baseboard_fab2(sch_1):page55_i115@mstr_discrete.res~
(chips)',
 PATH='I115',
 DRAWING='@BASEBOARD_FAB2_LIB.BASEBOARD_FAB2(SCH_1):PAGE55',
 WATTAGE='1/16W',
 TOLERANCE='1%',
 SEC_TYPE='0402',
 MATERIAL='CHIP',
 BOM_COST='PROC_SOCKET',
 PHYS_PAGE='55',
 XY='(6575,2725)',
 ROT='2',
 VER='2',
 VALUE='100.0',
 PACK_TYPE='0402',
 PART_NUMBER='G21796-017',
 LOCATION='R7P19',
 ROOM='CPU1',
 SEC='1',
 CDS_LIB='mstr_discrete',
 CDS_PART_NAME='RES_0402-100.0,1%,1/16W,CHIP,GA',
 PRIM_FILE='./archive_libs/mstr_discrete/res/chips/chips.prt';

PART_NAME
 R7P20 'RES_0402-150.0,1%,1/16W,CHIP,GA':
 ROOM='PROC_SIDEBAND';

SECTION_NUMBER 1
 '@BASEBOARD_FAB2_LIB.BASEBOARD_FAB2(SCH_1):PAGE97_I44@MSTR_DISCRETE.RES(CHIPS)':
 C_PATH='@baseboard_fab2_lib.baseboard_fab2(sch_1):page97_i44@mstr_discrete.res(~
chips)',
 P_PATH='@baseboard_fab2_lib.baseboard_fab2(sch_1):page97_i44@mstr_discrete.res(~
chips)',
 PATH='I44',
 DRAWING='@BASEBOARD_FAB2_LIB.BASEBOARD_FAB2(SCH_1):PAGE97',
 WATTAGE='1/16W',
 TOLERANCE='1%',
 MATERIAL='CHIP',
 PHYS_PAGE='97',
 XY='(-1200,4525)',
 ROT='0',
 VER='2',
 VALUE='150.0',
 PACK_TYPE='0402',
 PART_NUMBER='G21796-009',
 LOCATION='R7P20',
 ROOM='PROC_SIDEBAND',
 CDS_LIB='mstr_discrete',
 CDS_PART_NAME='RES_0402-150.0,1%,1/16W,CHIP,GA',
 PRIM_FILE='./archive_libs/mstr_discrete/res/chips/chips.prt';

PART_NAME
 R7P21 'RES_0402-150.0,1%,1/16W,CHIP,GA':
 ROOM='PROC_SIDEBAND';

SECTION_NUMBER 1
 '@BASEBOARD_FAB2_LIB.BASEBOARD_FAB2(SCH_1):PAGE152_I62@MSTR_DISCRETE.RES(CHIPS)':
 C_PATH='@baseboard_fab2_lib.baseboard_fab2(sch_1):page152_i62@mstr_discrete.res~
(chips)',
 P_PATH='@baseboard_fab2_lib.baseboard_fab2(sch_1):page152_i62@mstr_discrete.res~
(chips)',
 PATH='I62',
 DRAWING='@BASEBOARD_FAB2_LIB.BASEBOARD_FAB2(SCH_1):PAGE152',
 WATTAGE='1/16W',
 TOLERANCE='1%',
 SEC_TYPE='0402',
 MATERIAL='CHIP',
 BOM_COST='PROC_SIDEBAND',
 PHYS_PAGE='152',
 XY='(-8350,3275)',
 ROT='2',
 VER='2',
 VALUE='150.0',
 PACK_TYPE='0402',
 PART_NUMBER='G21796-009',
 LOCATION='R7P21',
 ROOM='PROC_SIDEBAND',
 SEC='1',
 CDS_LIB='mstr_discrete',
 CDS_PART_NAME='RES_0402-150.0,1%,1/16W,CHIP,GA',
 PRIM_FILE='./archive_libs/mstr_discrete/res/chips/chips.prt';

PART_NAME
 R7P22 'RES_0402-240,1.0%,1/16W,EMPTY,A':
 ROOM='PROC_SIDEBAND';

SECTION_NUMBER 1
 '@BASEBOARD_FAB2_LIB.BASEBOARD_FAB2(SCH_1):PAGE90_I76@MSTR_DISCRETE.RES(CHIPS)':
 C_PATH='@baseboard_fab2_lib.baseboard_fab2(sch_1):page90_i76@mstr_discrete.res(~
chips)',
 P_PATH='@baseboard_fab2_lib.baseboard_fab2(sch_1):page90_i76@mstr_discrete.res(~
chips)',
 PATH='I76',
 DRAWING='@BASEBOARD_FAB2_LIB.BASEBOARD_FAB2(SCH_1):PAGE90',
 WATTAGE='1/16W',
 TOLERANCE='1.0%',
 SEC_TYPE='0402',
 MATERIAL='EMPTY',
 BOM_COST='PROC',
 PHYS_PAGE='90',
 XY='(-2450,800)',
 ROT='0',
 VER='1',
 VALUE='240',
 PACK_TYPE='0402',
 PART_NUMBER='G21796-294',
 LOCATION='R7P22',
 ROOM='PROC_SIDEBAND',
 SEC='1',
 CDS_LIB='mstr_discrete',
 CDS_PART_NAME='RES_0402-240,1.0%,1/16W,EMPTY,A',
 PRIM_FILE='./archive_libs/mstr_discrete/res/chips/chips.prt';

PART_NAME
 R7P25 'RES_0402-49.9,1%,1/16W,CHIP,G2A':
 ROOM='CPU1';

SECTION_NUMBER 1
 '@BASEBOARD_FAB2_LIB.BASEBOARD_FAB2(SCH_1):PAGE55_I170@MSTR_DISCRETE.RES(CHIPS)':
 C_PATH='@baseboard_fab2_lib.baseboard_fab2(sch_1):page55_i170@mstr_discrete.res~
(chips)',
 P_PATH='@baseboard_fab2_lib.baseboard_fab2(sch_1):page55_i170@mstr_discrete.res~
(chips)',
 PATH='I170',
 DRAWING='@BASEBOARD_FAB2_LIB.BASEBOARD_FAB2(SCH_1):PAGE55',
 WATTAGE='1/16W',
 TOLERANCE='1%',
 SEC_TYPE='0402',
 MATERIAL='CHIP',
 BOM_COST='PROC_SOCKET',
 PHYS_PAGE='55',
 XY='(12100,3900)',
 ROT='0',
 VER='1',
 VALUE='49.9',
 PACK_TYPE='0402',
 PART_NUMBER='G21796-047',
 LOCATION='R7P25',
 ROOM='CPU1',
 SEC='1',
 CDS_LIB='mstr_discrete',
 CDS_PART_NAME='RES_0402-49.9,1%,1/16W,CHIP,G2A',
 PRIM_FILE='./archive_libs/mstr_discrete/res/chips/chips.prt';

PART_NAME
 R7P26 'RES_0402-49.9,1%,1/16W,CHIP,G2A':
 ROOM='CPU1';

SECTION_NUMBER 1
 '@BASEBOARD_FAB2_LIB.BASEBOARD_FAB2(SCH_1):PAGE55_I156@MSTR_DISCRETE.RES(CHIPS)':
 C_PATH='@baseboard_fab2_lib.baseboard_fab2(sch_1):page55_i156@mstr_discrete.res~
(chips)',
 P_PATH='@baseboard_fab2_lib.baseboard_fab2(sch_1):page55_i156@mstr_discrete.res~
(chips)',
 PATH='I156',
 DRAWING='@BASEBOARD_FAB2_LIB.BASEBOARD_FAB2(SCH_1):PAGE55',
 WATTAGE='1/16W',
 TOLERANCE='1%',
 SEC_TYPE='0402',
 MATERIAL='CHIP',
 BOM_COST='PROC_SOCKET',
 PHYS_PAGE='55',
 XY='(12100,3850)',
 ROT='0',
 VER='1',
 VALUE='49.9',
 PACK_TYPE='0402',
 PART_NUMBER='G21796-047',
 LOCATION='R7P26',
 ROOM='CPU1',
 SEC='1',
 CDS_LIB='mstr_discrete',
 CDS_PART_NAME='RES_0402-49.9,1%,1/16W,CHIP,G2A',
 PRIM_FILE='./archive_libs/mstr_discrete/res/chips/chips.prt';

PART_NAME
 R7P27 'RES_0402-150.0,1%,1/16W,CHIP,GA':
 ROOM='PROC_SIDEBAND';

SECTION_NUMBER 1
 '@BASEBOARD_FAB2_LIB.BASEBOARD_FAB2(SCH_1):PAGE92_I65@MSTR_DISCRETE.RES(CHIPS)':
 C_PATH='@baseboard_fab2_lib.baseboard_fab2(sch_1):page92_i65@mstr_discrete.res(~
chips)',
 P_PATH='@baseboard_fab2_lib.baseboard_fab2(sch_1):page92_i65@mstr_discrete.res(~
chips)',
 PATH='I65',
 DRAWING='@BASEBOARD_FAB2_LIB.BASEBOARD_FAB2(SCH_1):PAGE92',
 WATTAGE='1/16W',
 TOLERANCE='1%',
 SEC_TYPE='0402',
 MATERIAL='CHIP',
 BOM_COST='PROC_SIDEBAND',
 PHYS_PAGE='92',
 XY='(-4275,1800)',
 ROT='0',
 VER='2',
 VALUE='150.0',
 PACK_TYPE='0402',
 PART_NUMBER='G21796-009',
 LOCATION='R7P27',
 ROOM='PROC_SIDEBAND',
 SEC='1',
 CDS_LIB='mstr_discrete',
 CDS_PART_NAME='RES_0402-150.0,1%,1/16W,CHIP,GA',
 PRIM_FILE='./archive_libs/mstr_discrete/res/chips/chips.prt';

PART_NAME
 R7P28 'RES_0402-150.0,1%,1/16W,CHIP,GA':
 ROOM='PROC_SIDEBAND';

SECTION_NUMBER 1
 '@BASEBOARD_FAB2_LIB.BASEBOARD_FAB2(SCH_1):PAGE93_I106@MSTR_DISCRETE.RES(CHIPS)':
 C_PATH='@baseboard_fab2_lib.baseboard_fab2(sch_1):page93_i106@mstr_discrete.res~
(chips)',
 P_PATH='@baseboard_fab2_lib.baseboard_fab2(sch_1):page93_i106@mstr_discrete.res~
(chips)',
 PATH='I106',
 DRAWING='@BASEBOARD_FAB2_LIB.BASEBOARD_FAB2(SCH_1):PAGE93',
 WATTAGE='1/16W',
 TOLERANCE='1%',
 SEC_TYPE='0402',
 MATERIAL='CHIP',
 BOM_COST='PROC_SIDEBAND',
 PHYS_PAGE='93',
 XY='(-2200,2500)',
 ROT='0',
 VER='2',
 VALUE='150.0',
 PACK_TYPE='0402',
 PART_NUMBER='G21796-009',
 LOCATION='R7P28',
 ROOM='PROC_SIDEBAND',
 SEC='1',
 CDS_LIB='mstr_discrete',
 CDS_PART_NAME='RES_0402-150.0,1%,1/16W,CHIP,GA',
 PRIM_FILE='./archive_libs/mstr_discrete/res/chips/chips.prt';

PART_NAME
 R7P29 'RES_0402-51.1,1.0%,1/16W,CHIP,A':
 ROOM='DEBUG';

SECTION_NUMBER 1
 '@BASEBOARD_FAB2_LIB.BASEBOARD_FAB2(SCH_1):PAGE112_I61@MSTR_DISCRETE.RES(CHIPS)':
 C_PATH='@baseboard_fab2_lib.baseboard_fab2(sch_1):page112_i61@mstr_discrete.res~
(chips)',
 P_PATH='@baseboard_fab2_lib.baseboard_fab2(sch_1):page112_i61@mstr_discrete.res~
(chips)',
 PATH='I61',
 DRAWING='@BASEBOARD_FAB2_LIB.BASEBOARD_FAB2(SCH_1):PAGE112',
 WATTAGE='1/16W',
 TOLERANCE='1.0%',
 MATERIAL='CHIP',
 BOM_COST='DEBUG',
 PHYS_PAGE='112',
 XY='(875,1100)',
 ROT='0',
 VER='2',
 VALUE='51.1',
 PACK_TYPE='0402',
 PART_NUMBER='G21796-208',
 LOCATION='R7P29',
 ROOM='DEBUG',
 CDS_LIB='mstr_discrete',
 CDS_PART_NAME='RES_0402-51.1,1.0%,1/16W,CHIP,A',
 PRIM_FILE='./archive_libs/mstr_discrete/res/chips/chips.prt';

PART_NAME
 R7P30 'RES_0402-100.0,1%,1/16W,CHIP,GA':
 ROOM='DEBUG';

SECTION_NUMBER 1
 '@BASEBOARD_FAB2_LIB.BASEBOARD_FAB2(SCH_1):PAGE112_I50@MSTR_DISCRETE.RES(CHIPS)':
 C_PATH='@baseboard_fab2_lib.baseboard_fab2(sch_1):page112_i50@mstr_discrete.res~
(chips)',
 P_PATH='@baseboard_fab2_lib.baseboard_fab2(sch_1):page112_i50@mstr_discrete.res~
(chips)',
 PATH='I50',
 DRAWING='@BASEBOARD_FAB2_LIB.BASEBOARD_FAB2(SCH_1):PAGE112',
 WATTAGE='1/16W',
 TOLERANCE='1%',
 SEC_TYPE='0402',
 MATERIAL='CHIP',
 PHYS_PAGE='112',
 XY='(2325,2400)',
 ROT='0',
 VER='2',
 VALUE='100.0',
 PACK_TYPE='0402',
 PART_NUMBER='G21796-017',
 LOCATION='R7P30',
 ROOM='DEBUG',
 SEC='1',
 CDS_LIB='mstr_discrete',
 CDS_PART_NAME='RES_0402-100.0,1%,1/16W,CHIP,GA',
 PRIM_FILE='./archive_libs/mstr_discrete/res/chips/chips.prt';

PART_NAME
 R7R1 'RES_0402-51.1,1.0%,1/16W,CHIP,A':;

SECTION_NUMBER 1
 '@BASEBOARD_FAB2_LIB.BASEBOARD_FAB2(SCH_1):PAGE214_I109@MSTR_DISCRETE.RES(CHIPS)':
 C_PATH='@baseboard_fab2_lib.baseboard_fab2(sch_1):page214_i109@mstr_discrete.re~
s(chips)',
 P_PATH='@baseboard_fab2_lib.baseboard_fab2(sch_1):page214_i109@mstr_discrete.re~
s(chips)',
 PATH='I109',
 DRAWING='@BASEBOARD_FAB2_LIB.BASEBOARD_FAB2(SCH_1):PAGE214',
 WATTAGE='1/16W',
 TOLERANCE='1.0%',
 SEC_TYPE='0402',
 MATERIAL='CHIP',
 PHYS_PAGE='214',
 XY='(3975,3425)',
 ROT='0',
 VER='2',
 VALUE='51.1',
 PACK_TYPE='0402',
 PART_NUMBER='G21796-208',
 LOCATION='R7R1',
 SEC='1',
 CDS_LIB='mstr_discrete',
 CDS_PART_NAME='RES_0402-51.1,1.0%,1/16W,CHIP,A',
 PRIM_FILE='./archive_libs/mstr_discrete/res/chips/chips.prt';

PART_NAME
 R7U2 'RES_0402-100.0,1%,1/16W,EMPTY,A':
 ROOM='VDDQ_GHJ_PWR_VR';

SECTION_NUMBER 1
 '@BASEBOARD_FAB2_LIB.BASEBOARD_FAB2(SCH_1):PAGE225_I74@MSTR_DISCRETE.RES(CHIPS)':
 C_PATH='@baseboard_fab2_lib.baseboard_fab2(sch_1):page225_i74@mstr_discrete.res~
(chips)',
 P_PATH='@baseboard_fab2_lib.baseboard_fab2(sch_1):page225_i74@mstr_discrete.res~
(chips)',
 PATH='I74',
 DRAWING='@BASEBOARD_FAB2_LIB.BASEBOARD_FAB2(SCH_1):PAGE225',
 WATTAGE='1/16W',
 TOLERANCE='1%',
 SEC_TYPE='0402',
 MATERIAL='EMPTY',
 PHYS_PAGE='225',
 XY='(-650,2075)',
 ROT='0',
 VER='2',
 VALUE='100.0',
 PACK_TYPE='0402',
 PART_NUMBER='G21796-017',
 LOCATION='R7U2',
 ROOM='VDDQ_GHJ_PWR_VR',
 SEC='1',
 CDS_LIB='mstr_discrete',
 CDS_PART_NAME='RES_0402-100.0,1%,1/16W,EMPTY,A',
 PRIM_FILE='./archive_libs/mstr_discrete/res/chips/chips.prt';

PART_NAME
 R7W1 'RES_0402-0.0,5%,1/16W,CHIP,G21A':
 ROOM='SB';

SECTION_NUMBER 1
 '@BASEBOARD_FAB2_LIB.BASEBOARD_FAB2(SCH_1):PAGE118_I167@MSTR_DISCRETE.RES(CHIPS)':
 C_PATH='@baseboard_fab2_lib.baseboard_fab2(sch_1):page118_i167@mstr_discrete.re~
s(chips)',
 P_PATH='@baseboard_fab2_lib.baseboard_fab2(sch_1):page118_i167@mstr_discrete.re~
s(chips)',
 PATH='I167',
 DRAWING='@BASEBOARD_FAB2_LIB.BASEBOARD_FAB2(SCH_1):PAGE118',
 WATTAGE='1/16W',
 TOLERANCE='5%',
 SEC_TYPE='0402',
 MATERIAL='CHIP',
 BOM_COST='SB',
 PHYS_PAGE='118',
 XY='(-6650,4075)',
 ROT='0',
 VER='1',
 VALUE='0.0',
 PACK_TYPE='0402',
 PART_NUMBER='G21497-005',
 LOCATION='R7W1',
 ROOM='SB',
 SEC='1',
 CDS_LIB='mstr_discrete',
 CDS_PART_NAME='RES_0402-0.0,5%,1/16W,CHIP,G21A',
 PRIM_FILE='./archive_libs/mstr_discrete/res/chips/chips.prt';

PART_NAME
 R7W2 'RES_0402-10.0K,1%,1/16W,EMPTY,A':
 ROOM='DB1200ZL';

SECTION_NUMBER 1
 '@BASEBOARD_FAB2_LIB.BASEBOARD_FAB2(SCH_1):PAGE166_I42@MSTR_DISCRETE.RES(CHIPS)':
 C_PATH='@baseboard_fab2_lib.baseboard_fab2(sch_1):page166_i42@mstr_discrete.res~
(chips)',
 P_PATH='@baseboard_fab2_lib.baseboard_fab2(sch_1):page166_i42@mstr_discrete.res~
(chips)',
 PATH='I42',
 DRAWING='@BASEBOARD_FAB2_LIB.BASEBOARD_FAB2(SCH_1):PAGE166',
 WATTAGE='1/16W',
 TOLERANCE='1%',
 SEC_TYPE='0402',
 MATERIAL='EMPTY',
 BOM_COST='SYS_CLOCK',
 PHYS_PAGE='166',
 XY='(-2400,2500)',
 ROT='0',
 VER='2',
 VALUE='10.0K',
 PACK_TYPE='0402',
 PART_NUMBER='G21796-016',
 LOCATION='R7W2',
 ROOM='DB1200ZL',
 SEC='1',
 CDS_LIB='mstr_discrete',
 CDS_PART_NAME='RES_0402-10.0K,1%,1/16W,EMPTY,A',
 PRIM_FILE='./archive_libs/mstr_discrete/res/chips/chips.prt';

PART_NAME
 R7W3 'RES_0402-10.0K,1%,1/16W,EMPTY,A':
 ROOM='DB1200ZL';

SECTION_NUMBER 1
 '@BASEBOARD_FAB2_LIB.BASEBOARD_FAB2(SCH_1):PAGE166_I46@MSTR_DISCRETE.RES(CHIPS)':
 C_PATH='@baseboard_fab2_lib.baseboard_fab2(sch_1):page166_i46@mstr_discrete.res~
(chips)',
 P_PATH='@baseboard_fab2_lib.baseboard_fab2(sch_1):page166_i46@mstr_discrete.res~
(chips)',
 PATH='I46',
 DRAWING='@BASEBOARD_FAB2_LIB.BASEBOARD_FAB2(SCH_1):PAGE166',
 WATTAGE='1/16W',
 TOLERANCE='1%',
 SEC_TYPE='0402',
 MATERIAL='EMPTY',
 BOM_COST='SYS_CLOCK',
 PHYS_PAGE='166',
 XY='(-2400,3150)',
 ROT='0',
 VER='2',
 VALUE='10.0K',
 PACK_TYPE='0402',
 PART_NUMBER='G21796-016',
 LOCATION='R7W3',
 ROOM='DB1200ZL',
 SEC='1',
 CDS_LIB='mstr_discrete',
 CDS_PART_NAME='RES_0402-10.0K,1%,1/16W,EMPTY,A',
 PRIM_FILE='./archive_libs/mstr_discrete/res/chips/chips.prt';

PART_NAME
 R7W4 'RES_0402-49.9,1%,1/16W,EMPTY,GA':
 ROOM='SB';

SECTION_NUMBER 1
 '@BASEBOARD_FAB2_LIB.BASEBOARD_FAB2(SCH_1):PAGE92_I106@MSTR_DISCRETE.RES(CHIPS)':
 C_PATH='@baseboard_fab2_lib.baseboard_fab2(sch_1):page92_i106@mstr_discrete.res~
(chips)',
 P_PATH='@baseboard_fab2_lib.baseboard_fab2(sch_1):page92_i106@mstr_discrete.res~
(chips)',
 PATH='I106',
 DRAWING='@BASEBOARD_FAB2_LIB.BASEBOARD_FAB2(SCH_1):PAGE92',
 WATTAGE='1/16W',
 TOLERANCE='1%',
 SEC_TYPE='0402',
 MATERIAL='EMPTY',
 PHYS_PAGE='92',
 XY='(-100,3050)',
 ROT='0',
 VER='2',
 VALUE='49.9',
 PACK_TYPE='0402',
 PART_NUMBER='G21796-047',
 LOCATION='R7W4',
 ROOM='SB',
 SEC='1',
 CDS_LIB='mstr_discrete',
 CDS_PART_NAME='RES_0402-49.9,1%,1/16W,EMPTY,GA',
 PRIM_FILE='./archive_libs/mstr_discrete/res/chips/chips.prt';

PART_NAME
 R7W5 'RES_0402-0.0,5%,1/16W,CHIP,G21A':
 ROOM='MIO_BIOS_MEM';

SECTION_NUMBER 1
 '@BASEBOARD_FAB2_LIB.BASEBOARD_FAB2(SCH_1):PAGE153_I187@MSTR_DISCRETE.RES(CHIPS)':
 C_PATH='@baseboard_fab2_lib.baseboard_fab2(sch_1):page153_i187@mstr_discrete.re~
s(chips)',
 P_PATH='@baseboard_fab2_lib.baseboard_fab2(sch_1):page153_i187@mstr_discrete.re~
s(chips)',
 PATH='I187',
 DRAWING='@BASEBOARD_FAB2_LIB.BASEBOARD_FAB2(SCH_1):PAGE153',
 WATTAGE='1/16W',
 TOLERANCE='5%',
 MATERIAL='CHIP',
 PHYS_PAGE='153',
 XY='(-6550,3625)',
 ROT='0',
 VER='1',
 VALUE='0.0',
 PACK_TYPE='0402',
 PART_NUMBER='G21497-005',
 LOCATION='R7W5',
 ROOM='MIO_BIOS_MEM',
 CDS_LIB='mstr_discrete',
 CDS_PART_NAME='RES_0402-0.0,5%,1/16W,CHIP,G21A',
 PRIM_FILE='./archive_libs/mstr_discrete/res/chips/chips.prt';

PART_NAME
 R7W6 'RES_0402-0.0,5%,1/16W,CHIP,G21A':
 ROOM='SB';

SECTION_NUMBER 1
 '@BASEBOARD_FAB2_LIB.BASEBOARD_FAB2(SCH_1):PAGE118_I176@MSTR_DISCRETE.RES(CHIPS)':
 C_PATH='@baseboard_fab2_lib.baseboard_fab2(sch_1):page118_i176@mstr_discrete.re~
s(chips)',
 P_PATH='@baseboard_fab2_lib.baseboard_fab2(sch_1):page118_i176@mstr_discrete.re~
s(chips)',
 PATH='I176',
 DRAWING='@BASEBOARD_FAB2_LIB.BASEBOARD_FAB2(SCH_1):PAGE118',
 POP='NOPOP',
 WATTAGE='1/16W',
 TOLERANCE='5%',
 SEC_TYPE='0402',
 MATERIAL='CHIP',
 BOM_COST='SB',
 PHYS_PAGE='118',
 XY='(-6650,4225)',
 ROT='0',
 VER='1',
 VALUE='0.0',
 PACK_TYPE='0402',
 PART_NUMBER='G21497-005',
 LOCATION='R7W6',
 ROOM='SB',
 SEC='1',
 CDS_LIB='mstr_discrete',
 CDS_PART_NAME='RES_0402-0.0,5%,1/16W,CHIP,G21A',
 PRIM_FILE='./archive_libs/mstr_discrete/res/chips/chips.prt';

PART_NAME
 R7W8 'RES_0402-0.0,5%,1/16W,CHIP,G21A':
 ROOM='CPU0';

SECTION_NUMBER 1
 '@BASEBOARD_FAB2_LIB.BASEBOARD_FAB2(SCH_1):PAGE120_I269@MSTR_DISCRETE.RES(CHIPS)':
 C_PATH='@baseboard_fab2_lib.baseboard_fab2(sch_1):page120_i269@mstr_discrete.re~
s(chips)',
 P_PATH='@baseboard_fab2_lib.baseboard_fab2(sch_1):page120_i269@mstr_discrete.re~
s(chips)',
 PATH='I269',
 DRAWING='@BASEBOARD_FAB2_LIB.BASEBOARD_FAB2(SCH_1):PAGE120',
 WATTAGE='1/16W',
 TOLERANCE='5%',
 SEC_TYPE='0402',
 MATERIAL='CHIP',
 BOM_COST='PROC_SIDEBAND',
 PHYS_PAGE='120',
 XY='(-6650,3800)',
 ROT='0',
 VER='1',
 VALUE='0.0',
 PACK_TYPE='0402',
 PART_NUMBER='G21497-005',
 LOCATION='R7W8',
 ROOM='CPU0',
 SEC='1',
 CDS_LIB='mstr_discrete',
 CDS_PART_NAME='RES_0402-0.0,5%,1/16W,CHIP,G21A',
 PRIM_FILE='./archive_libs/mstr_discrete/res/chips/chips.prt';

PART_NAME
 R7W9 'RES_0402-0.0,5%,1/16W,CHIP,G21A':
 ROOM='SB';

SECTION_NUMBER 1
 '@BASEBOARD_FAB2_LIB.BASEBOARD_FAB2(SCH_1):PAGE118_I177@MSTR_DISCRETE.RES(CHIPS)':
 C_PATH='@baseboard_fab2_lib.baseboard_fab2(sch_1):page118_i177@mstr_discrete.re~
s(chips)',
 P_PATH='@baseboard_fab2_lib.baseboard_fab2(sch_1):page118_i177@mstr_discrete.re~
s(chips)',
 PATH='I177',
 DRAWING='@BASEBOARD_FAB2_LIB.BASEBOARD_FAB2(SCH_1):PAGE118',
 POP='NOPOP',
 WATTAGE='1/16W',
 TOLERANCE='5%',
 SEC_TYPE='0402',
 MATERIAL='CHIP',
 BOM_COST='SB',
 PHYS_PAGE='118',
 XY='(-6650,4375)',
 ROT='0',
 VER='1',
 VALUE='0.0',
 PACK_TYPE='0402',
 PART_NUMBER='G21497-005',
 LOCATION='R7W9',
 ROOM='SB',
 SEC='1',
 CDS_LIB='mstr_discrete',
 CDS_PART_NAME='RES_0402-0.0,5%,1/16W,CHIP,G21A',
 PRIM_FILE='./archive_libs/mstr_discrete/res/chips/chips.prt';

PART_NAME
 R7W10 'RES_0402-0.0,5%,1/16W,CHIP,G21A':
 ROOM='CPU0';

SECTION_NUMBER 1
 '@BASEBOARD_FAB2_LIB.BASEBOARD_FAB2(SCH_1):PAGE120_I270@MSTR_DISCRETE.RES(CHIPS)':
 C_PATH='@baseboard_fab2_lib.baseboard_fab2(sch_1):page120_i270@mstr_discrete.re~
s(chips)',
 P_PATH='@baseboard_fab2_lib.baseboard_fab2(sch_1):page120_i270@mstr_discrete.re~
s(chips)',
 PATH='I270',
 DRAWING='@BASEBOARD_FAB2_LIB.BASEBOARD_FAB2(SCH_1):PAGE120',
 WATTAGE='1/16W',
 TOLERANCE='5%',
 SEC_TYPE='0402',
 MATERIAL='CHIP',
 BOM_COST='PROC_SIDEBAND',
 PHYS_PAGE='120',
 XY='(-6200,3700)',
 ROT='0',
 VER='1',
 VALUE='0.0',
 PACK_TYPE='0402',
 PART_NUMBER='G21497-005',
 LOCATION='R7W10',
 ROOM='CPU0',
 SEC='1',
 CDS_LIB='mstr_discrete',
 CDS_PART_NAME='RES_0402-0.0,5%,1/16W,CHIP,G21A',
 PRIM_FILE='./archive_libs/mstr_discrete/res/chips/chips.prt';

PART_NAME
 R7W11 'RES_0402-0.0,5%,1/16W,CHIP,G21A':
 ROOM='CPU0';

SECTION_NUMBER 1
 '@BASEBOARD_FAB2_LIB.BASEBOARD_FAB2(SCH_1):PAGE120_I273@MSTR_DISCRETE.RES(CHIPS)':
 C_PATH='@baseboard_fab2_lib.baseboard_fab2(sch_1):page120_i273@mstr_discrete.re~
s(chips)',
 P_PATH='@baseboard_fab2_lib.baseboard_fab2(sch_1):page120_i273@mstr_discrete.re~
s(chips)',
 PATH='I273',
 DRAWING='@BASEBOARD_FAB2_LIB.BASEBOARD_FAB2(SCH_1):PAGE120',
 WATTAGE='1/16W',
 TOLERANCE='5%',
 SEC_TYPE='0402',
 MATERIAL='CHIP',
 BOM_COST='PROC_SIDEBAND',
 PHYS_PAGE='120',
 XY='(-950,2800)',
 ROT='0',
 VER='1',
 VALUE='0.0',
 PACK_TYPE='0402',
 PART_NUMBER='G21497-005',
 LOCATION='R7W11',
 ROOM='CPU0',
 SEC='1',
 CDS_LIB='mstr_discrete',
 CDS_PART_NAME='RES_0402-0.0,5%,1/16W,CHIP,G21A',
 PRIM_FILE='./archive_libs/mstr_discrete/res/chips/chips.prt';

PART_NAME
 R7W12 'RES_0402-0.0,5%,1/16W,CHIP,G21A':
 ROOM='CPU0';

SECTION_NUMBER 1
 '@BASEBOARD_FAB2_LIB.BASEBOARD_FAB2(SCH_1):PAGE120_I271@MSTR_DISCRETE.RES(CHIPS)':
 C_PATH='@baseboard_fab2_lib.baseboard_fab2(sch_1):page120_i271@mstr_discrete.re~
s(chips)',
 P_PATH='@baseboard_fab2_lib.baseboard_fab2(sch_1):page120_i271@mstr_discrete.re~
s(chips)',
 PATH='I271',
 DRAWING='@BASEBOARD_FAB2_LIB.BASEBOARD_FAB2(SCH_1):PAGE120',
 WATTAGE='1/16W',
 TOLERANCE='5%',
 SEC_TYPE='0402',
 MATERIAL='CHIP',
 BOM_COST='PROC_SIDEBAND',
 PHYS_PAGE='120',
 XY='(-6400,3750)',
 ROT='0',
 VER='1',
 VALUE='0.0',
 PACK_TYPE='0402',
 PART_NUMBER='G21497-005',
 LOCATION='R7W12',
 ROOM='CPU0',
 SEC='1',
 CDS_LIB='mstr_discrete',
 CDS_PART_NAME='RES_0402-0.0,5%,1/16W,CHIP,G21A',
 PRIM_FILE='./archive_libs/mstr_discrete/res/chips/chips.prt';

PART_NAME
 R7W13 'RES_0402-0.0,5%,1/16W,CHIP,G21A':
 ROOM='CPU0';

SECTION_NUMBER 1
 '@BASEBOARD_FAB2_LIB.BASEBOARD_FAB2(SCH_1):PAGE119_I226@MSTR_DISCRETE.RES(CHIPS)':
 C_PATH='@baseboard_fab2_lib.baseboard_fab2(sch_1):page119_i226@mstr_discrete.re~
s(chips)',
 P_PATH='@baseboard_fab2_lib.baseboard_fab2(sch_1):page119_i226@mstr_discrete.re~
s(chips)',
 PATH='I226',
 DRAWING='@BASEBOARD_FAB2_LIB.BASEBOARD_FAB2(SCH_1):PAGE119',
 WATTAGE='1/16W',
 TOLERANCE='5%',
 SEC_TYPE='0402',
 MATERIAL='CHIP',
 BOM_COST='PROC_SIDEBAND',
 PHYS_PAGE='119',
 XY='(-6950,4400)',
 ROT='0',
 VER='1',
 VALUE='0.0',
 PACK_TYPE='0402',
 PART_NUMBER='G21497-005',
 LOCATION='R7W13',
 ROOM='CPU0',
 SEC='1',
 CDS_LIB='mstr_discrete',
 CDS_PART_NAME='RES_0402-0.0,5%,1/16W,CHIP,G21A',
 PRIM_FILE='./archive_libs/mstr_discrete/res/chips/chips.prt';

PART_NAME
 R7W14 'RES_0402-0.0,5%,1/16W,CHIP,G21A':
 ROOM='CPU0';

SECTION_NUMBER 1
 '@BASEBOARD_FAB2_LIB.BASEBOARD_FAB2(SCH_1):PAGE120_I274@MSTR_DISCRETE.RES(CHIPS)':
 C_PATH='@baseboard_fab2_lib.baseboard_fab2(sch_1):page120_i274@mstr_discrete.re~
s(chips)',
 P_PATH='@baseboard_fab2_lib.baseboard_fab2(sch_1):page120_i274@mstr_discrete.re~
s(chips)',
 PATH='I274',
 DRAWING='@BASEBOARD_FAB2_LIB.BASEBOARD_FAB2(SCH_1):PAGE120',
 WATTAGE='1/16W',
 TOLERANCE='5%',
 SEC_TYPE='0402',
 MATERIAL='CHIP',
 BOM_COST='PROC_SIDEBAND',
 PHYS_PAGE='120',
 XY='(-6775,2650)',
 ROT='0',
 VER='1',
 VALUE='0.0',
 PACK_TYPE='0402',
 PART_NUMBER='G21497-005',
 LOCATION='R7W14',
 ROOM='CPU0',
 SEC='1',
 CDS_LIB='mstr_discrete',
 CDS_PART_NAME='RES_0402-0.0,5%,1/16W,CHIP,G21A',
 PRIM_FILE='./archive_libs/mstr_discrete/res/chips/chips.prt';

PART_NAME
 R7W15 'RES_0402-0.0,5%,1/16W,CHIP,G21A':
 ROOM='CPU0';

SECTION_NUMBER 1
 '@BASEBOARD_FAB2_LIB.BASEBOARD_FAB2(SCH_1):PAGE119_I227@MSTR_DISCRETE.RES(CHIPS)':
 C_PATH='@baseboard_fab2_lib.baseboard_fab2(sch_1):page119_i227@mstr_discrete.re~
s(chips)',
 P_PATH='@baseboard_fab2_lib.baseboard_fab2(sch_1):page119_i227@mstr_discrete.re~
s(chips)',
 PATH='I227',
 DRAWING='@BASEBOARD_FAB2_LIB.BASEBOARD_FAB2(SCH_1):PAGE119',
 POP='NOPOP',
 WATTAGE='1/16W',
 TOLERANCE='5%',
 SEC_TYPE='0402',
 MATERIAL='CHIP',
 BOM_COST='PROC_SIDEBAND',
 PHYS_PAGE='119',
 XY='(-6700,4300)',
 ROT='0',
 VER='1',
 VALUE='0.0',
 PACK_TYPE='0402',
 PART_NUMBER='G21497-005',
 LOCATION='R7W15',
 ROOM='CPU0',
 SEC='1',
 CDS_LIB='mstr_discrete',
 CDS_PART_NAME='RES_0402-0.0,5%,1/16W,CHIP,G21A',
 PRIM_FILE='./archive_libs/mstr_discrete/res/chips/chips.prt';

PART_NAME
 R7W16 'RES_0402-0.0,5%,1/16W,CHIP,G21A':
 ROOM='CPU0';

SECTION_NUMBER 1
 '@BASEBOARD_FAB2_LIB.BASEBOARD_FAB2(SCH_1):PAGE120_I276@MSTR_DISCRETE.RES(CHIPS)':
 C_PATH='@baseboard_fab2_lib.baseboard_fab2(sch_1):page120_i276@mstr_discrete.re~
s(chips)',
 P_PATH='@baseboard_fab2_lib.baseboard_fab2(sch_1):page120_i276@mstr_discrete.re~
s(chips)',
 PATH='I276',
 DRAWING='@BASEBOARD_FAB2_LIB.BASEBOARD_FAB2(SCH_1):PAGE120',
 WATTAGE='1/16W',
 TOLERANCE='5%',
 SEC_TYPE='0402',
 MATERIAL='CHIP',
 BOM_COST='PROC_SIDEBAND',
 PHYS_PAGE='120',
 XY='(-950,2700)',
 ROT='0',
 VER='1',
 VALUE='0.0',
 PACK_TYPE='0402',
 PART_NUMBER='G21497-005',
 LOCATION='R7W16',
 ROOM='CPU0',
 SEC='1',
 CDS_LIB='mstr_discrete',
 CDS_PART_NAME='RES_0402-0.0,5%,1/16W,CHIP,G21A',
 PRIM_FILE='./archive_libs/mstr_discrete/res/chips/chips.prt';

PART_NAME
 R7W17 'RES_0402-0.0,5%,1/16W,CHIP,G21A':
 ROOM='CPU0';

SECTION_NUMBER 1
 '@BASEBOARD_FAB2_LIB.BASEBOARD_FAB2(SCH_1):PAGE119_I229@MSTR_DISCRETE.RES(CHIPS)':
 C_PATH='@baseboard_fab2_lib.baseboard_fab2(sch_1):page119_i229@mstr_discrete.re~
s(chips)',
 P_PATH='@baseboard_fab2_lib.baseboard_fab2(sch_1):page119_i229@mstr_discrete.re~
s(chips)',
 PATH='I229',
 DRAWING='@BASEBOARD_FAB2_LIB.BASEBOARD_FAB2(SCH_1):PAGE119',
 WATTAGE='1/16W',
 TOLERANCE='5%',
 SEC_TYPE='0402',
 MATERIAL='CHIP',
 BOM_COST='PROC_SIDEBAND',
 PHYS_PAGE='119',
 XY='(-1550,4250)',
 ROT='0',
 VER='1',
 VALUE='0.0',
 PACK_TYPE='0402',
 PART_NUMBER='G21497-005',
 LOCATION='R7W17',
 ROOM='CPU0',
 SEC='1',
 CDS_LIB='mstr_discrete',
 CDS_PART_NAME='RES_0402-0.0,5%,1/16W,CHIP,G21A',
 PRIM_FILE='./archive_libs/mstr_discrete/res/chips/chips.prt';

PART_NAME
 R7W18 'RES_0402-0.0,5%,1/16W,CHIP,G21A':
 ROOM='CPU0';

SECTION_NUMBER 1
 '@BASEBOARD_FAB2_LIB.BASEBOARD_FAB2(SCH_1):PAGE120_I277@MSTR_DISCRETE.RES(CHIPS)':
 C_PATH='@baseboard_fab2_lib.baseboard_fab2(sch_1):page120_i277@mstr_discrete.re~
s(chips)',
 P_PATH='@baseboard_fab2_lib.baseboard_fab2(sch_1):page120_i277@mstr_discrete.re~
s(chips)',
 PATH='I277',
 DRAWING='@BASEBOARD_FAB2_LIB.BASEBOARD_FAB2(SCH_1):PAGE120',
 WATTAGE='1/16W',
 TOLERANCE='5%',
 SEC_TYPE='0402',
 MATERIAL='CHIP',
 BOM_COST='PROC_SIDEBAND',
 PHYS_PAGE='120',
 XY='(-6850,3050)',
 ROT='0',
 VER='1',
 VALUE='0.0',
 PACK_TYPE='0402',
 PART_NUMBER='G21497-005',
 LOCATION='R7W18',
 ROOM='CPU0',
 SEC='1',
 CDS_LIB='mstr_discrete',
 CDS_PART_NAME='RES_0402-0.0,5%,1/16W,CHIP,G21A',
 PRIM_FILE='./archive_libs/mstr_discrete/res/chips/chips.prt';

PART_NAME
 R7W19 'RES_0402-4.75K,1%,1/16W,CHIP,GA':
 ROOM='CPU0';

SECTION_NUMBER 1
 '@BASEBOARD_FAB2_LIB.BASEBOARD_FAB2(SCH_1):PAGE118_I180@MSTR_DISCRETE.RES(CHIPS)':
 C_PATH='@baseboard_fab2_lib.baseboard_fab2(sch_1):page118_i180@mstr_discrete.re~
s(chips)',
 P_PATH='@baseboard_fab2_lib.baseboard_fab2(sch_1):page118_i180@mstr_discrete.re~
s(chips)',
 PATH='I180',
 DRAWING='@BASEBOARD_FAB2_LIB.BASEBOARD_FAB2(SCH_1):PAGE118',
 WATTAGE='1/16W',
 TOLERANCE='1%',
 SEC_TYPE='0402',
 MATERIAL='CHIP',
 PHYS_PAGE='118',
 XY='(-6450,4600)',
 ROT='0',
 VER='2',
 VALUE='4.75K',
 PACK_TYPE='0402',
 PART_NUMBER='G21796-072',
 LOCATION='R7W19',
 ROOM='CPU0',
 SEC='1',
 CDS_LIB='mstr_discrete',
 CDS_PART_NAME='RES_0402-4.75K,1%,1/16W,CHIP,GA',
 PRIM_FILE='./archive_libs/mstr_discrete/res/chips/chips.prt';

PART_NAME
 R7W20 'RES_0402-4.75K,1%,1/16W,CHIP,GA':
 ROOM='CPU0';

SECTION_NUMBER 1
 '@BASEBOARD_FAB2_LIB.BASEBOARD_FAB2(SCH_1):PAGE120_I278@MSTR_DISCRETE.RES(CHIPS)':
 C_PATH='@baseboard_fab2_lib.baseboard_fab2(sch_1):page120_i278@mstr_discrete.re~
s(chips)',
 P_PATH='@baseboard_fab2_lib.baseboard_fab2(sch_1):page120_i278@mstr_discrete.re~
s(chips)',
 PATH='I278',
 DRAWING='@BASEBOARD_FAB2_LIB.BASEBOARD_FAB2(SCH_1):PAGE120',
 POP='NOPOP',
 WATTAGE='1/16W',
 TOLERANCE='1%',
 SEC_TYPE='0402',
 MATERIAL='CHIP',
 PHYS_PAGE='120',
 XY='(-6500,4500)',
 ROT='0',
 VER='2',
 VALUE='4.75K',
 PACK_TYPE='0402',
 PART_NUMBER='G21796-072',
 LOCATION='R7W20',
 ROOM='CPU0',
 SEC='1',
 CDS_LIB='mstr_discrete',
 CDS_PART_NAME='RES_0402-4.75K,1%,1/16W,CHIP,GA',
 PRIM_FILE='./archive_libs/mstr_discrete/res/chips/chips.prt';

PART_NAME
 R7W21 'RES_0402-4.75K,1%,1/16W,CHIP,GA':
 ROOM='CPU0';

SECTION_NUMBER 1
 '@BASEBOARD_FAB2_LIB.BASEBOARD_FAB2(SCH_1):PAGE118_I183@MSTR_DISCRETE.RES(CHIPS)':
 C_PATH='@baseboard_fab2_lib.baseboard_fab2(sch_1):page118_i183@mstr_discrete.re~
s(chips)',
 P_PATH='@baseboard_fab2_lib.baseboard_fab2(sch_1):page118_i183@mstr_discrete.re~
s(chips)',
 PATH='I183',
 DRAWING='@BASEBOARD_FAB2_LIB.BASEBOARD_FAB2(SCH_1):PAGE118',
 WATTAGE='1/16W',
 TOLERANCE='1%',
 SEC_TYPE='0402',
 MATERIAL='CHIP',
 PHYS_PAGE='118',
 XY='(-6200,4600)',
 ROT='0',
 VER='2',
 VALUE='4.75K',
 PACK_TYPE='0402',
 PART_NUMBER='G21796-072',
 LOCATION='R7W21',
 ROOM='CPU0',
 SEC='1',
 CDS_LIB='mstr_discrete',
 CDS_PART_NAME='RES_0402-4.75K,1%,1/16W,CHIP,GA',
 PRIM_FILE='./archive_libs/mstr_discrete/res/chips/chips.prt';

PART_NAME
 R7W22 'RES_0402-4.75K,1%,1/16W,CHIP,GA':
 ROOM='CPU0';

SECTION_NUMBER 1
 '@BASEBOARD_FAB2_LIB.BASEBOARD_FAB2(SCH_1):PAGE119_I230@MSTR_DISCRETE.RES(CHIPS)':
 C_PATH='@baseboard_fab2_lib.baseboard_fab2(sch_1):page119_i230@mstr_discrete.re~
s(chips)',
 P_PATH='@baseboard_fab2_lib.baseboard_fab2(sch_1):page119_i230@mstr_discrete.re~
s(chips)',
 PATH='I230',
 DRAWING='@BASEBOARD_FAB2_LIB.BASEBOARD_FAB2(SCH_1):PAGE119',
 POP='NOPOP',
 WATTAGE='1/16W',
 TOLERANCE='1%',
 SEC_TYPE='0402',
 MATERIAL='CHIP',
 PHYS_PAGE='119',
 XY='(-1700,1600)',
 ROT='0',
 VER='2',
 VALUE='4.75K',
 PACK_TYPE='0402',
 PART_NUMBER='G21796-072',
 LOCATION='R7W22',
 ROOM='CPU0',
 SEC='1',
 CDS_LIB='mstr_discrete',
 CDS_PART_NAME='RES_0402-4.75K,1%,1/16W,CHIP,GA',
 PRIM_FILE='./archive_libs/mstr_discrete/res/chips/chips.prt';

PART_NAME
 R8A1 'RES_0402-10.0,1%,1/16W,CHIP,G2A':
 ROOM='PVNN_PCH_STBY',
 NO_XNET_CONNECTION='1';

SECTION_NUMBER 1
 '@BASEBOARD_FAB2_LIB.BASEBOARD_FAB2(SCH_1):PAGE235_I210@MSTR_DISCRETE.RES(CHIPS)':
 C_PATH='@baseboard_fab2_lib.baseboard_fab2(sch_1):page235_i210@mstr_discrete.re~
s(chips)',
 P_PATH='@baseboard_fab2_lib.baseboard_fab2(sch_1):page235_i210@mstr_discrete.re~
s(chips)',
 PATH='I210',
 DRAWING='@BASEBOARD_FAB2_LIB.BASEBOARD_FAB2(SCH_1):PAGE235',
 WATTAGE='1/16W',
 TOLERANCE='1%',
 SEC_TYPE='0402',
 MATERIAL='CHIP',
 NO_XNET_CONNECTION='1',
 PHYS_PAGE='235',
 XY='(-12675,2750)',
 ROT='0',
 VER='1',
 VALUE='10.0',
 PACK_TYPE='0402',
 PART_NUMBER='G21796-066',
 LOCATION='R8A1',
 ROOM='PVNN_PCH_STBY',
 SEC='1',
 CDS_LIB='mstr_discrete',
 CDS_PART_NAME='RES_0402-10.0,1%,1/16W,CHIP,G2A',
 PRIM_FILE='./archive_libs/mstr_discrete/res/chips/chips.prt';

PART_NAME
 R8A2 'RES_0402-2.67K,1%,1/16W,CHIP,GA':;

SECTION_NUMBER 1
 '@BASEBOARD_FAB2_LIB.BASEBOARD_FAB2(SCH_1):PAGE235_I217@MSTR_DISCRETE.RES(CHIPS)':
 C_PATH='@baseboard_fab2_lib.baseboard_fab2(sch_1):page235_i217@mstr_discrete.re~
s(chips)',
 P_PATH='@baseboard_fab2_lib.baseboard_fab2(sch_1):page235_i217@mstr_discrete.re~
s(chips)',
 PATH='I217',
 DRAWING='@BASEBOARD_FAB2_LIB.BASEBOARD_FAB2(SCH_1):PAGE235',
 WATTAGE='1/16W',
 TOLERANCE='1%',
 SEC_TYPE='0402',
 MATERIAL='CHIP',
 PHYS_PAGE='235',
 XY='(-10450,2150)',
 ROT='0',
 VER='2',
 VALUE='2.67K',
 PACK_TYPE='0402',
 PART_NUMBER='G21796-180',
 LOCATION='R8A2',
 SEC='1',
 CDS_LIB='mstr_discrete',
 CDS_PART_NAME='RES_0402-2.67K,1%,1/16W,CHIP,GA',
 PRIM_FILE='./archive_libs/mstr_discrete/res/chips/chips.prt';

PART_NAME
 R8A4 'RES_0402-100.0K,1%,1/16W,CHIP,B':
 ROOM='PVNN_PCH_STBY';

SECTION_NUMBER 1
 '@BASEBOARD_FAB2_LIB.BASEBOARD_FAB2(SCH_1):PAGE235_I165@MSTR_DISCRETE.RES(CHIPS)':
 C_PATH='@baseboard_fab2_lib.baseboard_fab2(sch_1):page235_i165@mstr_discrete.re~
s(chips)',
 P_PATH='@baseboard_fab2_lib.baseboard_fab2(sch_1):page235_i165@mstr_discrete.re~
s(chips)',
 PATH='I165',
 DRAWING='@BASEBOARD_FAB2_LIB.BASEBOARD_FAB2(SCH_1):PAGE235',
 WATTAGE='1/16W',
 TOLERANCE='1%',
 SEC_TYPE='0402',
 MATERIAL='CHIP',
 PHYS_PAGE='235',
 XY='(-12325,5500)',
 ROT='0',
 VER='2',
 VALUE='100.0K',
 PACK_TYPE='0402',
 PART_NUMBER='G21796-160',
 LOCATION='R8A4',
 ROOM='PVNN_PCH_STBY',
 SEC='1',
 CDS_LIB='mstr_discrete',
 CDS_PART_NAME='RES_0402-100.0K,1%,1/16W,CHIP,B',
 PRIM_FILE='./archive_libs/mstr_discrete/res/chips/chips.prt';

PART_NAME
 R8A5 'RES_0402-1.00K,1%,1/16W,CHIP,GA':;

SECTION_NUMBER 1
 '@BASEBOARD_FAB2_LIB.BASEBOARD_FAB2(SCH_1):PAGE235_I216@MSTR_DISCRETE.RES(CHIPS)':
 C_PATH='@baseboard_fab2_lib.baseboard_fab2(sch_1):page235_i216@mstr_discrete.re~
s(chips)',
 P_PATH='@baseboard_fab2_lib.baseboard_fab2(sch_1):page235_i216@mstr_discrete.re~
s(chips)',
 PATH='I216',
 DRAWING='@BASEBOARD_FAB2_LIB.BASEBOARD_FAB2(SCH_1):PAGE235',
 WATTAGE='1/16W',
 TOLERANCE='1%',
 SEC_TYPE='0402',
 MATERIAL='CHIP',
 PHYS_PAGE='235',
 XY='(-8075,4950)',
 ROT='0',
 VER='2',
 VALUE='1.00K',
 PACK_TYPE='0402',
 PART_NUMBER='G21796-026',
 LOCATION='R8A5',
 SEC='1',
 CDS_LIB='mstr_discrete',
 CDS_PART_NAME='RES_0402-1.00K,1%,1/16W,CHIP,GA',
 PRIM_FILE='./archive_libs/mstr_discrete/res/chips/chips.prt';

PART_NAME
 R8A6 'RES_0402-1.00K,1%,1/16W,CHIP,GA':
 ROOM='PVNN_PCH_STBY';

SECTION_NUMBER 1
 '@BASEBOARD_FAB2_LIB.BASEBOARD_FAB2(SCH_1):PAGE235_I149@MSTR_DISCRETE.RES(CHIPS)':
 C_PATH='@baseboard_fab2_lib.baseboard_fab2(sch_1):page235_i149@mstr_discrete.re~
s(chips)',
 P_PATH='@baseboard_fab2_lib.baseboard_fab2(sch_1):page235_i149@mstr_discrete.re~
s(chips)',
 PATH='I149',
 DRAWING='@BASEBOARD_FAB2_LIB.BASEBOARD_FAB2(SCH_1):PAGE235',
 WATTAGE='1/16W',
 TOLERANCE='1%',
 SEC_TYPE='0402',
 MATERIAL='CHIP',
 PHYS_PAGE='235',
 XY='(-9100,4950)',
 ROT='0',
 VER='2',
 VALUE='1.00K',
 PACK_TYPE='0402',
 PART_NUMBER='G21796-026',
 LOCATION='R8A6',
 ROOM='PVNN_PCH_STBY',
 SEC='1',
 CDS_LIB='mstr_discrete',
 CDS_PART_NAME='RES_0402-1.00K,1%,1/16W,CHIP,GA',
 PRIM_FILE='./archive_libs/mstr_discrete/res/chips/chips.prt';

PART_NAME
 R8A7 'RES_0402-100.0K,1%,1/16W,EMPTYA':
 ROOM='BMC';

SECTION_NUMBER 1
 '@BASEBOARD_FAB2_LIB.BASEBOARD_FAB2(SCH_1):PAGE235_I222@MSTR_DISCRETE.RES(CHIPS)':
 C_PATH='@baseboard_fab2_lib.baseboard_fab2(sch_1):page235_i222@mstr_discrete.re~
s(chips)',
 P_PATH='@baseboard_fab2_lib.baseboard_fab2(sch_1):page235_i222@mstr_discrete.re~
s(chips)',
 PATH='I222',
 DRAWING='@BASEBOARD_FAB2_LIB.BASEBOARD_FAB2(SCH_1):PAGE235',
 WATTAGE='1/16W',
 TOLERANCE='1%',
 SEC_TYPE='0402',
 MATERIAL='EMPTY',
 BOM_COST='SM_CONTROLLER',
 PHYS_PAGE='235',
 XY='(-11175,5075)',
 ROT='0',
 VER='2',
 VALUE='100.0K',
 PACK_TYPE='0402',
 PART_NUMBER='G21796-010',
 LOCATION='R8A7',
 ROOM='BMC',
 SEC='1',
 CDS_LIB='mstr_discrete',
 CDS_PART_NAME='RES_0402-100.0K,1%,1/16W,EMPTYA',
 PRIM_FILE='./archive_libs/mstr_discrete/res/chips/chips.prt';

PART_NAME
 R8A10 'RES_0402-5.11K,1%,1/16W,CHIP,GA':
 ROOM='P1V8_PCH_STBY_VR';

SECTION_NUMBER 1
 '@BASEBOARD_FAB2_LIB.BASEBOARD_FAB2(SCH_1):PAGE237_I3@MSTR_DISCRETE.RES(CHIPS)':
 C_PATH='@baseboard_fab2_lib.baseboard_fab2(sch_1):page237_i3@mstr_discrete.res(~
chips)',
 P_PATH='@baseboard_fab2_lib.baseboard_fab2(sch_1):page237_i3@mstr_discrete.res(~
chips)',
 PATH='I3',
 DRAWING='@BASEBOARD_FAB2_LIB.BASEBOARD_FAB2(SCH_1):PAGE237',
 WATTAGE='1/16W',
 TOLERANCE='1%',
 MATERIAL='CHIP',
 BOM_COST='P1V8_PCH_STBY_VR',
 PHYS_PAGE='237',
 XY='(1350,3875)',
 ROT='0',
 VER='2',
 VALUE='5.11K',
 PACK_TYPE='0402',
 PART_NUMBER='G21796-140',
 LOCATION='R8A10',
 ROOM='P1V8_PCH_STBY_VR',
 CDS_LIB='mstr_discrete',
 CDS_PART_NAME='RES_0402-5.11K,1%,1/16W,CHIP,GA',
 PRIM_FILE='./archive_libs/mstr_discrete/res/chips/chips.prt';

PART_NAME
 R8A11 'RES_0402-22.1,1.0%,1/16W,CHIP,A':
 ROOM='P1V8_PCH_STBY_VR';

SECTION_NUMBER 1
 '@BASEBOARD_FAB2_LIB.BASEBOARD_FAB2(SCH_1):PAGE237_I90@MSTR_DISCRETE.RES(CHIPS)':
 C_PATH='@baseboard_fab2_lib.baseboard_fab2(sch_1):page237_i90@mstr_discrete.res~
(chips)',
 P_PATH='@baseboard_fab2_lib.baseboard_fab2(sch_1):page237_i90@mstr_discrete.res~
(chips)',
 PATH='I90',
 DRAWING='@BASEBOARD_FAB2_LIB.BASEBOARD_FAB2(SCH_1):PAGE237',
 WATTAGE='1/16W',
 TOLERANCE='1.0%',
 SEC_TYPE='0402',
 MATERIAL='CHIP',
 PHYS_PAGE='237',
 XY='(2175,3650)',
 ROT='0',
 VER='1',
 VALUE='22.1',
 PACK_TYPE='0402',
 PART_NUMBER='G21796-250',
 LOCATION='R8A11',
 ROOM='P1V8_PCH_STBY_VR',
 SEC='1',
 CDS_LIB='mstr_discrete',
 CDS_PART_NAME='RES_0402-22.1,1.0%,1/16W,CHIP,A',
 PRIM_FILE='./archive_libs/mstr_discrete/res/chips/chips.prt';

PART_NAME
 R8A12 'RES_0603-475.0,1%,1/10W,CHIP,GA':
 ROOM='P1V8_PCH_STBY_VR';

SECTION_NUMBER 1
 '@BASEBOARD_FAB2_LIB.BASEBOARD_FAB2(SCH_1):PAGE237_I15@MSTR_DISCRETE.RES(CHIPS)':
 C_PATH='@baseboard_fab2_lib.baseboard_fab2(sch_1):page237_i15@mstr_discrete.res~
(chips)',
 P_PATH='@baseboard_fab2_lib.baseboard_fab2(sch_1):page237_i15@mstr_discrete.res~
(chips)',
 PATH='I15',
 DRAWING='@BASEBOARD_FAB2_LIB.BASEBOARD_FAB2(SCH_1):PAGE237',
 WATTAGE='1/10W',
 TOLERANCE='1%',
 SEC_TYPE='0603',
 MATERIAL='CHIP',
 BOM_COST='P1V8_PCH_STBY_VR',
 PHYS_PAGE='237',
 XY='(2800,2125)',
 ROT='0',
 VER='2',
 VALUE='475.0',
 PACK_TYPE='0603',
 PART_NUMBER='G22026-030',
 LOCATION='R8A12',
 ROOM='P1V8_PCH_STBY_VR',
 SEC='1',
 CDS_LIB='mstr_discrete',
 CDS_PART_NAME='RES_0603-475.0,1%,1/10W,CHIP,GA',
 PRIM_FILE='./archive_libs/mstr_discrete/res/chips/chips.prt';

PART_NAME
 R8A13 'RES_0402-150.0,1%,1/16W,CHIP,GA':
 ROOM='DEBUG';

SECTION_NUMBER 1
 '@BASEBOARD_FAB2_LIB.BASEBOARD_FAB2(SCH_1):PAGE112_I79@MSTR_DISCRETE.RES(CHIPS)':
 C_PATH='@baseboard_fab2_lib.baseboard_fab2(sch_1):page112_i79@mstr_discrete.res~
(chips)',
 P_PATH='@baseboard_fab2_lib.baseboard_fab2(sch_1):page112_i79@mstr_discrete.res~
(chips)',
 PATH='I79',
 DRAWING='@BASEBOARD_FAB2_LIB.BASEBOARD_FAB2(SCH_1):PAGE112',
 WATTAGE='1/16W',
 TOLERANCE='1%',
 SEC_TYPE='0402',
 MATERIAL='CHIP',
 PHYS_PAGE='112',
 XY='(-2325,4425)',
 ROT='0',
 VER='2',
 VALUE='150.0',
 PACK_TYPE='0402',
 PART_NUMBER='G21796-009',
 LOCATION='R8A13',
 ROOM='DEBUG',
 SEC='1',
 CDS_LIB='mstr_discrete',
 CDS_PART_NAME='RES_0402-150.0,1%,1/16W,CHIP,GA',
 PRIM_FILE='./archive_libs/mstr_discrete/res/chips/chips.prt';

PART_NAME
 R8A14 'RES_0402-150.0,1%,1/16W,CHIP,GA':
 ROOM='DEBUG';

SECTION_NUMBER 1
 '@BASEBOARD_FAB2_LIB.BASEBOARD_FAB2(SCH_1):PAGE112_I80@MSTR_DISCRETE.RES(CHIPS)':
 C_PATH='@baseboard_fab2_lib.baseboard_fab2(sch_1):page112_i80@mstr_discrete.res~
(chips)',
 P_PATH='@baseboard_fab2_lib.baseboard_fab2(sch_1):page112_i80@mstr_discrete.res~
(chips)',
 PATH='I80',
 DRAWING='@BASEBOARD_FAB2_LIB.BASEBOARD_FAB2(SCH_1):PAGE112',
 WATTAGE='1/16W',
 TOLERANCE='1%',
 SEC_TYPE='0402',
 MATERIAL='CHIP',
 PHYS_PAGE='112',
 XY='(-2700,4425)',
 ROT='0',
 VER='2',
 VALUE='150.0',
 PACK_TYPE='0402',
 PART_NUMBER='G21796-009',
 LOCATION='R8A14',
 ROOM='DEBUG',
 SEC='1',
 CDS_LIB='mstr_discrete',
 CDS_PART_NAME='RES_0402-150.0,1%,1/16W,CHIP,GA',
 PRIM_FILE='./archive_libs/mstr_discrete/res/chips/chips.prt';

PART_NAME
 R8B1 'RES_0402-51.1,1.0%,1/16W,CHIP,A':
 ROOM='DEBUG';

SECTION_NUMBER 1
 '@BASEBOARD_FAB2_LIB.BASEBOARD_FAB2(SCH_1):PAGE112_I95@MSTR_DISCRETE.RES(CHIPS)':
 C_PATH='@baseboard_fab2_lib.baseboard_fab2(sch_1):page112_i95@mstr_discrete.res~
(chips)',
 P_PATH='@baseboard_fab2_lib.baseboard_fab2(sch_1):page112_i95@mstr_discrete.res~
(chips)',
 PATH='I95',
 DRAWING='@BASEBOARD_FAB2_LIB.BASEBOARD_FAB2(SCH_1):PAGE112',
 WATTAGE='1/16W',
 TOLERANCE='1.0%',
 MATERIAL='CHIP',
 BOM_COST='DEBUG',
 PHYS_PAGE='112',
 XY='(-2700,3600)',
 ROT='0',
 VER='2',
 VALUE='51.1',
 PACK_TYPE='0402',
 PART_NUMBER='G21796-208',
 LOCATION='R8B1',
 ROOM='DEBUG',
 CDS_LIB='mstr_discrete',
 CDS_PART_NAME='RES_0402-51.1,1.0%,1/16W,CHIP,A',
 PRIM_FILE='./archive_libs/mstr_discrete/res/chips/chips.prt';

PART_NAME
 R8B2 'RES_0402-1.00K,1%,1/16W,CHIP,GA':
 ROOM='DEBUG';

SECTION_NUMBER 1
 '@BASEBOARD_FAB2_LIB.BASEBOARD_FAB2(SCH_1):PAGE112_I94@MSTR_DISCRETE.RES(CHIPS)':
 C_PATH='@baseboard_fab2_lib.baseboard_fab2(sch_1):page112_i94@mstr_discrete.res~
(chips)',
 P_PATH='@baseboard_fab2_lib.baseboard_fab2(sch_1):page112_i94@mstr_discrete.res~
(chips)',
 PATH='I94',
 DRAWING='@BASEBOARD_FAB2_LIB.BASEBOARD_FAB2(SCH_1):PAGE112',
 WATTAGE='1/16W',
 TOLERANCE='1%',
 SEC_TYPE='0402',
 MATERIAL='CHIP',
 BOM_COST='DEBUG',
 PHYS_PAGE='112',
 XY='(-2325,3600)',
 ROT='0',
 VER='2',
 VALUE='1.00K',
 PACK_TYPE='0402',
 PART_NUMBER='G21796-026',
 LOCATION='R8B2',
 ROOM='DEBUG',
 SEC='1',
 CDS_LIB='mstr_discrete',
 CDS_PART_NAME='RES_0402-1.00K,1%,1/16W,CHIP,GA',
 PRIM_FILE='./archive_libs/mstr_discrete/res/chips/chips.prt';

PART_NAME
 R8B3 'RES_0402-4.75K,1%,1/16W,CHIP,GA':
 ROOM='HFI',
 SIGNAL_MODEL='DEFAULT_RESISTOR_4750OHM_2_1';

SECTION_NUMBER 1
 '@BASEBOARD_FAB2_LIB.BASEBOARD_FAB2(SCH_1):PAGE91_I24@MSTR_DISCRETE.RES(CHIPS)':
 C_PATH='@baseboard_fab2_lib.baseboard_fab2(sch_1):page91_i24@mstr_discrete.res(~
chips)',
 P_PATH='@baseboard_fab2_lib.baseboard_fab2(sch_1):page91_i24@mstr_discrete.res(~
chips)',
 PATH='I24',
 DRAWING='@BASEBOARD_FAB2_LIB.BASEBOARD_FAB2(SCH_1):PAGE91',
 WATTAGE='1/16W',
 TOLERANCE='1%',
 SEC_TYPE='0402',
 MATERIAL='CHIP',
 PHYS_PAGE='91',
 XY='(-1875,3350)',
 ROT='2',
 VER='2',
 VALUE='4.75K',
 PACK_TYPE='0402',
 PART_NUMBER='G21796-072',
 LOCATION='R8B3',
 SIGNAL_MODEL='DEFAULT_RESISTOR_4750OHM_2_1',
 ROOM='HFI',
 SEC='1',
 CDS_LIB='mstr_discrete',
 CDS_PART_NAME='RES_0402-4.75K,1%,1/16W,CHIP,GA',
 PRIM_FILE='./archive_libs/mstr_discrete/res/chips/chips.prt';

PART_NAME
 R8B4 'RES_0402-100.0K,1%,1/16W,CHIP,A':
 ROOM='HOT_SWAP';

SECTION_NUMBER 1
 '@BASEBOARD_FAB2_LIB.BASEBOARD_FAB2(SCH_1):PAGE198_I83@MSTR_DISCRETE.RES(CHIPS)':
 C_PATH='@baseboard_fab2_lib.baseboard_fab2(sch_1):page198_i83@mstr_discrete.res~
(chips)',
 P_PATH='@baseboard_fab2_lib.baseboard_fab2(sch_1):page198_i83@mstr_discrete.res~
(chips)',
 PATH='I83',
 DRAWING='@BASEBOARD_FAB2_LIB.BASEBOARD_FAB2(SCH_1):PAGE198',
 WATTAGE='1/16W',
 TOLERANCE='1%',
 SEC_TYPE='0402',
 MATERIAL='CHIP',
 PHYS_PAGE='198',
 XY='(-6850,2625)',
 ROT='0',
 VER='2',
 VALUE='100.0K',
 PACK_TYPE='0402',
 PART_NUMBER='G21796-010',
 LOCATION='R8B4',
 ROOM='HOT_SWAP',
 SEC='1',
 CDS_LIB='mstr_discrete',
 CDS_PART_NAME='RES_0402-100.0K,1%,1/16W,CHIP,A',
 PRIM_FILE='./archive_libs/mstr_discrete/res/chips/chips.prt';

PART_NAME
 R8B5 'RES_0402-4.75K,1%,1/16W,CHIP,GA':
 ROOM='HFI',
 SIGNAL_MODEL='DEFAULT_RESISTOR_4750OHM_2_1';

SECTION_NUMBER 1
 '@BASEBOARD_FAB2_LIB.BASEBOARD_FAB2(SCH_1):PAGE91_I22@MSTR_DISCRETE.RES(CHIPS)':
 C_PATH='@baseboard_fab2_lib.baseboard_fab2(sch_1):page91_i22@mstr_discrete.res(~
chips)',
 P_PATH='@baseboard_fab2_lib.baseboard_fab2(sch_1):page91_i22@mstr_discrete.res(~
chips)',
 PATH='I22',
 DRAWING='@BASEBOARD_FAB2_LIB.BASEBOARD_FAB2(SCH_1):PAGE91',
 WATTAGE='1/16W',
 TOLERANCE='1%',
 SEC_TYPE='0402',
 MATERIAL='CHIP',
 PHYS_PAGE='91',
 XY='(-1500,3350)',
 ROT='2',
 VER='2',
 VALUE='4.75K',
 PACK_TYPE='0402',
 PART_NUMBER='G21796-072',
 LOCATION='R8B5',
 SIGNAL_MODEL='DEFAULT_RESISTOR_4750OHM_2_1',
 ROOM='HFI',
 SEC='1',
 CDS_LIB='mstr_discrete',
 CDS_PART_NAME='RES_0402-4.75K,1%,1/16W,CHIP,GA',
 PRIM_FILE='./archive_libs/mstr_discrete/res/chips/chips.prt';

PART_NAME
 R8B6 'RES_0402-1.8K,1%,1/16W,CHIP,G2A':
 ROOM='SMBUS_CPU0_STL';

SECTION_NUMBER 1
 '@BASEBOARD_FAB2_LIB.BASEBOARD_FAB2(SCH_1):PAGE91_I37@MSTR_DISCRETE.RES(CHIPS)':
 C_PATH='@baseboard_fab2_lib.baseboard_fab2(sch_1):page91_i37@mstr_discrete.res(~
chips)',
 P_PATH='@baseboard_fab2_lib.baseboard_fab2(sch_1):page91_i37@mstr_discrete.res(~
chips)',
 PATH='I37',
 DRAWING='@BASEBOARD_FAB2_LIB.BASEBOARD_FAB2(SCH_1):PAGE91',
 WATTAGE='1/16W',
 TOLERANCE='1%',
 SEC_TYPE='0402',
 MATERIAL='CHIP',
 PHYS_PAGE='91',
 XY='(2250,3375)',
 ROT='0',
 VER='2',
 VALUE='1.8K',
 PACK_TYPE='0402',
 PART_NUMBER='G21796-336',
 LOCATION='R8B6',
 ROOM='SMBUS_CPU0_STL',
 SEC='1',
 CDS_LIB='mstr_discrete',
 CDS_PART_NAME='RES_0402-1.8K,1%,1/16W,CHIP,G2A',
 PRIM_FILE='./archive_libs/mstr_discrete/res/chips/chips.prt';

PART_NAME
 R8B7 'RES_0402-1.8K,1%,1/16W,CHIP,G2A':
 ROOM='SMBUS_CPU0_STL';

SECTION_NUMBER 1
 '@BASEBOARD_FAB2_LIB.BASEBOARD_FAB2(SCH_1):PAGE91_I36@MSTR_DISCRETE.RES(CHIPS)':
 C_PATH='@baseboard_fab2_lib.baseboard_fab2(sch_1):page91_i36@mstr_discrete.res(~
chips)',
 P_PATH='@baseboard_fab2_lib.baseboard_fab2(sch_1):page91_i36@mstr_discrete.res(~
chips)',
 PATH='I36',
 DRAWING='@BASEBOARD_FAB2_LIB.BASEBOARD_FAB2(SCH_1):PAGE91',
 WATTAGE='1/16W',
 TOLERANCE='1%',
 SEC_TYPE='0402',
 MATERIAL='CHIP',
 PHYS_PAGE='91',
 XY='(1975,3375)',
 ROT='0',
 VER='2',
 VALUE='1.8K',
 PACK_TYPE='0402',
 PART_NUMBER='G21796-336',
 LOCATION='R8B7',
 ROOM='SMBUS_CPU0_STL',
 SEC='1',
 CDS_LIB='mstr_discrete',
 CDS_PART_NAME='RES_0402-1.8K,1%,1/16W,CHIP,G2A',
 PRIM_FILE='./archive_libs/mstr_discrete/res/chips/chips.prt';

PART_NAME
 R8B8 'RES_0402-4.75K,1%,1/16W,CHIP,GA':
 ROOM='HFI',
 SIGNAL_MODEL='DEFAULT_RESISTOR_4750OHM_2_1';

SECTION_NUMBER 1
 '@BASEBOARD_FAB2_LIB.BASEBOARD_FAB2(SCH_1):PAGE91_I14@MSTR_DISCRETE.RES(CHIPS)':
 C_PATH='@baseboard_fab2_lib.baseboard_fab2(sch_1):page91_i14@mstr_discrete.res(~
chips)',
 P_PATH='@baseboard_fab2_lib.baseboard_fab2(sch_1):page91_i14@mstr_discrete.res(~
chips)',
 PATH='I14',
 DRAWING='@BASEBOARD_FAB2_LIB.BASEBOARD_FAB2(SCH_1):PAGE91',
 WATTAGE='1/16W',
 TOLERANCE='1%',
 SEC_TYPE='0402',
 MATERIAL='CHIP',
 PHYS_PAGE='91',
 XY='(1250,3375)',
 ROT='0',
 VER='2',
 VALUE='4.75K',
 PACK_TYPE='0402',
 PART_NUMBER='G21796-072',
 LOCATION='R8B8',
 SIGNAL_MODEL='DEFAULT_RESISTOR_4750OHM_2_1',
 ROOM='HFI',
 SEC='1',
 CDS_LIB='mstr_discrete',
 CDS_PART_NAME='RES_0402-4.75K,1%,1/16W,CHIP,GA',
 PRIM_FILE='./archive_libs/mstr_discrete/res/chips/chips.prt';

PART_NAME
 R8B9 'RES_0402-113,1%,1/16W,CHIP,G21A':
 ROOM='SB';

SECTION_NUMBER 1
 '@BASEBOARD_FAB2_LIB.BASEBOARD_FAB2(SCH_1):PAGE115_I90@MSTR_DISCRETE.RES(CHIPS)':
 C_PATH='@baseboard_fab2_lib.baseboard_fab2(sch_1):page115_i90@mstr_discrete.res~
(chips)',
 P_PATH='@baseboard_fab2_lib.baseboard_fab2(sch_1):page115_i90@mstr_discrete.res~
(chips)',
 PATH='I90',
 DRAWING='@BASEBOARD_FAB2_LIB.BASEBOARD_FAB2(SCH_1):PAGE115',
 WATTAGE='1/16W',
 TOLERANCE='1%',
 SEC_TYPE='0402',
 MATERIAL='CHIP',
 PHYS_PAGE='115',
 XY='(-5750,1775)',
 ROT='0',
 VER='2',
 VALUE='113',
 PACK_TYPE='0402',
 PART_NUMBER='G21796-341',
 LOCATION='R8B9',
 ROOM='SB',
 SEC='1',
 CDS_LIB='mstr_discrete',
 CDS_PART_NAME='RES_0402-113,1%,1/16W,CHIP,G21A',
 PRIM_FILE='./archive_libs/mstr_discrete/res/chips/chips.prt';

PART_NAME
 R8B10 'RES_0402-4.75K,1%,1/16W,CHIP,GA':
 ROOM='HFI',
 SIGNAL_MODEL='DEFAULT_RESISTOR_4750OHM_2_1';

SECTION_NUMBER 1
 '@BASEBOARD_FAB2_LIB.BASEBOARD_FAB2(SCH_1):PAGE91_I16@MSTR_DISCRETE.RES(CHIPS)':
 C_PATH='@baseboard_fab2_lib.baseboard_fab2(sch_1):page91_i16@mstr_discrete.res(~
chips)',
 P_PATH='@baseboard_fab2_lib.baseboard_fab2(sch_1):page91_i16@mstr_discrete.res(~
chips)',
 PATH='I16',
 DRAWING='@BASEBOARD_FAB2_LIB.BASEBOARD_FAB2(SCH_1):PAGE91',
 WATTAGE='1/16W',
 TOLERANCE='1%',
 SEC_TYPE='0402',
 MATERIAL='CHIP',
 PHYS_PAGE='91',
 XY='(1000,3375)',
 ROT='0',
 VER='2',
 VALUE='4.75K',
 PACK_TYPE='0402',
 PART_NUMBER='G21796-072',
 LOCATION='R8B10',
 SIGNAL_MODEL='DEFAULT_RESISTOR_4750OHM_2_1',
 ROOM='HFI',
 SEC='1',
 CDS_LIB='mstr_discrete',
 CDS_PART_NAME='RES_0402-4.75K,1%,1/16W,CHIP,GA',
 PRIM_FILE='./archive_libs/mstr_discrete/res/chips/chips.prt';

PART_NAME
 R8B11 'RES_0402-1.8K,1%,1/16W,CHIP,G2A':
 ROOM='SMBUS_CPU0_STL';

SECTION_NUMBER 1
 '@BASEBOARD_FAB2_LIB.BASEBOARD_FAB2(SCH_1):PAGE91_I35@MSTR_DISCRETE.RES(CHIPS)':
 C_PATH='@baseboard_fab2_lib.baseboard_fab2(sch_1):page91_i35@mstr_discrete.res(~
chips)',
 P_PATH='@baseboard_fab2_lib.baseboard_fab2(sch_1):page91_i35@mstr_discrete.res(~
chips)',
 PATH='I35',
 DRAWING='@BASEBOARD_FAB2_LIB.BASEBOARD_FAB2(SCH_1):PAGE91',
 WATTAGE='1/16W',
 TOLERANCE='1%',
 SEC_TYPE='0402',
 MATERIAL='CHIP',
 PHYS_PAGE='91',
 XY='(1725,3375)',
 ROT='0',
 VER='2',
 VALUE='1.8K',
 PACK_TYPE='0402',
 PART_NUMBER='G21796-336',
 LOCATION='R8B11',
 ROOM='SMBUS_CPU0_STL',
 SEC='1',
 CDS_LIB='mstr_discrete',
 CDS_PART_NAME='RES_0402-1.8K,1%,1/16W,CHIP,G2A',
 PRIM_FILE='./archive_libs/mstr_discrete/res/chips/chips.prt';

PART_NAME
 R8B12 'RES_0402-0.0,5%,1/16W,CHIP,G21A':
 ROOM='P1V05_PCH_STBY';

SECTION_NUMBER 1
 '@BASEBOARD_FAB2_LIB.BASEBOARD_FAB2(SCH_1):PAGE236_I59@MSTR_DISCRETE.RES(CHIPS)':
 C_PATH='@baseboard_fab2_lib.baseboard_fab2(sch_1):page236_i59@mstr_discrete.res~
(chips)',
 P_PATH='@baseboard_fab2_lib.baseboard_fab2(sch_1):page236_i59@mstr_discrete.res~
(chips)',
 PATH='I59',
 DRAWING='@BASEBOARD_FAB2_LIB.BASEBOARD_FAB2(SCH_1):PAGE236',
 WATTAGE='1/16W',
 TOLERANCE='5%',
 SEC_TYPE='0402',
 MATERIAL='CHIP',
 BOM_COST='P1V05_PCH_STBY',
 PHYS_PAGE='236',
 XY='(7425,850)',
 ROT='0',
 VER='1',
 VALUE='0.0',
 PACK_TYPE='0402',
 PART_NUMBER='G21497-005',
 LOCATION='R8B12',
 ROOM='P1V05_PCH_STBY',
 SEC='1',
 CDS_LIB='mstr_discrete',
 CDS_PART_NAME='RES_0402-0.0,5%,1/16W,CHIP,G21A',
 PRIM_FILE='./archive_libs/mstr_discrete/res/chips/chips.prt';

PART_NAME
 R8B13 'RES_0402-1.8K,1%,1/16W,CHIP,G2A':
 ROOM='SMBUS_CPU0_STL';

SECTION_NUMBER 1
 '@BASEBOARD_FAB2_LIB.BASEBOARD_FAB2(SCH_1):PAGE91_I34@MSTR_DISCRETE.RES(CHIPS)':
 C_PATH='@baseboard_fab2_lib.baseboard_fab2(sch_1):page91_i34@mstr_discrete.res(~
chips)',
 P_PATH='@baseboard_fab2_lib.baseboard_fab2(sch_1):page91_i34@mstr_discrete.res(~
chips)',
 PATH='I34',
 DRAWING='@BASEBOARD_FAB2_LIB.BASEBOARD_FAB2(SCH_1):PAGE91',
 WATTAGE='1/16W',
 TOLERANCE='1%',
 SEC_TYPE='0402',
 MATERIAL='CHIP',
 PHYS_PAGE='91',
 XY='(1500,3375)',
 ROT='0',
 VER='2',
 VALUE='1.8K',
 PACK_TYPE='0402',
 PART_NUMBER='G21796-336',
 LOCATION='R8B13',
 ROOM='SMBUS_CPU0_STL',
 SEC='1',
 CDS_LIB='mstr_discrete',
 CDS_PART_NAME='RES_0402-1.8K,1%,1/16W,CHIP,G2A',
 PRIM_FILE='./archive_libs/mstr_discrete/res/chips/chips.prt';

PART_NAME
 R8B14 'RES_0402-0.0,5%,1/16W,CHIP,G21A':
 ROOM='P1V05_PCH_STBY';

SECTION_NUMBER 1
 '@BASEBOARD_FAB2_LIB.BASEBOARD_FAB2(SCH_1):PAGE236_I56@MSTR_DISCRETE.RES(CHIPS)':
 C_PATH='@baseboard_fab2_lib.baseboard_fab2(sch_1):page236_i56@mstr_discrete.res~
(chips)',
 P_PATH='@baseboard_fab2_lib.baseboard_fab2(sch_1):page236_i56@mstr_discrete.res~
(chips)',
 PATH='I56',
 DRAWING='@BASEBOARD_FAB2_LIB.BASEBOARD_FAB2(SCH_1):PAGE236',
 WATTAGE='1/16W',
 TOLERANCE='5%',
 SEC_TYPE='0402',
 MATERIAL='CHIP',
 BOM_COST='P1V05_PCH_STBY',
 PHYS_PAGE='236',
 XY='(7450,1300)',
 ROT='0',
 VER='1',
 VALUE='0.0',
 PACK_TYPE='0402',
 PART_NUMBER='G21497-005',
 LOCATION='R8B14',
 ROOM='P1V05_PCH_STBY',
 SEC='1',
 CDS_LIB='mstr_discrete',
 CDS_PART_NAME='RES_0402-0.0,5%,1/16W,CHIP,G21A',
 PRIM_FILE='./archive_libs/mstr_discrete/res/chips/chips.prt';

PART_NAME
 R8B15 'RES_0402-100.0,1%,1/16W,EMPTY,A':
 ROOM='P1V05_PCH_STBY',
 NO_XNET_CONNECTION='1';

SECTION_NUMBER 1
 '@BASEBOARD_FAB2_LIB.BASEBOARD_FAB2(SCH_1):PAGE236_I57@MSTR_DISCRETE.RES(CHIPS)':
 C_PATH='@baseboard_fab2_lib.baseboard_fab2(sch_1):page236_i57@mstr_discrete.res~
(chips)',
 P_PATH='@baseboard_fab2_lib.baseboard_fab2(sch_1):page236_i57@mstr_discrete.res~
(chips)',
 PATH='I57',
 DRAWING='@BASEBOARD_FAB2_LIB.BASEBOARD_FAB2(SCH_1):PAGE236',
 WATTAGE='1/16W',
 TOLERANCE='1%',
 SEC_TYPE='0402',
 MATERIAL='EMPTY',
 BOM_COST='P1V05_PCH_STBY',
 NO_XNET_CONNECTION='1',
 PHYS_PAGE='236',
 XY='(7175,1050)',
 ROT='0',
 VER='2',
 VALUE='100.0',
 PACK_TYPE='0402',
 PART_NUMBER='G21796-017',
 LOCATION='R8B15',
 ROOM='P1V05_PCH_STBY',
 SEC='1',
 CDS_LIB='mstr_discrete',
 CDS_PART_NAME='RES_0402-100.0,1%,1/16W,EMPTY,A',
 PRIM_FILE='./archive_libs/mstr_discrete/res/chips/chips.prt';

PART_NAME
 R8B16 'RES_0402-4.75K,1%,1/16W,CHIP,GA':
 ROOM='HFI',
 SIGNAL_MODEL='DEFAULT_RESISTOR_4750OHM_2_1';

SECTION_NUMBER 1
 '@BASEBOARD_FAB2_LIB.BASEBOARD_FAB2(SCH_1):PAGE91_I17@MSTR_DISCRETE.RES(CHIPS)':
 C_PATH='@baseboard_fab2_lib.baseboard_fab2(sch_1):page91_i17@mstr_discrete.res(~
chips)',
 P_PATH='@baseboard_fab2_lib.baseboard_fab2(sch_1):page91_i17@mstr_discrete.res(~
chips)',
 PATH='I17',
 DRAWING='@BASEBOARD_FAB2_LIB.BASEBOARD_FAB2(SCH_1):PAGE91',
 WATTAGE='1/16W',
 TOLERANCE='1%',
 SEC_TYPE='0402',
 MATERIAL='CHIP',
 PHYS_PAGE='91',
 XY='(750,3375)',
 ROT='0',
 VER='2',
 VALUE='4.75K',
 PACK_TYPE='0402',
 PART_NUMBER='G21796-072',
 LOCATION='R8B16',
 SIGNAL_MODEL='DEFAULT_RESISTOR_4750OHM_2_1',
 ROOM='HFI',
 SEC='1',
 CDS_LIB='mstr_discrete',
 CDS_PART_NAME='RES_0402-4.75K,1%,1/16W,CHIP,GA',
 PRIM_FILE='./archive_libs/mstr_discrete/res/chips/chips.prt';

PART_NAME
 R8B17 'RES_0402-4.75K,1%,1/16W,CHIP,GA':
 ROOM='HFI',
 SIGNAL_MODEL='DEFAULT_RESISTOR_4750OHM_2_1';

SECTION_NUMBER 1
 '@BASEBOARD_FAB2_LIB.BASEBOARD_FAB2(SCH_1):PAGE91_I18@MSTR_DISCRETE.RES(CHIPS)':
 C_PATH='@baseboard_fab2_lib.baseboard_fab2(sch_1):page91_i18@mstr_discrete.res(~
chips)',
 P_PATH='@baseboard_fab2_lib.baseboard_fab2(sch_1):page91_i18@mstr_discrete.res(~
chips)',
 PATH='I18',
 DRAWING='@BASEBOARD_FAB2_LIB.BASEBOARD_FAB2(SCH_1):PAGE91',
 WATTAGE='1/16W',
 TOLERANCE='1%',
 SEC_TYPE='0402',
 MATERIAL='CHIP',
 PHYS_PAGE='91',
 XY='(500,3375)',
 ROT='0',
 VER='2',
 VALUE='4.75K',
 PACK_TYPE='0402',
 PART_NUMBER='G21796-072',
 LOCATION='R8B17',
 SIGNAL_MODEL='DEFAULT_RESISTOR_4750OHM_2_1',
 ROOM='HFI',
 SEC='1',
 CDS_LIB='mstr_discrete',
 CDS_PART_NAME='RES_0402-4.75K,1%,1/16W,CHIP,GA',
 PRIM_FILE='./archive_libs/mstr_discrete/res/chips/chips.prt';

PART_NAME
 R8B18 'RES_0402-4.75K,1%,1/16W,CHIP,GA':
 ROOM='HFI',
 SIGNAL_MODEL='DEFAULT_RESISTOR_4750OHM_2_1';

SECTION_NUMBER 1
 '@BASEBOARD_FAB2_LIB.BASEBOARD_FAB2(SCH_1):PAGE91_I20@MSTR_DISCRETE.RES(CHIPS)':
 C_PATH='@baseboard_fab2_lib.baseboard_fab2(sch_1):page91_i20@mstr_discrete.res(~
chips)',
 P_PATH='@baseboard_fab2_lib.baseboard_fab2(sch_1):page91_i20@mstr_discrete.res(~
chips)',
 PATH='I20',
 DRAWING='@BASEBOARD_FAB2_LIB.BASEBOARD_FAB2(SCH_1):PAGE91',
 WATTAGE='1/16W',
 TOLERANCE='1%',
 SEC_TYPE='0402',
 MATERIAL='CHIP',
 PHYS_PAGE='91',
 XY='(-750,3350)',
 ROT='2',
 VER='2',
 VALUE='4.75K',
 PACK_TYPE='0402',
 PART_NUMBER='G21796-072',
 LOCATION='R8B18',
 SIGNAL_MODEL='DEFAULT_RESISTOR_4750OHM_2_1',
 ROOM='HFI',
 SEC='1',
 CDS_LIB='mstr_discrete',
 CDS_PART_NAME='RES_0402-4.75K,1%,1/16W,CHIP,GA',
 PRIM_FILE='./archive_libs/mstr_discrete/res/chips/chips.prt';

PART_NAME
 R8B19 'RES_0402-4.75K,1%,1/16W,CHIP,GA':
 ROOM='HFI',
 SIGNAL_MODEL='DEFAULT_RESISTOR_4750OHM_2_1';

SECTION_NUMBER 1
 '@BASEBOARD_FAB2_LIB.BASEBOARD_FAB2(SCH_1):PAGE91_I21@MSTR_DISCRETE.RES(CHIPS)':
 C_PATH='@baseboard_fab2_lib.baseboard_fab2(sch_1):page91_i21@mstr_discrete.res(~
chips)',
 P_PATH='@baseboard_fab2_lib.baseboard_fab2(sch_1):page91_i21@mstr_discrete.res(~
chips)',
 PATH='I21',
 DRAWING='@BASEBOARD_FAB2_LIB.BASEBOARD_FAB2(SCH_1):PAGE91',
 WATTAGE='1/16W',
 TOLERANCE='1%',
 SEC_TYPE='0402',
 MATERIAL='CHIP',
 PHYS_PAGE='91',
 XY='(-1125,3350)',
 ROT='2',
 VER='2',
 VALUE='4.75K',
 PACK_TYPE='0402',
 PART_NUMBER='G21796-072',
 LOCATION='R8B19',
 SIGNAL_MODEL='DEFAULT_RESISTOR_4750OHM_2_1',
 ROOM='HFI',
 SEC='1',
 CDS_LIB='mstr_discrete',
 CDS_PART_NAME='RES_0402-4.75K,1%,1/16W,CHIP,GA',
 PRIM_FILE='./archive_libs/mstr_discrete/res/chips/chips.prt';

PART_NAME
 R8B20 'RES_0402-10.0,1%,1/16W,CHIP,G2A':
 ROOM='SB';

SECTION_NUMBER 1
 '@BASEBOARD_FAB2_LIB.BASEBOARD_FAB2(SCH_1):PAGE114_I110@MSTR_DISCRETE.RES(CHIPS)':
 C_PATH='@baseboard_fab2_lib.baseboard_fab2(sch_1):page114_i110@mstr_discrete.re~
s(chips)',
 P_PATH='@baseboard_fab2_lib.baseboard_fab2(sch_1):page114_i110@mstr_discrete.re~
s(chips)',
 PATH='I110',
 DRAWING='@BASEBOARD_FAB2_LIB.BASEBOARD_FAB2(SCH_1):PAGE114',
 WATTAGE='1/16W',
 TOLERANCE='1%',
 SEC_TYPE='0402',
 MATERIAL='CHIP',
 PHYS_PAGE='114',
 XY='(2300,1350)',
 ROT='0',
 VER='1',
 VALUE='10.0',
 PACK_TYPE='0402',
 PART_NUMBER='G21796-066',
 LOCATION='R8B20',
 ROOM='SB',
 SEC='1',
 CDS_LIB='mstr_discrete',
 CDS_PART_NAME='RES_0402-10.0,1%,1/16W,CHIP,G2A',
 PRIM_FILE='./archive_libs/mstr_discrete/res/chips/chips.prt';

PART_NAME
 R8B21 'RES_0402-49.9,1%,1/16W,EMPTY,GA':
 ROOM='SB';

SECTION_NUMBER 1
 '@BASEBOARD_FAB2_LIB.BASEBOARD_FAB2(SCH_1):PAGE114_I124@MSTR_DISCRETE.RES(CHIPS)':
 C_PATH='@baseboard_fab2_lib.baseboard_fab2(sch_1):page114_i124@mstr_discrete.re~
s(chips)',
 P_PATH='@baseboard_fab2_lib.baseboard_fab2(sch_1):page114_i124@mstr_discrete.re~
s(chips)',
 PATH='I124',
 DRAWING='@BASEBOARD_FAB2_LIB.BASEBOARD_FAB2(SCH_1):PAGE114',
 WATTAGE='1/16W',
 TOLERANCE='1%',
 SEC_TYPE='0402',
 MATERIAL='EMPTY',
 PHYS_PAGE='114',
 XY='(2900,1100)',
 ROT='0',
 VER='2',
 VALUE='49.9',
 PACK_TYPE='0402',
 PART_NUMBER='G21796-047',
 LOCATION='R8B21',
 ROOM='SB',
 SEC='1',
 CDS_LIB='mstr_discrete',
 CDS_PART_NAME='RES_0402-49.9,1%,1/16W,EMPTY,GA',
 PRIM_FILE='./archive_libs/mstr_discrete/res/chips/chips.prt';

PART_NAME
 R8B23 'RES_0402-1.00K,1%,1/16W,CHIP,GA':
 ROOM='SB';

SECTION_NUMBER 1
 '@BASEBOARD_FAB2_LIB.BASEBOARD_FAB2(SCH_1):PAGE133_I280@MSTR_DISCRETE.RES(CHIPS)':
 C_PATH='@baseboard_fab2_lib.baseboard_fab2(sch_1):page133_i280@mstr_discrete.re~
s(chips)',
 P_PATH='@baseboard_fab2_lib.baseboard_fab2(sch_1):page133_i280@mstr_discrete.re~
s(chips)',
 PATH='I280',
 DRAWING='@BASEBOARD_FAB2_LIB.BASEBOARD_FAB2(SCH_1):PAGE133',
 WATTAGE='1/16W',
 TOLERANCE='1%',
 SEC_TYPE='0402',
 MATERIAL='CHIP',
 BOM_COST='SB',
 PHYS_PAGE='133',
 XY='(-2575,4675)',
 ROT='0',
 VER='1',
 VALUE='1.00K',
 PACK_TYPE='0402',
 PART_NUMBER='G21796-026',
 LOCATION='R8B23',
 ROOM='SB',
 SEC='1',
 CDS_LIB='mstr_discrete',
 CDS_PART_NAME='RES_0402-1.00K,1%,1/16W,CHIP,GA',
 PRIM_FILE='./archive_libs/mstr_discrete/res/chips/chips.prt';

PART_NAME
 R8B24 'RES_0402-3.3K,5%,1/16W,CHIP,G2A':;

SECTION_NUMBER 1
 '@BASEBOARD_FAB2_LIB.BASEBOARD_FAB2(SCH_1):PAGE138_I186@MSTR_DISCRETE.RES(CHIPS)':
 C_PATH='@baseboard_fab2_lib.baseboard_fab2(sch_1):page138_i186@mstr_discrete.re~
s(chips)',
 P_PATH='@baseboard_fab2_lib.baseboard_fab2(sch_1):page138_i186@mstr_discrete.re~
s(chips)',
 PATH='I186',
 DRAWING='@BASEBOARD_FAB2_LIB.BASEBOARD_FAB2(SCH_1):PAGE138',
 WATTAGE='1/16W',
 TOLERANCE='5%',
 SEC_TYPE='0402',
 MATERIAL='CHIP',
 PHYS_PAGE='138',
 XY='(-3175,2975)',
 ROT='5',
 VER='1',
 VALUE='3.3K',
 PACK_TYPE='0402',
 PART_NUMBER='G21497-013',
 LOCATION='R8B24',
 SEC='1',
 CDS_LIB='mstr_discrete',
 CDS_PART_NAME='RES_0402-3.3K,5%,1/16W,CHIP,G2A',
 PRIM_FILE='./archive_libs/mstr_discrete/res/chips/chips.prt';

PART_NAME
 R8B25 'RES_0402-4.75K,1%,1/16W,CHIP,GA':
 ROOM='BMC';

SECTION_NUMBER 1
 '@BASEBOARD_FAB2_LIB.BASEBOARD_FAB2(SCH_1):PAGE151_I175@MSTR_DISCRETE.RES(CHIPS)':
 C_PATH='@baseboard_fab2_lib.baseboard_fab2(sch_1):page151_i175@mstr_discrete.re~
s(chips)',
 P_PATH='@baseboard_fab2_lib.baseboard_fab2(sch_1):page151_i175@mstr_discrete.re~
s(chips)',
 PATH='I175',
 DRAWING='@BASEBOARD_FAB2_LIB.BASEBOARD_FAB2(SCH_1):PAGE151',
 WATTAGE='1/16W',
 TOLERANCE='1%',
 SEC_TYPE='0402',
 MATERIAL='CHIP',
 BOM_COST='SM_CONTROLLER',
 PHYS_PAGE='151',
 XY='(-2175,-475)',
 ROT='0',
 VER='2',
 VALUE='4.75K',
 PACK_TYPE='0402',
 PART_NUMBER='G21796-072',
 LOCATION='R8B25',
 ROOM='BMC',
 SEC='1',
 CDS_LIB='mstr_discrete',
 CDS_PART_NAME='RES_0402-4.75K,1%,1/16W,CHIP,GA',
 PRIM_FILE='./archive_libs/mstr_discrete/res/chips/chips.prt';

PART_NAME
 R8B26 'RES_0402-3.3K,5%,1/16W,CHIP,G2A':;

SECTION_NUMBER 1
 '@BASEBOARD_FAB2_LIB.BASEBOARD_FAB2(SCH_1):PAGE138_I187@MSTR_DISCRETE.RES(CHIPS)':
 C_PATH='@baseboard_fab2_lib.baseboard_fab2(sch_1):page138_i187@mstr_discrete.re~
s(chips)',
 P_PATH='@baseboard_fab2_lib.baseboard_fab2(sch_1):page138_i187@mstr_discrete.re~
s(chips)',
 PATH='I187',
 DRAWING='@BASEBOARD_FAB2_LIB.BASEBOARD_FAB2(SCH_1):PAGE138',
 WATTAGE='1/16W',
 TOLERANCE='5%',
 SEC_TYPE='0402',
 MATERIAL='CHIP',
 PHYS_PAGE='138',
 XY='(-2775,2925)',
 ROT='5',
 VER='1',
 VALUE='3.3K',
 PACK_TYPE='0402',
 PART_NUMBER='G21497-013',
 LOCATION='R8B26',
 SEC='1',
 CDS_LIB='mstr_discrete',
 CDS_PART_NAME='RES_0402-3.3K,5%,1/16W,CHIP,G2A',
 PRIM_FILE='./archive_libs/mstr_discrete/res/chips/chips.prt';

PART_NAME
 R8B29 'RES_0402-49.9,1%,1/16W,CHIP,G2A':
 ROOM='ST_SATA';

SECTION_NUMBER 1
 '@BASEBOARD_FAB2_LIB.BASEBOARD_FAB2(SCH_1):PAGE178_I21@MSTR_DISCRETE.RES(CHIPS)':
 C_PATH='@baseboard_fab2_lib.baseboard_fab2(sch_1):page178_i21@mstr_discrete.res~
(chips)',
 P_PATH='@baseboard_fab2_lib.baseboard_fab2(sch_1):page178_i21@mstr_discrete.res~
(chips)',
 PATH='I21',
 DRAWING='@BASEBOARD_FAB2_LIB.BASEBOARD_FAB2(SCH_1):PAGE178',
 WATTAGE='1/16W',
 TOLERANCE='1%',
 SEC_TYPE='0402',
 MATERIAL='CHIP',
 BOM_COST='ST_SATA',
 PHYS_PAGE='178',
 XY='(-800,1675)',
 ROT='0',
 VER='1',
 VALUE='49.9',
 PACK_TYPE='0402',
 PART_NUMBER='G21796-047',
 LOCATION='R8B29',
 ROOM='ST_SATA',
 SEC='1',
 CDS_LIB='mstr_discrete',
 CDS_PART_NAME='RES_0402-49.9,1%,1/16W,CHIP,G2A',
 PRIM_FILE='./archive_libs/mstr_discrete/res/chips/chips.prt';

PART_NAME
 R8B30 'RES_0402-1.00K,1%,1/16W,CHIP,GA':
 ROOM='SB';

SECTION_NUMBER 1
 '@BASEBOARD_FAB2_LIB.BASEBOARD_FAB2(SCH_1):PAGE133_I282@MSTR_DISCRETE.RES(CHIPS)':
 C_PATH='@baseboard_fab2_lib.baseboard_fab2(sch_1):page133_i282@mstr_discrete.re~
s(chips)',
 P_PATH='@baseboard_fab2_lib.baseboard_fab2(sch_1):page133_i282@mstr_discrete.re~
s(chips)',
 PATH='I282',
 DRAWING='@BASEBOARD_FAB2_LIB.BASEBOARD_FAB2(SCH_1):PAGE133',
 WATTAGE='1/16W',
 TOLERANCE='1%',
 SEC_TYPE='0402',
 MATERIAL='CHIP',
 BOM_COST='SB',
 PHYS_PAGE='133',
 XY='(-2575,4425)',
 ROT='0',
 VER='1',
 VALUE='1.00K',
 PACK_TYPE='0402',
 PART_NUMBER='G21796-026',
 LOCATION='R8B30',
 ROOM='SB',
 SEC='1',
 CDS_LIB='mstr_discrete',
 CDS_PART_NAME='RES_0402-1.00K,1%,1/16W,CHIP,GA',
 PRIM_FILE='./archive_libs/mstr_discrete/res/chips/chips.prt';

PART_NAME
 R8B31 'RES_0402-4.75K,1%,1/16W,CHIP,GA':
 ROOM='SB_PU_PD';

SECTION_NUMBER 1
 '@BASEBOARD_FAB2_LIB.BASEBOARD_FAB2(SCH_1):PAGE133_I307@MSTR_DISCRETE.RES(CHIPS)':
 C_PATH='@baseboard_fab2_lib.baseboard_fab2(sch_1):page133_i307@mstr_discrete.re~
s(chips)',
 P_PATH='@baseboard_fab2_lib.baseboard_fab2(sch_1):page133_i307@mstr_discrete.re~
s(chips)',
 PATH='I307',
 DRAWING='@BASEBOARD_FAB2_LIB.BASEBOARD_FAB2(SCH_1):PAGE133',
 WATTAGE='1/16W',
 TOLERANCE='1%',
 SEC_TYPE='0402',
 MATERIAL='CHIP',
 PHYS_PAGE='133',
 XY='(-4800,1650)',
 ROT='0',
 VER='1',
 VALUE='4.75K',
 PACK_TYPE='0402',
 PART_NUMBER='G21796-072',
 LOCATION='R8B31',
 ROOM='SB_PU_PD',
 SEC='1',
 CDS_LIB='mstr_discrete',
 CDS_PART_NAME='RES_0402-4.75K,1%,1/16W,CHIP,GA',
 PRIM_FILE='./archive_libs/mstr_discrete/res/chips/chips.prt';

PART_NAME
 R8B32 'RES_0402-10.0K,1%,1/16W,CHIP,GA':;

SECTION_NUMBER 1
 '@BASEBOARD_FAB2_LIB.BASEBOARD_FAB2(SCH_1):PAGE115_I114@MSTR_DISCRETE.RES(CHIPS)':
 C_PATH='@baseboard_fab2_lib.baseboard_fab2(sch_1):page115_i114@mstr_discrete.re~
s(chips)',
 P_PATH='@baseboard_fab2_lib.baseboard_fab2(sch_1):page115_i114@mstr_discrete.re~
s(chips)',
 PATH='I114',
 DRAWING='@BASEBOARD_FAB2_LIB.BASEBOARD_FAB2(SCH_1):PAGE115',
 WATTAGE='1/16W',
 TOLERANCE='1%',
 SEC_TYPE='0402',
 MATERIAL='CHIP',
 PHYS_PAGE='115',
 XY='(-5425,1775)',
 ROT='0',
 VER='2',
 VALUE='10.0K',
 PACK_TYPE='0402',
 PART_NUMBER='G21796-016',
 LOCATION='R8B32',
 SEC='1',
 CDS_LIB='mstr_discrete',
 CDS_PART_NAME='RES_0402-10.0K,1%,1/16W,CHIP,GA',
 PRIM_FILE='./archive_libs/mstr_discrete/res/chips/chips.prt';

PART_NAME
 R8C1 'RES_0402-4.75K,1%,1/16W,CHIP,GA':
 ROOM='SB_PU_PD';

SECTION_NUMBER 1
 '@BASEBOARD_FAB2_LIB.BASEBOARD_FAB2(SCH_1):PAGE133_I326@MSTR_DISCRETE.RES(CHIPS)':
 C_PATH='@baseboard_fab2_lib.baseboard_fab2(sch_1):page133_i326@mstr_discrete.re~
s(chips)',
 P_PATH='@baseboard_fab2_lib.baseboard_fab2(sch_1):page133_i326@mstr_discrete.re~
s(chips)',
 PATH='I326',
 DRAWING='@BASEBOARD_FAB2_LIB.BASEBOARD_FAB2(SCH_1):PAGE133',
 WATTAGE='1/16W',
 TOLERANCE='1%',
 SEC_TYPE='0402',
 MATERIAL='CHIP',
 PHYS_PAGE='133',
 XY='(-4800,1300)',
 ROT='0',
 VER='1',
 VALUE='4.75K',
 PACK_TYPE='0402',
 PART_NUMBER='G21796-072',
 LOCATION='R8C1',
 ROOM='SB_PU_PD',
 SEC='1',
 CDS_LIB='mstr_discrete',
 CDS_PART_NAME='RES_0402-4.75K,1%,1/16W,CHIP,GA',
 PRIM_FILE='./archive_libs/mstr_discrete/res/chips/chips.prt';

PART_NAME
 R8C2 'RES_0402-4.75K,1%,1/16W,CHIP,GA':
 ROOM='SB_PU_PD';

SECTION_NUMBER 1
 '@BASEBOARD_FAB2_LIB.BASEBOARD_FAB2(SCH_1):PAGE133_I304@MSTR_DISCRETE.RES(CHIPS)':
 C_PATH='@baseboard_fab2_lib.baseboard_fab2(sch_1):page133_i304@mstr_discrete.re~
s(chips)',
 P_PATH='@baseboard_fab2_lib.baseboard_fab2(sch_1):page133_i304@mstr_discrete.re~
s(chips)',
 PATH='I304',
 DRAWING='@BASEBOARD_FAB2_LIB.BASEBOARD_FAB2(SCH_1):PAGE133',
 WATTAGE='1/16W',
 TOLERANCE='1%',
 SEC_TYPE='0402',
 MATERIAL='CHIP',
 PHYS_PAGE='133',
 XY='(-4800,1825)',
 ROT='0',
 VER='1',
 VALUE='4.75K',
 PACK_TYPE='0402',
 PART_NUMBER='G21796-072',
 LOCATION='R8C2',
 ROOM='SB_PU_PD',
 SEC='1',
 CDS_LIB='mstr_discrete',
 CDS_PART_NAME='RES_0402-4.75K,1%,1/16W,CHIP,GA',
 PRIM_FILE='./archive_libs/mstr_discrete/res/chips/chips.prt';

PART_NAME
 R8C4 'RES_0402-1.00K,1%,1/16W,CHIP,GA':
 ROOM='SB';

SECTION_NUMBER 1
 '@BASEBOARD_FAB2_LIB.BASEBOARD_FAB2(SCH_1):PAGE133_I286@MSTR_DISCRETE.RES(CHIPS)':
 C_PATH='@baseboard_fab2_lib.baseboard_fab2(sch_1):page133_i286@mstr_discrete.re~
s(chips)',
 P_PATH='@baseboard_fab2_lib.baseboard_fab2(sch_1):page133_i286@mstr_discrete.re~
s(chips)',
 PATH='I286',
 DRAWING='@BASEBOARD_FAB2_LIB.BASEBOARD_FAB2(SCH_1):PAGE133',
 WATTAGE='1/16W',
 TOLERANCE='1%',
 SEC_TYPE='0402',
 MATERIAL='CHIP',
 BOM_COST='SB_PU_PD',
 PHYS_PAGE='133',
 XY='(-4800,950)',
 ROT='0',
 VER='1',
 VALUE='1.00K',
 PACK_TYPE='0402',
 PART_NUMBER='G21796-026',
 LOCATION='R8C4',
 ROOM='SB',
 SEC='1',
 CDS_LIB='mstr_discrete',
 CDS_PART_NAME='RES_0402-1.00K,1%,1/16W,CHIP,GA',
 PRIM_FILE='./archive_libs/mstr_discrete/res/chips/chips.prt';

PART_NAME
 R8C6 'RES_0402-4.75K,1%,1/16W,CHIP,GA':
 ROOM='SB_PU_PD';

SECTION_NUMBER 1
 '@BASEBOARD_FAB2_LIB.BASEBOARD_FAB2(SCH_1):PAGE133_I303@MSTR_DISCRETE.RES(CHIPS)':
 C_PATH='@baseboard_fab2_lib.baseboard_fab2(sch_1):page133_i303@mstr_discrete.re~
s(chips)',
 P_PATH='@baseboard_fab2_lib.baseboard_fab2(sch_1):page133_i303@mstr_discrete.re~
s(chips)',
 PATH='I303',
 DRAWING='@BASEBOARD_FAB2_LIB.BASEBOARD_FAB2(SCH_1):PAGE133',
 WATTAGE='1/16W',
 TOLERANCE='1%',
 SEC_TYPE='0402',
 MATERIAL='CHIP',
 PHYS_PAGE='133',
 XY='(-4675,2400)',
 ROT='0',
 VER='1',
 VALUE='4.75K',
 PACK_TYPE='0402',
 PART_NUMBER='G21796-072',
 LOCATION='R8C6',
 ROOM='SB_PU_PD',
 SEC='1',
 CDS_LIB='mstr_discrete',
 CDS_PART_NAME='RES_0402-4.75K,1%,1/16W,CHIP,GA',
 PRIM_FILE='./archive_libs/mstr_discrete/res/chips/chips.prt';

PART_NAME
 R8C7 'RES_0402-4.75K,1%,1/16W,CHIP,GA':
 ROOM='SB_PU_PD';

SECTION_NUMBER 1
 '@BASEBOARD_FAB2_LIB.BASEBOARD_FAB2(SCH_1):PAGE133_I327@MSTR_DISCRETE.RES(CHIPS)':
 C_PATH='@baseboard_fab2_lib.baseboard_fab2(sch_1):page133_i327@mstr_discrete.re~
s(chips)',
 P_PATH='@baseboard_fab2_lib.baseboard_fab2(sch_1):page133_i327@mstr_discrete.re~
s(chips)',
 PATH='I327',
 DRAWING='@BASEBOARD_FAB2_LIB.BASEBOARD_FAB2(SCH_1):PAGE133',
 WATTAGE='1/16W',
 TOLERANCE='1%',
 SEC_TYPE='0402',
 MATERIAL='CHIP',
 BOM_COST='SB',
 PHYS_PAGE='133',
 XY='(-4800,1125)',
 ROT='0',
 VER='1',
 VALUE='4.75K',
 PACK_TYPE='0402',
 PART_NUMBER='G21796-072',
 LOCATION='R8C7',
 ROOM='SB_PU_PD',
 SEC='1',
 CDS_LIB='mstr_discrete',
 CDS_PART_NAME='RES_0402-4.75K,1%,1/16W,CHIP,GA',
 PRIM_FILE='./archive_libs/mstr_discrete/res/chips/chips.prt';

PART_NAME
 R8C9 'RES_0402-4.75K,1%,1/16W,CHIP,GA':
 ROOM='BMC_MISC';

SECTION_NUMBER 1
 '@BASEBOARD_FAB2_LIB.BASEBOARD_FAB2(SCH_1):PAGE126_I20@MSTR_DISCRETE.RES(CHIPS)':
 C_PATH='@baseboard_fab2_lib.baseboard_fab2(sch_1):page126_i20@mstr_discrete.res~
(chips)',
 P_PATH='@baseboard_fab2_lib.baseboard_fab2(sch_1):page126_i20@mstr_discrete.res~
(chips)',
 PATH='I20',
 DRAWING='@BASEBOARD_FAB2_LIB.BASEBOARD_FAB2(SCH_1):PAGE126',
 WATTAGE='1/16W',
 TOLERANCE='1%',
 SEC_TYPE='0402',
 MATERIAL='CHIP',
 BOM_COST='SM_CONTROLLER',
 PHYS_PAGE='126',
 XY='(-3625,4425)',
 ROT='0',
 VER='2',
 VALUE='4.75K',
 PACK_TYPE='0402',
 PART_NUMBER='G21796-072',
 LOCATION='R8C9',
 ROOM='BMC_MISC',
 SEC='1',
 CDS_LIB='mstr_discrete',
 CDS_PART_NAME='RES_0402-4.75K,1%,1/16W,CHIP,GA',
 PRIM_FILE='./archive_libs/mstr_discrete/res/chips/chips.prt';

PART_NAME
 R8C11 'RES_0402-20.0,1%,1/16W,CHIP,G2A':
 ROOM='SMBUS';

SECTION_NUMBER 1
 '@BASEBOARD_FAB2_LIB.BASEBOARD_FAB2(SCH_1):PAGE138_I169@MSTR_DISCRETE.RES(CHIPS)':
 C_PATH='@baseboard_fab2_lib.baseboard_fab2(sch_1):page138_i169@mstr_discrete.re~
s(chips)',
 P_PATH='@baseboard_fab2_lib.baseboard_fab2(sch_1):page138_i169@mstr_discrete.re~
s(chips)',
 PATH='I169',
 DRAWING='@BASEBOARD_FAB2_LIB.BASEBOARD_FAB2(SCH_1):PAGE138',
 WATTAGE='1/16W',
 TOLERANCE='1%',
 SEC_TYPE='0402',
 MATERIAL='CHIP',
 BOM_COST='SM_CONTROLLER',
 PHYS_PAGE='138',
 XY='(-3975,4625)',
 ROT='0',
 VER='1',
 VALUE='20.0',
 PACK_TYPE='0402',
 PART_NUMBER='G21796-173',
 LOCATION='R8C11',
 ROOM='SMBUS',
 SEC='1',
 CDS_LIB='mstr_discrete',
 CDS_PART_NAME='RES_0402-20.0,1%,1/16W,CHIP,G2A',
 PRIM_FILE='./archive_libs/mstr_discrete/res/chips/chips.prt';

PART_NAME
 R8C12 'RES_0402-20.0,1%,1/16W,CHIP,G2A':
 ROOM='SMBUS';

SECTION_NUMBER 1
 '@BASEBOARD_FAB2_LIB.BASEBOARD_FAB2(SCH_1):PAGE138_I170@MSTR_DISCRETE.RES(CHIPS)':
 C_PATH='@baseboard_fab2_lib.baseboard_fab2(sch_1):page138_i170@mstr_discrete.re~
s(chips)',
 P_PATH='@baseboard_fab2_lib.baseboard_fab2(sch_1):page138_i170@mstr_discrete.re~
s(chips)',
 PATH='I170',
 DRAWING='@BASEBOARD_FAB2_LIB.BASEBOARD_FAB2(SCH_1):PAGE138',
 WATTAGE='1/16W',
 TOLERANCE='1%',
 SEC_TYPE='0402',
 MATERIAL='CHIP',
 BOM_COST='SM_CONTROLLER',
 PHYS_PAGE='138',
 XY='(-3975,4475)',
 ROT='0',
 VER='1',
 VALUE='20.0',
 PACK_TYPE='0402',
 PART_NUMBER='G21796-173',
 LOCATION='R8C12',
 ROOM='SMBUS',
 SEC='1',
 CDS_LIB='mstr_discrete',
 CDS_PART_NAME='RES_0402-20.0,1%,1/16W,CHIP,G2A',
 PRIM_FILE='./archive_libs/mstr_discrete/res/chips/chips.prt';

PART_NAME
 R8C14 'RES_0402-20.0,1%,1/16W,CHIP,G2A':
 ROOM='SMBUS';

SECTION_NUMBER 1
 '@BASEBOARD_FAB2_LIB.BASEBOARD_FAB2(SCH_1):PAGE138_I168@MSTR_DISCRETE.RES(CHIPS)':
 C_PATH='@baseboard_fab2_lib.baseboard_fab2(sch_1):page138_i168@mstr_discrete.re~
s(chips)',
 P_PATH='@baseboard_fab2_lib.baseboard_fab2(sch_1):page138_i168@mstr_discrete.re~
s(chips)',
 PATH='I168',
 DRAWING='@BASEBOARD_FAB2_LIB.BASEBOARD_FAB2(SCH_1):PAGE138',
 WATTAGE='1/16W',
 TOLERANCE='1%',
 SEC_TYPE='0402',
 MATERIAL='CHIP',
 BOM_COST='SM_CONTROLLER',
 PHYS_PAGE='138',
 XY='(-3775,3550)',
 ROT='0',
 VER='1',
 VALUE='20.0',
 PACK_TYPE='0402',
 PART_NUMBER='G21796-173',
 LOCATION='R8C14',
 ROOM='SMBUS',
 SEC='1',
 CDS_LIB='mstr_discrete',
 CDS_PART_NAME='RES_0402-20.0,1%,1/16W,CHIP,G2A',
 PRIM_FILE='./archive_libs/mstr_discrete/res/chips/chips.prt';

PART_NAME
 R8C15 'RES_0402-2.0K,1%,1/16W,CHIP,G2A':
 ROOM='SMBUS';

SECTION_NUMBER 1
 '@BASEBOARD_FAB2_LIB.BASEBOARD_FAB2(SCH_1):PAGE159_I235@MSTR_DISCRETE.RES(CHIPS)':
 C_PATH='@baseboard_fab2_lib.baseboard_fab2(sch_1):page159_i235@mstr_discrete.re~
s(chips)',
 P_PATH='@baseboard_fab2_lib.baseboard_fab2(sch_1):page159_i235@mstr_discrete.re~
s(chips)',
 PATH='I235',
 DRAWING='@BASEBOARD_FAB2_LIB.BASEBOARD_FAB2(SCH_1):PAGE159',
 WATTAGE='1/16W',
 TOLERANCE='1%',
 SEC_TYPE='0402',
 MATERIAL='CHIP',
 BOM_COST='SM_CONTROLLER',
 PHYS_PAGE='159',
 XY='(-3500,4100)',
 ROT='0',
 VER='2',
 VALUE='2.0K',
 PACK_TYPE='0402',
 PART_NUMBER='G21796-001',
 LOCATION='R8C15',
 ROOM='SMBUS',
 SEC='1',
 CDS_LIB='mstr_discrete',
 CDS_PART_NAME='RES_0402-2.0K,1%,1/16W,CHIP,G2A',
 PRIM_FILE='./archive_libs/mstr_discrete/res/chips/chips.prt';

PART_NAME
 R8C16 'RES_0402-2.0K,1%,1/16W,CHIP,G2A':
 ROOM='SMBUS';

SECTION_NUMBER 1
 '@BASEBOARD_FAB2_LIB.BASEBOARD_FAB2(SCH_1):PAGE159_I237@MSTR_DISCRETE.RES(CHIPS)':
 C_PATH='@baseboard_fab2_lib.baseboard_fab2(sch_1):page159_i237@mstr_discrete.re~
s(chips)',
 P_PATH='@baseboard_fab2_lib.baseboard_fab2(sch_1):page159_i237@mstr_discrete.re~
s(chips)',
 PATH='I237',
 DRAWING='@BASEBOARD_FAB2_LIB.BASEBOARD_FAB2(SCH_1):PAGE159',
 WATTAGE='1/16W',
 TOLERANCE='1%',
 SEC_TYPE='0402',
 MATERIAL='CHIP',
 BOM_COST='SM_CONTROLLER',
 PHYS_PAGE='159',
 XY='(-3900,4150)',
 ROT='0',
 VER='2',
 VALUE='2.0K',
 PACK_TYPE='0402',
 PART_NUMBER='G21796-001',
 LOCATION='R8C16',
 ROOM='SMBUS',
 SEC='1',
 CDS_LIB='mstr_discrete',
 CDS_PART_NAME='RES_0402-2.0K,1%,1/16W,CHIP,G2A',
 PRIM_FILE='./archive_libs/mstr_discrete/res/chips/chips.prt';

PART_NAME
 R8C17 'RES_0402-1.00K,1%,1/16W,EMPTY,A':
 ROOM='SB';

SECTION_NUMBER 1
 '@BASEBOARD_FAB2_LIB.BASEBOARD_FAB2(SCH_1):PAGE125_I41@MSTR_DISCRETE.RES(CHIPS)':
 C_PATH='@baseboard_fab2_lib.baseboard_fab2(sch_1):page125_i41@mstr_discrete.res~
(chips)',
 P_PATH='@baseboard_fab2_lib.baseboard_fab2(sch_1):page125_i41@mstr_discrete.res~
(chips)',
 PATH='I41',
 DRAWING='@BASEBOARD_FAB2_LIB.BASEBOARD_FAB2(SCH_1):PAGE125',
 WATTAGE='1/16W',
 TOLERANCE='1%',
 SEC_TYPE='0402',
 MATERIAL='EMPTY',
 BOM_COST='SB',
 PHYS_PAGE='125',
 XY='(-3225,2200)',
 ROT='0',
 VER='2',
 VALUE='1.00K',
 PACK_TYPE='0402',
 PART_NUMBER='G21796-026',
 LOCATION='R8C17',
 ROOM='SB',
 SEC='1',
 CDS_LIB='mstr_discrete',
 CDS_PART_NAME='RES_0402-1.00K,1%,1/16W,EMPTY,A',
 PRIM_FILE='./archive_libs/mstr_discrete/res/chips/chips.prt';

PART_NAME
 R8C18 'RES_0402-1.00K,1%,1/16W,CHIP,GA':
 ROOM='SB';

SECTION_NUMBER 1
 '@BASEBOARD_FAB2_LIB.BASEBOARD_FAB2(SCH_1):PAGE125_I40@MSTR_DISCRETE.RES(CHIPS)':
 C_PATH='@baseboard_fab2_lib.baseboard_fab2(sch_1):page125_i40@mstr_discrete.res~
(chips)',
 P_PATH='@baseboard_fab2_lib.baseboard_fab2(sch_1):page125_i40@mstr_discrete.res~
(chips)',
 PATH='I40',
 DRAWING='@BASEBOARD_FAB2_LIB.BASEBOARD_FAB2(SCH_1):PAGE125',
 WATTAGE='1/16W',
 TOLERANCE='1%',
 MATERIAL='CHIP',
 BOM_COST='SB',
 PHYS_PAGE='125',
 XY='(-3225,2525)',
 ROT='0',
 VER='2',
 VALUE='1.00K',
 PACK_TYPE='0402',
 PART_NUMBER='G21796-026',
 LOCATION='R8C18',
 ROOM='SB',
 CDS_LIB='mstr_discrete',
 CDS_PART_NAME='RES_0402-1.00K,1%,1/16W,CHIP,GA',
 PRIM_FILE='./archive_libs/mstr_discrete/res/chips/chips.prt';

PART_NAME
 R8C20 'RES_0402-20.0,1%,1/16W,CHIP,G2A':
 ROOM='SMBUS';

SECTION_NUMBER 1
 '@BASEBOARD_FAB2_LIB.BASEBOARD_FAB2(SCH_1):PAGE138_I167@MSTR_DISCRETE.RES(CHIPS)':
 C_PATH='@baseboard_fab2_lib.baseboard_fab2(sch_1):page138_i167@mstr_discrete.re~
s(chips)',
 P_PATH='@baseboard_fab2_lib.baseboard_fab2(sch_1):page138_i167@mstr_discrete.re~
s(chips)',
 PATH='I167',
 DRAWING='@BASEBOARD_FAB2_LIB.BASEBOARD_FAB2(SCH_1):PAGE138',
 WATTAGE='1/16W',
 TOLERANCE='1%',
 SEC_TYPE='0402',
 MATERIAL='CHIP',
 BOM_COST='SM_CONTROLLER',
 PHYS_PAGE='138',
 XY='(-3775,3700)',
 ROT='0',
 VER='1',
 VALUE='20.0',
 PACK_TYPE='0402',
 PART_NUMBER='G21796-173',
 LOCATION='R8C20',
 ROOM='SMBUS',
 SEC='1',
 CDS_LIB='mstr_discrete',
 CDS_PART_NAME='RES_0402-20.0,1%,1/16W,CHIP,G2A',
 PRIM_FILE='./archive_libs/mstr_discrete/res/chips/chips.prt';

PART_NAME
 R8C21 'RES_0402-100.0,1%,1/16W,CHIP,GA':
 ROOM='SB';

SECTION_NUMBER 1
 '@BASEBOARD_FAB2_LIB.BASEBOARD_FAB2(SCH_1):PAGE120_I275@MSTR_DISCRETE.RES(CHIPS)':
 C_PATH='@baseboard_fab2_lib.baseboard_fab2(sch_1):page120_i275@mstr_discrete.re~
s(chips)',
 P_PATH='@baseboard_fab2_lib.baseboard_fab2(sch_1):page120_i275@mstr_discrete.re~
s(chips)',
 PATH='I275',
 DRAWING='@BASEBOARD_FAB2_LIB.BASEBOARD_FAB2(SCH_1):PAGE120',
 WATTAGE='1/16W',
 TOLERANCE='1%',
 SEC_TYPE='0402',
 MATERIAL='CHIP',
 PHYS_PAGE='120',
 XY='(-1400,3050)',
 ROT='1',
 VER='2',
 VALUE='100.0',
 PACK_TYPE='0402',
 PART_NUMBER='G21796-017',
 LOCATION='R8C21',
 ROOM='SB',
 SEC='1',
 CDS_LIB='mstr_discrete',
 CDS_PART_NAME='RES_0402-100.0,1%,1/16W,CHIP,GA',
 PRIM_FILE='./archive_libs/mstr_discrete/res/chips/chips.prt';

PART_NAME
 R8C23 'RES_0402-0.0,5%,1/16W,EMPTY,G2A':
 ROOM='SB';

SECTION_NUMBER 1
 '@BASEBOARD_FAB2_LIB.BASEBOARD_FAB2(SCH_1):PAGE118_I125@MSTR_DISCRETE.RES(CHIPS)':
 C_PATH='@baseboard_fab2_lib.baseboard_fab2(sch_1):page118_i125@mstr_discrete.re~
s(chips)',
 P_PATH='@baseboard_fab2_lib.baseboard_fab2(sch_1):page118_i125@mstr_discrete.re~
s(chips)',
 PATH='I125',
 DRAWING='@BASEBOARD_FAB2_LIB.BASEBOARD_FAB2(SCH_1):PAGE118',
 WATTAGE='1/16W',
 TOLERANCE='5%',
 SEC_TYPE='0402',
 MATERIAL='EMPTY',
 BOM_COST='SB',
 PHYS_PAGE='118',
 XY='(-1675,675)',
 ROT='0',
 VER='1',
 VALUE='0.0',
 PACK_TYPE='0402',
 PART_NUMBER='G21497-005',
 LOCATION='R8C23',
 ROOM='SB',
 SEC='1',
 CDS_LIB='mstr_discrete',
 CDS_PART_NAME='RES_0402-0.0,5%,1/16W,EMPTY,G2A',
 PRIM_FILE='./archive_libs/mstr_discrete/res/chips/chips.prt';

PART_NAME
 R8C24 'RES_0402-0.0,5%,1/16W,CHIP,G21A':
 ROOM='SB';

SECTION_NUMBER 1
 '@BASEBOARD_FAB2_LIB.BASEBOARD_FAB2(SCH_1):PAGE118_I120@MSTR_DISCRETE.RES(CHIPS)':
 C_PATH='@baseboard_fab2_lib.baseboard_fab2(sch_1):page118_i120@mstr_discrete.re~
s(chips)',
 P_PATH='@baseboard_fab2_lib.baseboard_fab2(sch_1):page118_i120@mstr_discrete.re~
s(chips)',
 PATH='I120',
 DRAWING='@BASEBOARD_FAB2_LIB.BASEBOARD_FAB2(SCH_1):PAGE118',
 WATTAGE='1/16W',
 TOLERANCE='5%',
 SEC_TYPE='0402',
 MATERIAL='CHIP',
 BOM_COST='SB',
 PHYS_PAGE='118',
 XY='(-1675,900)',
 ROT='0',
 VER='1',
 VALUE='0.0',
 PACK_TYPE='0402',
 PART_NUMBER='G21497-005',
 LOCATION='R8C24',
 ROOM='SB',
 SEC='1',
 CDS_LIB='mstr_discrete',
 CDS_PART_NAME='RES_0402-0.0,5%,1/16W,CHIP,G21A',
 PRIM_FILE='./archive_libs/mstr_discrete/res/chips/chips.prt';

PART_NAME
 R8C25 'RES_0402-4.75K,1%,1/16W,CHIP,GA':
 ROOM='SB_PU_PD';

SECTION_NUMBER 1
 '@BASEBOARD_FAB2_LIB.BASEBOARD_FAB2(SCH_1):PAGE133_I333@MSTR_DISCRETE.RES(CHIPS)':
 C_PATH='@baseboard_fab2_lib.baseboard_fab2(sch_1):page133_i333@mstr_discrete.re~
s(chips)',
 P_PATH='@baseboard_fab2_lib.baseboard_fab2(sch_1):page133_i333@mstr_discrete.re~
s(chips)',
 PATH='I333',
 DRAWING='@BASEBOARD_FAB2_LIB.BASEBOARD_FAB2(SCH_1):PAGE133',
 WATTAGE='1/16W',
 TOLERANCE='1%',
 SEC_TYPE='0402',
 MATERIAL='CHIP',
 PHYS_PAGE='133',
 XY='(-2500,3150)',
 ROT='0',
 VER='1',
 VALUE='4.75K',
 PACK_TYPE='0402',
 PART_NUMBER='G21796-072',
 LOCATION='R8C25',
 ROOM='SB_PU_PD',
 SEC='1',
 CDS_LIB='mstr_discrete',
 CDS_PART_NAME='RES_0402-4.75K,1%,1/16W,CHIP,GA',
 PRIM_FILE='./archive_libs/mstr_discrete/res/chips/chips.prt';

PART_NAME
 R8C26 'RES_0402-100.0,1%,1/16W,CHIP,GA':
 ROOM='SB';

SECTION_NUMBER 1
 '@BASEBOARD_FAB2_LIB.BASEBOARD_FAB2(SCH_1):PAGE121_I35@MSTR_DISCRETE.RES(CHIPS)':
 C_PATH='@baseboard_fab2_lib.baseboard_fab2(sch_1):page121_i35@mstr_discrete.res~
(chips)',
 P_PATH='@baseboard_fab2_lib.baseboard_fab2(sch_1):page121_i35@mstr_discrete.res~
(chips)',
 PATH='I35',
 DRAWING='@BASEBOARD_FAB2_LIB.BASEBOARD_FAB2(SCH_1):PAGE121',
 WATTAGE='1/16W',
 TOLERANCE='1%',
 SEC_TYPE='0402',
 MATERIAL='CHIP',
 PHYS_PAGE='121',
 XY='(-7750,3675)',
 ROT='0',
 VER='2',
 VALUE='100.0',
 PACK_TYPE='0402',
 PART_NUMBER='G21796-017',
 LOCATION='R8C26',
 ROOM='SB',
 SEC='1',
 CDS_LIB='mstr_discrete',
 CDS_PART_NAME='RES_0402-100.0,1%,1/16W,CHIP,GA',
 PRIM_FILE='./archive_libs/mstr_discrete/res/chips/chips.prt';

PART_NAME
 R8D4 'RES_0402-20.0,1%,1/16W,CHIP,G2A':
 ROOM='SMBUS';

SECTION_NUMBER 1
 '@BASEBOARD_FAB2_LIB.BASEBOARD_FAB2(SCH_1):PAGE138_I164@MSTR_DISCRETE.RES(CHIPS)':
 C_PATH='@baseboard_fab2_lib.baseboard_fab2(sch_1):page138_i164@mstr_discrete.re~
s(chips)',
 P_PATH='@baseboard_fab2_lib.baseboard_fab2(sch_1):page138_i164@mstr_discrete.re~
s(chips)',
 PATH='I164',
 DRAWING='@BASEBOARD_FAB2_LIB.BASEBOARD_FAB2(SCH_1):PAGE138',
 WATTAGE='1/16W',
 TOLERANCE='1%',
 SEC_TYPE='0402',
 MATERIAL='CHIP',
 BOM_COST='SM_CONTROLLER',
 PHYS_PAGE='138',
 XY='(100,2125)',
 ROT='0',
 VER='1',
 VALUE='20.0',
 PACK_TYPE='0402',
 PART_NUMBER='G21796-173',
 LOCATION='R8D4',
 ROOM='SMBUS',
 SEC='1',
 CDS_LIB='mstr_discrete',
 CDS_PART_NAME='RES_0402-20.0,1%,1/16W,CHIP,G2A',
 PRIM_FILE='./archive_libs/mstr_discrete/res/chips/chips.prt';

PART_NAME
 R8D5 'RES_0402-1.00K,1%,1/16W,EMPTY,A':
 ROOM='SB';

SECTION_NUMBER 1
 '@BASEBOARD_FAB2_LIB.BASEBOARD_FAB2(SCH_1):PAGE125_I50@MSTR_DISCRETE.RES(CHIPS)':
 C_PATH='@baseboard_fab2_lib.baseboard_fab2(sch_1):page125_i50@mstr_discrete.res~
(chips)',
 P_PATH='@baseboard_fab2_lib.baseboard_fab2(sch_1):page125_i50@mstr_discrete.res~
(chips)',
 PATH='I50',
 DRAWING='@BASEBOARD_FAB2_LIB.BASEBOARD_FAB2(SCH_1):PAGE125',
 WATTAGE='1/16W',
 TOLERANCE='1%',
 MATERIAL='EMPTY',
 BOM_COST='SB',
 PHYS_PAGE='125',
 XY='(-925,4450)',
 ROT='0',
 VER='2',
 VALUE='1.00K',
 PACK_TYPE='0402',
 PART_NUMBER='G21796-026',
 LOCATION='R8D5',
 ROOM='SB',
 CDS_LIB='mstr_discrete',
 CDS_PART_NAME='RES_0402-1.00K,1%,1/16W,EMPTY,A',
 PRIM_FILE='./archive_libs/mstr_discrete/res/chips/chips.prt';

PART_NAME
 R8D7 'RES_0402-20.0,1%,1/16W,CHIP,G2A':
 ROOM='SMBUS';

SECTION_NUMBER 1
 '@BASEBOARD_FAB2_LIB.BASEBOARD_FAB2(SCH_1):PAGE138_I163@MSTR_DISCRETE.RES(CHIPS)':
 C_PATH='@baseboard_fab2_lib.baseboard_fab2(sch_1):page138_i163@mstr_discrete.re~
s(chips)',
 P_PATH='@baseboard_fab2_lib.baseboard_fab2(sch_1):page138_i163@mstr_discrete.re~
s(chips)',
 PATH='I163',
 DRAWING='@BASEBOARD_FAB2_LIB.BASEBOARD_FAB2(SCH_1):PAGE138',
 WATTAGE='1/16W',
 TOLERANCE='1%',
 SEC_TYPE='0402',
 MATERIAL='CHIP',
 BOM_COST='SM_CONTROLLER',
 PHYS_PAGE='138',
 XY='(100,2275)',
 ROT='0',
 VER='1',
 VALUE='20.0',
 PACK_TYPE='0402',
 PART_NUMBER='G21796-173',
 LOCATION='R8D7',
 ROOM='SMBUS',
 SEC='1',
 CDS_LIB='mstr_discrete',
 CDS_PART_NAME='RES_0402-20.0,1%,1/16W,CHIP,G2A',
 PRIM_FILE='./archive_libs/mstr_discrete/res/chips/chips.prt';

PART_NAME
 R8D11 'RES_0402-33.2,1%,1/16W,CHIP,G2A':
 ROOM='SB';

SECTION_NUMBER 1
 '@BASEBOARD_FAB2_LIB.BASEBOARD_FAB2(SCH_1):PAGE121_I101@MSTR_DISCRETE.RES(CHIPS)':
 C_PATH='@baseboard_fab2_lib.baseboard_fab2(sch_1):page121_i101@mstr_discrete.re~
s(chips)',
 P_PATH='@baseboard_fab2_lib.baseboard_fab2(sch_1):page121_i101@mstr_discrete.re~
s(chips)',
 PATH='I101',
 DRAWING='@BASEBOARD_FAB2_LIB.BASEBOARD_FAB2(SCH_1):PAGE121',
 WATTAGE='1/16W',
 TOLERANCE='1%',
 SEC_TYPE='0402',
 MATERIAL='CHIP',
 PHYS_PAGE='121',
 XY='(-5100,1175)',
 ROT='0',
 VER='1',
 VALUE='33.2',
 PACK_TYPE='0402',
 PART_NUMBER='G21796-074',
 LOCATION='R8D11',
 ROOM='SB',
 SEC='1',
 CDS_LIB='mstr_discrete',
 CDS_PART_NAME='RES_0402-33.2,1%,1/16W,CHIP,G2A',
 PRIM_FILE='./archive_libs/mstr_discrete/res/chips/chips.prt';

PART_NAME
 R8D13 'RES_0402-10.0K,1%,1/16W,EMPTY,A':
 ROOM='DB1200ZL';

SECTION_NUMBER 1
 '@BASEBOARD_FAB2_LIB.BASEBOARD_FAB2(SCH_1):PAGE125_I87@MSTR_DISCRETE.RES(CHIPS)':
 C_PATH='@baseboard_fab2_lib.baseboard_fab2(sch_1):page125_i87@mstr_discrete.res~
(chips)',
 P_PATH='@baseboard_fab2_lib.baseboard_fab2(sch_1):page125_i87@mstr_discrete.res~
(chips)',
 PATH='I87',
 DRAWING='@BASEBOARD_FAB2_LIB.BASEBOARD_FAB2(SCH_1):PAGE125',
 WATTAGE='1/16W',
 TOLERANCE='1%',
 SEC_TYPE='0402',
 MATERIAL='EMPTY',
 BOM_COST='SYS_CLOCK',
 PHYS_PAGE='125',
 XY='(-925,4925)',
 ROT='0',
 VER='2',
 VALUE='10.0K',
 PACK_TYPE='0402',
 PART_NUMBER='G21796-016',
 LOCATION='R8D13',
 ROOM='DB1200ZL',
 SEC='1',
 CDS_LIB='mstr_discrete',
 CDS_PART_NAME='RES_0402-10.0K,1%,1/16W,EMPTY,A',
 PRIM_FILE='./archive_libs/mstr_discrete/res/chips/chips.prt';

PART_NAME
 R8D14 'RES_0402-4.75K,1%,1/16W,CHIP,GA':
 ROOM='SB';

SECTION_NUMBER 1
 '@BASEBOARD_FAB2_LIB.BASEBOARD_FAB2(SCH_1):PAGE133_I301@MSTR_DISCRETE.RES(CHIPS)':
 C_PATH='@baseboard_fab2_lib.baseboard_fab2(sch_1):page133_i301@mstr_discrete.re~
s(chips)',
 P_PATH='@baseboard_fab2_lib.baseboard_fab2(sch_1):page133_i301@mstr_discrete.re~
s(chips)',
 PATH='I301',
 DRAWING='@BASEBOARD_FAB2_LIB.BASEBOARD_FAB2(SCH_1):PAGE133',
 WATTAGE='1/16W',
 TOLERANCE='1%',
 SEC_TYPE='0402',
 MATERIAL='CHIP',
 BOM_COST='SB',
 PHYS_PAGE='133',
 XY='(-2475,1800)',
 ROT='0',
 VER='1',
 VALUE='4.75K',
 PACK_TYPE='0402',
 PART_NUMBER='G21796-072',
 LOCATION='R8D14',
 ROOM='SB',
 SEC='1',
 CDS_LIB='mstr_discrete',
 CDS_PART_NAME='RES_0402-4.75K,1%,1/16W,CHIP,GA',
 PRIM_FILE='./archive_libs/mstr_discrete/res/chips/chips.prt';

PART_NAME
 R8D15 'RES_0402-1.37K,1%,1/16W,CHIP,GA':
 ROOM='SMBUS';

SECTION_NUMBER 1
 '@BASEBOARD_FAB2_LIB.BASEBOARD_FAB2(SCH_1):PAGE138_I88@MSTR_DISCRETE.RES(CHIPS)':
 C_PATH='@baseboard_fab2_lib.baseboard_fab2(sch_1):page138_i88@mstr_discrete.res~
(chips)',
 P_PATH='@baseboard_fab2_lib.baseboard_fab2(sch_1):page138_i88@mstr_discrete.res~
(chips)',
 PATH='I88',
 DRAWING='@BASEBOARD_FAB2_LIB.BASEBOARD_FAB2(SCH_1):PAGE138',
 WATTAGE='1/16W',
 TOLERANCE='1%',
 SEC_TYPE='0402',
 MATERIAL='CHIP',
 BOM_COST='SM_CONTROLLER',
 PHYS_PAGE='138',
 XY='(875,2525)',
 ROT='0',
 VER='2',
 VALUE='1.37K',
 PACK_TYPE='0402',
 PART_NUMBER='G21796-095',
 LOCATION='R8D15',
 ROOM='SMBUS',
 SEC='1',
 CDS_LIB='mstr_discrete',
 CDS_PART_NAME='RES_0402-1.37K,1%,1/16W,CHIP,GA',
 PRIM_FILE='./archive_libs/mstr_discrete/res/chips/chips.prt';

PART_NAME
 R8D16 'RES_0402-10.0K,1%,1/16W,CHIP,GA':
 ROOM='SB_HEADERS';

SECTION_NUMBER 1
 '@BASEBOARD_FAB2_LIB.BASEBOARD_FAB2(SCH_1):PAGE125_I85@MSTR_DISCRETE.RES(CHIPS)':
 C_PATH='@baseboard_fab2_lib.baseboard_fab2(sch_1):page125_i85@mstr_discrete.res~
(chips)',
 P_PATH='@baseboard_fab2_lib.baseboard_fab2(sch_1):page125_i85@mstr_discrete.res~
(chips)',
 PATH='I85',
 DRAWING='@BASEBOARD_FAB2_LIB.BASEBOARD_FAB2(SCH_1):PAGE125',
 WATTAGE='1/16W',
 TOLERANCE='1%',
 MATERIAL='CHIP',
 BOM_COST='SB',
 PHYS_PAGE='125',
 XY='(-5050,3775)',
 ROT='0',
 VER='2',
 VALUE='10.0K',
 PACK_TYPE='0402',
 PART_NUMBER='G21796-016',
 LOCATION='R8D16',
 ROOM='SB_HEADERS',
 CDS_LIB='mstr_discrete',
 CDS_PART_NAME='RES_0402-10.0K,1%,1/16W,CHIP,GA',
 PRIM_FILE='./archive_libs/mstr_discrete/res/chips/chips.prt';

PART_NAME
 R8D17 'RES_0402-1.37K,1%,1/16W,CHIP,GA':
 ROOM='SMBUS';

SECTION_NUMBER 1
 '@BASEBOARD_FAB2_LIB.BASEBOARD_FAB2(SCH_1):PAGE138_I87@MSTR_DISCRETE.RES(CHIPS)':
 C_PATH='@baseboard_fab2_lib.baseboard_fab2(sch_1):page138_i87@mstr_discrete.res~
(chips)',
 P_PATH='@baseboard_fab2_lib.baseboard_fab2(sch_1):page138_i87@mstr_discrete.res~
(chips)',
 PATH='I87',
 DRAWING='@BASEBOARD_FAB2_LIB.BASEBOARD_FAB2(SCH_1):PAGE138',
 WATTAGE='1/16W',
 TOLERANCE='1%',
 SEC_TYPE='0402',
 MATERIAL='CHIP',
 BOM_COST='SM_CONTROLLER',
 PHYS_PAGE='138',
 XY='(500,2575)',
 ROT='0',
 VER='2',
 VALUE='1.37K',
 PACK_TYPE='0402',
 PART_NUMBER='G21796-095',
 LOCATION='R8D17',
 ROOM='SMBUS',
 SEC='1',
 CDS_LIB='mstr_discrete',
 CDS_PART_NAME='RES_0402-1.37K,1%,1/16W,CHIP,GA',
 PRIM_FILE='./archive_libs/mstr_discrete/res/chips/chips.prt';

PART_NAME
 R8D19 'RES_0402-49.9,1%,1/16W,CHIP,G2A':
 ROOM='ST_SATA';

SECTION_NUMBER 1
 '@BASEBOARD_FAB2_LIB.BASEBOARD_FAB2(SCH_1):PAGE178_I8@MSTR_DISCRETE.RES(CHIPS)':
 C_PATH='@baseboard_fab2_lib.baseboard_fab2(sch_1):page178_i8@mstr_discrete.res(~
chips)',
 P_PATH='@baseboard_fab2_lib.baseboard_fab2(sch_1):page178_i8@mstr_discrete.res(~
chips)',
 PATH='I8',
 DRAWING='@BASEBOARD_FAB2_LIB.BASEBOARD_FAB2(SCH_1):PAGE178',
 WATTAGE='1/16W',
 TOLERANCE='1%',
 SEC_TYPE='0402',
 MATERIAL='CHIP',
 BOM_COST='ST_SATA',
 PHYS_PAGE='178',
 XY='(-800,3575)',
 ROT='0',
 VER='1',
 VALUE='49.9',
 PACK_TYPE='0402',
 PART_NUMBER='G21796-047',
 LOCATION='R8D19',
 ROOM='ST_SATA',
 SEC='1',
 CDS_LIB='mstr_discrete',
 CDS_PART_NAME='RES_0402-49.9,1%,1/16W,CHIP,G2A',
 PRIM_FILE='./archive_libs/mstr_discrete/res/chips/chips.prt';

PART_NAME
 R8D20 'RES_0402-49.9,1%,1/16W,CHIP,G2A':
 ROOM='ST_SATA';

SECTION_NUMBER 1
 '@BASEBOARD_FAB2_LIB.BASEBOARD_FAB2(SCH_1):PAGE178_I1@MSTR_DISCRETE.RES(CHIPS)':
 C_PATH='@baseboard_fab2_lib.baseboard_fab2(sch_1):page178_i1@mstr_discrete.res(~
chips)',
 P_PATH='@baseboard_fab2_lib.baseboard_fab2(sch_1):page178_i1@mstr_discrete.res(~
chips)',
 PATH='I1',
 DRAWING='@BASEBOARD_FAB2_LIB.BASEBOARD_FAB2(SCH_1):PAGE178',
 WATTAGE='1/16W',
 TOLERANCE='1%',
 SEC_TYPE='0402',
 MATERIAL='CHIP',
 BOM_COST='ST_SATA',
 PHYS_PAGE='178',
 XY='(-800,3725)',
 ROT='0',
 VER='1',
 VALUE='49.9',
 PACK_TYPE='0402',
 PART_NUMBER='G21796-047',
 LOCATION='R8D20',
 ROOM='ST_SATA',
 SEC='1',
 CDS_LIB='mstr_discrete',
 CDS_PART_NAME='RES_0402-49.9,1%,1/16W,CHIP,G2A',
 PRIM_FILE='./archive_libs/mstr_discrete/res/chips/chips.prt';

PART_NAME
 R8D21 'RES_0402-1.00K,1%,1/16W,CHIP,GA':
 ROOM='SB';

SECTION_NUMBER 1
 '@BASEBOARD_FAB2_LIB.BASEBOARD_FAB2(SCH_1):PAGE135_I120@MSTR_DISCRETE.RES(CHIPS)':
 C_PATH='@baseboard_fab2_lib.baseboard_fab2(sch_1):page135_i120@mstr_discrete.re~
s(chips)',
 P_PATH='@baseboard_fab2_lib.baseboard_fab2(sch_1):page135_i120@mstr_discrete.re~
s(chips)',
 PATH='I120',
 DRAWING='@BASEBOARD_FAB2_LIB.BASEBOARD_FAB2(SCH_1):PAGE135',
 WATTAGE='1/16W',
 TOLERANCE='1%',
 SEC_TYPE='0402',
 MATERIAL='CHIP',
 BOM_COST='SB',
 PHYS_PAGE='135',
 XY='(-225,2250)',
 ROT='0',
 VER='2',
 VALUE='1.00K',
 PACK_TYPE='0402',
 PART_NUMBER='G21796-026',
 LOCATION='R8D21',
 ROOM='SB',
 SEC='1',
 CDS_LIB='mstr_discrete',
 CDS_PART_NAME='RES_0402-1.00K,1%,1/16W,CHIP,GA',
 PRIM_FILE='./archive_libs/mstr_discrete/res/chips/chips.prt';

PART_NAME
 R8D22 'RES_0402-33.2,1%,1/16W,CHIP,G2A':
 ROOM='BMC_MISC';

SECTION_NUMBER 1
 '@BASEBOARD_FAB2_LIB.BASEBOARD_FAB2(SCH_1):PAGE157_I386@MSTR_DISCRETE.RES(CHIPS)':
 C_PATH='@baseboard_fab2_lib.baseboard_fab2(sch_1):page157_i386@mstr_discrete.re~
s(chips)',
 P_PATH='@baseboard_fab2_lib.baseboard_fab2(sch_1):page157_i386@mstr_discrete.re~
s(chips)',
 PATH='I386',
 DRAWING='@BASEBOARD_FAB2_LIB.BASEBOARD_FAB2(SCH_1):PAGE157',
 WATTAGE='1/16W',
 TOLERANCE='1%',
 SEC_TYPE='0402',
 MATERIAL='CHIP',
 BOM_COST='SM',
 PHYS_PAGE='157',
 XY='(-1925,1150)',
 ROT='0',
 VER='1',
 VALUE='33.2',
 PACK_TYPE='0402',
 PART_NUMBER='G21796-074',
 LOCATION='R8D22',
 ROOM='BMC_MISC',
 SEC='1',
 CDS_LIB='mstr_discrete',
 CDS_PART_NAME='RES_0402-33.2,1%,1/16W,CHIP,G2A',
 PRIM_FILE='./archive_libs/mstr_discrete/res/chips/chips.prt';

PART_NAME
 R8D23 'RES_0402-20.0,1%,1/16W,CHIP,G2A':
 ROOM='TEMP_SENSORS';

SECTION_NUMBER 1
 '@BASEBOARD_FAB2_LIB.BASEBOARD_FAB2(SCH_1):PAGE167_I85@MSTR_DISCRETE.RES(CHIPS)':
 C_PATH='@baseboard_fab2_lib.baseboard_fab2(sch_1):page167_i85@mstr_discrete.res~
(chips)',
 P_PATH='@baseboard_fab2_lib.baseboard_fab2(sch_1):page167_i85@mstr_discrete.res~
(chips)',
 PATH='I85',
 DRAWING='@BASEBOARD_FAB2_LIB.BASEBOARD_FAB2(SCH_1):PAGE167',
 WATTAGE='1/16W',
 TOLERANCE='1%',
 SEC_TYPE='0402',
 MATERIAL='CHIP',
 BOM_COST='SM_THERM',
 PHYS_PAGE='167',
 XY='(-1475,1550)',
 ROT='0',
 VER='1',
 VALUE='20.0',
 PACK_TYPE='0402',
 PART_NUMBER='G21796-173',
 LOCATION='R8D23',
 ROOM='TEMP_SENSORS',
 SEC='1',
 CDS_LIB='mstr_discrete',
 CDS_PART_NAME='RES_0402-20.0,1%,1/16W,CHIP,G2A',
 PRIM_FILE='./archive_libs/mstr_discrete/res/chips/chips.prt';

PART_NAME
 R8D24 'RES_0402-20.0,1%,1/16W,CHIP,G2A':
 ROOM='TEMP_SENSORS';

SECTION_NUMBER 1
 '@BASEBOARD_FAB2_LIB.BASEBOARD_FAB2(SCH_1):PAGE167_I84@MSTR_DISCRETE.RES(CHIPS)':
 C_PATH='@baseboard_fab2_lib.baseboard_fab2(sch_1):page167_i84@mstr_discrete.res~
(chips)',
 P_PATH='@baseboard_fab2_lib.baseboard_fab2(sch_1):page167_i84@mstr_discrete.res~
(chips)',
 PATH='I84',
 DRAWING='@BASEBOARD_FAB2_LIB.BASEBOARD_FAB2(SCH_1):PAGE167',
 WATTAGE='1/16W',
 TOLERANCE='1%',
 SEC_TYPE='0402',
 MATERIAL='CHIP',
 BOM_COST='SM_THERM',
 PHYS_PAGE='167',
 XY='(-4000,1550)',
 ROT='0',
 VER='1',
 VALUE='20.0',
 PACK_TYPE='0402',
 PART_NUMBER='G21796-173',
 LOCATION='R8D24',
 ROOM='TEMP_SENSORS',
 SEC='1',
 CDS_LIB='mstr_discrete',
 CDS_PART_NAME='RES_0402-20.0,1%,1/16W,CHIP,G2A',
 PRIM_FILE='./archive_libs/mstr_discrete/res/chips/chips.prt';

PART_NAME
 R8D25 'RES_0402-4.75K,1%,1/16W,CHIP,GA':
 ROOM='BMC_MISC';

SECTION_NUMBER 1
 '@BASEBOARD_FAB2_LIB.BASEBOARD_FAB2(SCH_1):PAGE157_I335@MSTR_DISCRETE.RES(CHIPS)':
 C_PATH='@baseboard_fab2_lib.baseboard_fab2(sch_1):page157_i335@mstr_discrete.re~
s(chips)',
 P_PATH='@baseboard_fab2_lib.baseboard_fab2(sch_1):page157_i335@mstr_discrete.re~
s(chips)',
 PATH='I335',
 DRAWING='@BASEBOARD_FAB2_LIB.BASEBOARD_FAB2(SCH_1):PAGE157',
 WATTAGE='1/16W',
 TOLERANCE='1%',
 SEC_TYPE='0402',
 MATERIAL='CHIP',
 BOM_COST='SM_CONTROLLER',
 PHYS_PAGE='157',
 XY='(-2275,1525)',
 ROT='0',
 VER='2',
 VALUE='4.75K',
 PACK_TYPE='0402',
 PART_NUMBER='G21796-072',
 LOCATION='R8D25',
 ROOM='BMC_MISC',
 SEC='1',
 CDS_LIB='mstr_discrete',
 CDS_PART_NAME='RES_0402-4.75K,1%,1/16W,CHIP,GA',
 PRIM_FILE='./archive_libs/mstr_discrete/res/chips/chips.prt';

PART_NAME
 R8D26 'RES_0402-4.75K,1%,1/16W,CHIP,GA':
 ROOM='FAST_PROCHOT';

SECTION_NUMBER 1
 '@BASEBOARD_FAB2_LIB.BASEBOARD_FAB2(SCH_1):PAGE170_I71@MSTR_DISCRETE.RES(CHIPS)':
 C_PATH='@baseboard_fab2_lib.baseboard_fab2(sch_1):page170_i71@mstr_discrete.res~
(chips)',
 P_PATH='@baseboard_fab2_lib.baseboard_fab2(sch_1):page170_i71@mstr_discrete.res~
(chips)',
 PATH='I71',
 DRAWING='@BASEBOARD_FAB2_LIB.BASEBOARD_FAB2(SCH_1):PAGE170',
 WATTAGE='1/16W',
 TOLERANCE='1%',
 SEC_TYPE='0402',
 MATERIAL='CHIP',
 BOM_COST='FAST_PROCHOT',
 PHYS_PAGE='170',
 XY='(-3150,5100)',
 ROT='0',
 VER='2',
 VALUE='4.75K',
 PACK_TYPE='0402',
 PART_NUMBER='G21796-072',
 LOCATION='R8D26',
 ROOM='FAST_PROCHOT',
 SEC='1',
 CDS_LIB='mstr_discrete',
 CDS_PART_NAME='RES_0402-4.75K,1%,1/16W,CHIP,GA',
 PRIM_FILE='./archive_libs/mstr_discrete/res/chips/chips.prt';

PART_NAME
 R8D27 'RES_0402-1.00K,1%,1/16W,CHIP,GA':
 ROOM='TEMP_SENSORS';

SECTION_NUMBER 1
 '@BASEBOARD_FAB2_LIB.BASEBOARD_FAB2(SCH_1):PAGE167_I50@MSTR_DISCRETE.RES(CHIPS)':
 C_PATH='@baseboard_fab2_lib.baseboard_fab2(sch_1):page167_i50@mstr_discrete.res~
(chips)',
 P_PATH='@baseboard_fab2_lib.baseboard_fab2(sch_1):page167_i50@mstr_discrete.res~
(chips)',
 PATH='I50',
 DRAWING='@BASEBOARD_FAB2_LIB.BASEBOARD_FAB2(SCH_1):PAGE167',
 WATTAGE='1/16W',
 TOLERANCE='1%',
 SEC_TYPE='0402',
 MATERIAL='CHIP',
 BOM_COST='SM_THERM',
 PHYS_PAGE='167',
 XY='(-3500,1300)',
 ROT='0',
 VER='2',
 VALUE='1.00K',
 PACK_TYPE='0402',
 PART_NUMBER='G21796-026',
 LOCATION='R8D27',
 ROOM='TEMP_SENSORS',
 SEC='1',
 CDS_LIB='mstr_discrete',
 CDS_PART_NAME='RES_0402-1.00K,1%,1/16W,CHIP,GA',
 PRIM_FILE='./archive_libs/mstr_discrete/res/chips/chips.prt';

PART_NAME
 R8D28 'RES_0402-1.00K,1%,1/16W,CHIP,GA':
 ROOM='TEMP_SENSORS';

SECTION_NUMBER 1
 '@BASEBOARD_FAB2_LIB.BASEBOARD_FAB2(SCH_1):PAGE167_I70@MSTR_DISCRETE.RES(CHIPS)':
 C_PATH='@baseboard_fab2_lib.baseboard_fab2(sch_1):page167_i70@mstr_discrete.res~
(chips)',
 P_PATH='@baseboard_fab2_lib.baseboard_fab2(sch_1):page167_i70@mstr_discrete.res~
(chips)',
 PATH='I70',
 DRAWING='@BASEBOARD_FAB2_LIB.BASEBOARD_FAB2(SCH_1):PAGE167',
 WATTAGE='1/16W',
 TOLERANCE='1%',
 SEC_TYPE='0402',
 MATERIAL='CHIP',
 BOM_COST='SM_THERM',
 PHYS_PAGE='167',
 XY='(-3550,1975)',
 ROT='0',
 VER='2',
 VALUE='1.00K',
 PACK_TYPE='0402',
 PART_NUMBER='G21796-026',
 LOCATION='R8D28',
 ROOM='TEMP_SENSORS',
 SEC='1',
 CDS_LIB='mstr_discrete',
 CDS_PART_NAME='RES_0402-1.00K,1%,1/16W,CHIP,GA',
 PRIM_FILE='./archive_libs/mstr_discrete/res/chips/chips.prt';

PART_NAME
 R8D29 'RES_0402-4.75K,1%,1/16W,CHIP,GA':
 ROOM='NVDIMM';

SECTION_NUMBER 1
 '@BASEBOARD_FAB2_LIB.BASEBOARD_FAB2(SCH_1):PAGE89_I26@MSTR_DISCRETE.RES(CHIPS)':
 C_PATH='@baseboard_fab2_lib.baseboard_fab2(sch_1):page89_i26@mstr_discrete.res(~
chips)',
 P_PATH='@baseboard_fab2_lib.baseboard_fab2(sch_1):page89_i26@mstr_discrete.res(~
chips)',
 PATH='I26',
 DRAWING='@BASEBOARD_FAB2_LIB.BASEBOARD_FAB2(SCH_1):PAGE89',
 WATTAGE='1/16W',
 TOLERANCE='1%',
 MATERIAL='CHIP',
 PHYS_PAGE='89',
 XY='(1750,4500)',
 ROT='0',
 VER='2',
 VALUE='4.75K',
 PACK_TYPE='0402',
 PART_NUMBER='G21796-072',
 LOCATION='R8D29',
 ROOM='NVDIMM',
 CDS_LIB='mstr_discrete',
 CDS_PART_NAME='RES_0402-4.75K,1%,1/16W,CHIP,GA',
 PRIM_FILE='./archive_libs/mstr_discrete/res/chips/chips.prt';

PART_NAME
 R8D30 'RES_0402-10.0K,1%,1/16W,CHIP,GA':
 ROOM='NV_DIMM';

SECTION_NUMBER 1
 '@BASEBOARD_FAB2_LIB.BASEBOARD_FAB2(SCH_1):PAGE89_I34@MSTR_DISCRETE.RES(CHIPS)':
 C_PATH='@baseboard_fab2_lib.baseboard_fab2(sch_1):page89_i34@mstr_discrete.res(~
chips)',
 P_PATH='@baseboard_fab2_lib.baseboard_fab2(sch_1):page89_i34@mstr_discrete.res(~
chips)',
 PATH='I34',
 DRAWING='@BASEBOARD_FAB2_LIB.BASEBOARD_FAB2(SCH_1):PAGE89',
 WATTAGE='1/16W',
 TOLERANCE='1%',
 SEC_TYPE='0402',
 MATERIAL='CHIP',
 BOM_COST='MEM_NV',
 PHYS_PAGE='89',
 XY='(775,3700)',
 ROT='0',
 VER='1',
 VALUE='10.0K',
 PACK_TYPE='0402',
 PART_NUMBER='G21796-016',
 LOCATION='R8D30',
 ROOM='NV_DIMM',
 SEC='1',
 CDS_LIB='mstr_discrete',
 CDS_PART_NAME='RES_0402-10.0K,1%,1/16W,CHIP,GA',
 PRIM_FILE='./archive_libs/mstr_discrete/res/chips/chips.prt';

PART_NAME
 R8D31 'RES_0402-4.75K,1%,1/16W,CHIP,GA':
 ROOM='NVDIMM';

SECTION_NUMBER 1
 '@BASEBOARD_FAB2_LIB.BASEBOARD_FAB2(SCH_1):PAGE89_I27@MSTR_DISCRETE.RES(CHIPS)':
 C_PATH='@baseboard_fab2_lib.baseboard_fab2(sch_1):page89_i27@mstr_discrete.res(~
chips)',
 P_PATH='@baseboard_fab2_lib.baseboard_fab2(sch_1):page89_i27@mstr_discrete.res(~
chips)',
 PATH='I27',
 DRAWING='@BASEBOARD_FAB2_LIB.BASEBOARD_FAB2(SCH_1):PAGE89',
 WATTAGE='1/16W',
 TOLERANCE='1%',
 MATERIAL='CHIP',
 PHYS_PAGE='89',
 XY='(2450,4725)',
 ROT='0',
 VER='2',
 VALUE='4.75K',
 PACK_TYPE='0402',
 PART_NUMBER='G21796-072',
 LOCATION='R8D31',
 ROOM='NVDIMM',
 CDS_LIB='mstr_discrete',
 CDS_PART_NAME='RES_0402-4.75K,1%,1/16W,CHIP,GA',
 PRIM_FILE='./archive_libs/mstr_discrete/res/chips/chips.prt';

PART_NAME
 R8D35 'RES_0402-0.0,5%,1/16W,CHIP,G21A':
 ROOM='TPM';

SECTION_NUMBER 1
 '@BASEBOARD_FAB2_LIB.BASEBOARD_FAB2(SCH_1):PAGE184_I92@MSTR_DISCRETE.RES(CHIPS)':
 C_PATH='@baseboard_fab2_lib.baseboard_fab2(sch_1):page184_i92@mstr_discrete.res~
(chips)',
 P_PATH='@baseboard_fab2_lib.baseboard_fab2(sch_1):page184_i92@mstr_discrete.res~
(chips)',
 PATH='I92',
 DRAWING='@BASEBOARD_FAB2_LIB.BASEBOARD_FAB2(SCH_1):PAGE184',
 WATTAGE='1/16W',
 TOLERANCE='5%',
 SEC_TYPE='0402',
 MATERIAL='CHIP',
 BOM_COST='MIO_SECURITY',
 PHYS_PAGE='184',
 XY='(-4750,-3575)',
 ROT='0',
 VER='1',
 VALUE='0.0',
 PACK_TYPE='0402',
 PART_NUMBER='G21497-005',
 LOCATION='R8D35',
 ROOM='TPM',
 SEC='1',
 CDS_LIB='mstr_discrete',
 CDS_PART_NAME='RES_0402-0.0,5%,1/16W,CHIP,G21A',
 PRIM_FILE='./archive_libs/mstr_discrete/res/chips/chips.prt';

PART_NAME
 R8D36 'RES_0402-33.2,1%,1/16W,CHIP,G2A':
 ROOM='BMC_MISC';

SECTION_NUMBER 1
 '@BASEBOARD_FAB2_LIB.BASEBOARD_FAB2(SCH_1):PAGE157_I388@MSTR_DISCRETE.RES(CHIPS)':
 C_PATH='@baseboard_fab2_lib.baseboard_fab2(sch_1):page157_i388@mstr_discrete.re~
s(chips)',
 P_PATH='@baseboard_fab2_lib.baseboard_fab2(sch_1):page157_i388@mstr_discrete.re~
s(chips)',
 PATH='I388',
 DRAWING='@BASEBOARD_FAB2_LIB.BASEBOARD_FAB2(SCH_1):PAGE157',
 POP='NOPOP',
 WATTAGE='1/16W',
 TOLERANCE='1%',
 SEC_TYPE='0402',
 MATERIAL='CHIP',
 BOM_COST='SM',
 PHYS_PAGE='157',
 XY='(-1425,1375)',
 ROT='0',
 VER='1',
 VALUE='33.2',
 PACK_TYPE='0402',
 PART_NUMBER='G21796-074',
 LOCATION='R8D36',
 ROOM='BMC_MISC',
 SEC='1',
 CDS_LIB='mstr_discrete',
 CDS_PART_NAME='RES_0402-33.2,1%,1/16W,CHIP,G2A',
 PRIM_FILE='./archive_libs/mstr_discrete/res/chips/chips.prt';

PART_NAME
 R8D37 'RES_0402-4.75K,1%,1/16W,CHIP,GA':
 ROOM='V_SUPER';

SECTION_NUMBER 1
 '@BASEBOARD_FAB2_LIB.BASEBOARD_FAB2(SCH_1):PAGE196_I115@MSTR_DISCRETE.RES(CHIPS)':
 C_PATH='@baseboard_fab2_lib.baseboard_fab2(sch_1):page196_i115@mstr_discrete.re~
s(chips)',
 P_PATH='@baseboard_fab2_lib.baseboard_fab2(sch_1):page196_i115@mstr_discrete.re~
s(chips)',
 PATH='I115',
 DRAWING='@BASEBOARD_FAB2_LIB.BASEBOARD_FAB2(SCH_1):PAGE196',
 WATTAGE='1/16W',
 TOLERANCE='1%',
 SEC_TYPE='0402',
 MATERIAL='CHIP',
 PHYS_PAGE='196',
 XY='(-1750,1450)',
 ROT='0',
 VER='2',
 VALUE='4.75K',
 PACK_TYPE='0402',
 PART_NUMBER='G21796-072',
 LOCATION='R8D37',
 ROOM='V_SUPER',
 SEC='1',
 CDS_LIB='mstr_discrete',
 CDS_PART_NAME='RES_0402-4.75K,1%,1/16W,CHIP,GA',
 PRIM_FILE='./archive_libs/mstr_discrete/res/chips/chips.prt';

PART_NAME
 R8D38 'RES_0402-100.0K,1%,1/16W,CHIP,A':
 ROOM='V_SUPER';

SECTION_NUMBER 1
 '@BASEBOARD_FAB2_LIB.BASEBOARD_FAB2(SCH_1):PAGE196_I112@MSTR_DISCRETE.RES(CHIPS)':
 C_PATH='@baseboard_fab2_lib.baseboard_fab2(sch_1):page196_i112@mstr_discrete.re~
s(chips)',
 P_PATH='@baseboard_fab2_lib.baseboard_fab2(sch_1):page196_i112@mstr_discrete.re~
s(chips)',
 PATH='I112',
 DRAWING='@BASEBOARD_FAB2_LIB.BASEBOARD_FAB2(SCH_1):PAGE196',
 NEW_VALUE='511K',
 CONFIG='64.51135.6DL',
 WATTAGE='1/16W',
 TOLERANCE='1%',
 SEC_TYPE='0402',
 MATERIAL='CHIP',
 PHYS_PAGE='196',
 XY='(-1750,2850)',
 ROT='0',
 VER='2',
 VALUE='100.0K',
 PACK_TYPE='0402',
 PART_NUMBER='G21796-010',
 LOCATION='R8D38',
 ROOM='V_SUPER',
 SEC='1',
 CDS_LIB='mstr_discrete',
 CDS_PART_NAME='RES_0402-100.0K,1%,1/16W,CHIP,A',
 PRIM_FILE='./archive_libs/mstr_discrete/res/chips/chips.prt';

PART_NAME
 R8D39 'RES_0402-49.9K,1%,1/16W,CHIP,GA':
 ROOM='V_SUPER';

SECTION_NUMBER 1
 '@BASEBOARD_FAB2_LIB.BASEBOARD_FAB2(SCH_1):PAGE196_I114@MSTR_DISCRETE.RES(CHIPS)':
 C_PATH='@baseboard_fab2_lib.baseboard_fab2(sch_1):page196_i114@mstr_discrete.re~
s(chips)',
 P_PATH='@baseboard_fab2_lib.baseboard_fab2(sch_1):page196_i114@mstr_discrete.re~
s(chips)',
 PATH='I114',
 DRAWING='@BASEBOARD_FAB2_LIB.BASEBOARD_FAB2(SCH_1):PAGE196',
 WATTAGE='1/16W',
 TOLERANCE='1%',
 SEC_TYPE='0402',
 MATERIAL='CHIP',
 PHYS_PAGE='196',
 XY='(-1750,1850)',
 ROT='0',
 VER='2',
 VALUE='49.9K',
 PACK_TYPE='0402',
 PART_NUMBER='G21796-048',
 LOCATION='R8D39',
 ROOM='V_SUPER',
 SEC='1',
 CDS_LIB='mstr_discrete',
 CDS_PART_NAME='RES_0402-49.9K,1%,1/16W,CHIP,GA',
 PRIM_FILE='./archive_libs/mstr_discrete/res/chips/chips.prt';

PART_NAME
 R8D40 'RES_0402-20.0K,1%,1/16W,CHIP,GA':
 ROOM='SB';

SECTION_NUMBER 1
 '@BASEBOARD_FAB2_LIB.BASEBOARD_FAB2(SCH_1):PAGE196_I130@MSTR_DISCRETE.RES(CHIPS)':
 C_PATH='@baseboard_fab2_lib.baseboard_fab2(sch_1):page196_i130@mstr_discrete.re~
s(chips)',
 P_PATH='@baseboard_fab2_lib.baseboard_fab2(sch_1):page196_i130@mstr_discrete.re~
s(chips)',
 PATH='I130',
 DRAWING='@BASEBOARD_FAB2_LIB.BASEBOARD_FAB2(SCH_1):PAGE196',
 WATTAGE='1/16W',
 TOLERANCE='1%',
 SEC_TYPE='0402',
 MATERIAL='CHIP',
 BOM_COST='SB',
 PHYS_PAGE='196',
 XY='(-1750,2400)',
 ROT='0',
 VER='2',
 VALUE='20.0K',
 PACK_TYPE='0402',
 PART_NUMBER='G21796-040',
 LOCATION='R8D40',
 ROOM='SB',
 SEC='1',
 CDS_LIB='mstr_discrete',
 CDS_PART_NAME='RES_0402-20.0K,1%,1/16W,CHIP,GA',
 PRIM_FILE='./archive_libs/mstr_discrete/res/chips/chips.prt';

PART_NAME
 R8D41 'RES_0402-10.0K,1%,1/16W,CHIP,GA':
 ROOM='V_SUPER';

SECTION_NUMBER 1
 '@BASEBOARD_FAB2_LIB.BASEBOARD_FAB2(SCH_1):PAGE196_I120@MSTR_DISCRETE.RES(CHIPS)':
 C_PATH='@baseboard_fab2_lib.baseboard_fab2(sch_1):page196_i120@mstr_discrete.re~
s(chips)',
 P_PATH='@baseboard_fab2_lib.baseboard_fab2(sch_1):page196_i120@mstr_discrete.re~
s(chips)',
 PATH='I120',
 DRAWING='@BASEBOARD_FAB2_LIB.BASEBOARD_FAB2(SCH_1):PAGE196',
 WATTAGE='1/16W',
 TOLERANCE='1%',
 SEC_TYPE='0402',
 MATERIAL='CHIP',
 PHYS_PAGE='196',
 XY='(50,2650)',
 ROT='0',
 VER='2',
 VALUE='10.0K',
 PACK_TYPE='0402',
 PART_NUMBER='G21796-016',
 LOCATION='R8D41',
 ROOM='V_SUPER',
 SEC='1',
 CDS_LIB='mstr_discrete',
 CDS_PART_NAME='RES_0402-10.0K,1%,1/16W,CHIP,GA',
 PRIM_FILE='./archive_libs/mstr_discrete/res/chips/chips.prt';

PART_NAME
 R8D42 'RES_0402-100.0,1%,1/16W,CHIP,GA':
 ROOM='V_SUPER';

SECTION_NUMBER 1
 '@BASEBOARD_FAB2_LIB.BASEBOARD_FAB2(SCH_1):PAGE196_I106@MSTR_DISCRETE.RES(CHIPS)':
 C_PATH='@baseboard_fab2_lib.baseboard_fab2(sch_1):page196_i106@mstr_discrete.re~
s(chips)',
 P_PATH='@baseboard_fab2_lib.baseboard_fab2(sch_1):page196_i106@mstr_discrete.re~
s(chips)',
 PATH='I106',
 DRAWING='@BASEBOARD_FAB2_LIB.BASEBOARD_FAB2(SCH_1):PAGE196',
 WATTAGE='1/16W',
 TOLERANCE='1%',
 SEC_TYPE='0402',
 MATERIAL='CHIP',
 PHYS_PAGE='196',
 XY='(1350,2400)',
 ROT='0',
 VER='1',
 VALUE='100.0',
 PACK_TYPE='0402',
 PART_NUMBER='G21796-017',
 LOCATION='R8D42',
 ROOM='V_SUPER',
 SEC='1',
 CDS_LIB='mstr_discrete',
 CDS_PART_NAME='RES_0402-100.0,1%,1/16W,CHIP,GA',
 PRIM_FILE='./archive_libs/mstr_discrete/res/chips/chips.prt';

PART_NAME
 R8D43 'RES_0402-0.0,5%,1/16W,CHIP,G21A':
 ROOM='CLOCK_CPU1_OSC';

SECTION_NUMBER 1
 '@BASEBOARD_FAB2_LIB.BASEBOARD_FAB2(SCH_1):PAGE104_I93@MSTR_DISCRETE.RES(CHIPS)':
 C_PATH='@baseboard_fab2_lib.baseboard_fab2(sch_1):page104_i93@mstr_discrete.res~
(chips)',
 P_PATH='@baseboard_fab2_lib.baseboard_fab2(sch_1):page104_i93@mstr_discrete.res~
(chips)',
 PATH='I93',
 DRAWING='@BASEBOARD_FAB2_LIB.BASEBOARD_FAB2(SCH_1):PAGE104',
 WATTAGE='1/16W',
 TOLERANCE='5%',
 SEC_TYPE='0402',
 MATERIAL='CHIP',
 PHYS_PAGE='104',
 XY='(550,2200)',
 ROT='0',
 VER='1',
 VALUE='0.0',
 PACK_TYPE='0402',
 PART_NUMBER='G21497-005',
 LOCATION='R8D43',
 ROOM='CLOCK_CPU1_OSC',
 SEC='1',
 CDS_LIB='mstr_discrete',
 CDS_PART_NAME='RES_0402-0.0,5%,1/16W,CHIP,G21A',
 PRIM_FILE='./archive_libs/mstr_discrete/res/chips/chips.prt';

PART_NAME
 R8D44 'RES_0402-10.0K,1%,1/16W,CHIP,GA':
 ROOM='SB';

SECTION_NUMBER 1
 '@BASEBOARD_FAB2_LIB.BASEBOARD_FAB2(SCH_1):PAGE133_I362@MSTR_DISCRETE.RES(CHIPS)':
 C_PATH='@baseboard_fab2_lib.baseboard_fab2(sch_1):page133_i362@mstr_discrete.re~
s(chips)',
 P_PATH='@baseboard_fab2_lib.baseboard_fab2(sch_1):page133_i362@mstr_discrete.re~
s(chips)',
 PATH='I362',
 DRAWING='@BASEBOARD_FAB2_LIB.BASEBOARD_FAB2(SCH_1):PAGE133',
 WATTAGE='1/16W',
 TOLERANCE='1%',
 SEC_TYPE='0402',
 MATERIAL='CHIP',
 BOM_COST='SB',
 PHYS_PAGE='133',
 XY='(-2475,2450)',
 ROT='0',
 VER='1',
 VALUE='10.0K',
 PACK_TYPE='0402',
 PART_NUMBER='G21796-016',
 LOCATION='R8D44',
 ROOM='SB',
 SEC='1',
 CDS_LIB='mstr_discrete',
 CDS_PART_NAME='RES_0402-10.0K,1%,1/16W,CHIP,GA',
 PRIM_FILE='./archive_libs/mstr_discrete/res/chips/chips.prt';

PART_NAME
 R8E1 'RES_0402-0.0,5%,1/16W,CHIP,G21A':
 ROOM='TPM';

SECTION_NUMBER 1
 '@BASEBOARD_FAB2_LIB.BASEBOARD_FAB2(SCH_1):PAGE184_I99@MSTR_DISCRETE.RES(CHIPS)':
 C_PATH='@baseboard_fab2_lib.baseboard_fab2(sch_1):page184_i99@mstr_discrete.res~
(chips)',
 P_PATH='@baseboard_fab2_lib.baseboard_fab2(sch_1):page184_i99@mstr_discrete.res~
(chips)',
 PATH='I99',
 DRAWING='@BASEBOARD_FAB2_LIB.BASEBOARD_FAB2(SCH_1):PAGE184',
 WATTAGE='1/16W',
 TOLERANCE='5%',
 MATERIAL='CHIP',
 BOM_COST='MIO_SECURITY',
 PHYS_PAGE='184',
 XY='(-2575,-3425)',
 ROT='0',
 VER='1',
 VALUE='0.0',
 PACK_TYPE='0402',
 PART_NUMBER='G21497-005',
 LOCATION='R8E1',
 ROOM='TPM',
 CDS_LIB='mstr_discrete',
 CDS_PART_NAME='RES_0402-0.0,5%,1/16W,CHIP,G21A',
 PRIM_FILE='./archive_libs/mstr_discrete/res/chips/chips.prt';

PART_NAME
 R8E2 'RES_0402-1.00K,1%,1/16W,CHIP,GA':
 ROOM='DEBUG';

SECTION_NUMBER 1
 '@BASEBOARD_FAB2_LIB.BASEBOARD_FAB2(SCH_1):PAGE111_I89@MSTR_DISCRETE.RES(CHIPS)':
 C_PATH='@baseboard_fab2_lib.baseboard_fab2(sch_1):page111_i89@mstr_discrete.res~
(chips)',
 P_PATH='@baseboard_fab2_lib.baseboard_fab2(sch_1):page111_i89@mstr_discrete.res~
(chips)',
 PATH='I89',
 DRAWING='@BASEBOARD_FAB2_LIB.BASEBOARD_FAB2(SCH_1):PAGE111',
 WATTAGE='1/16W',
 TOLERANCE='1%',
 SEC_TYPE='0402',
 MATERIAL='CHIP',
 BOM_COST='DEBUG',
 PHYS_PAGE='111',
 XY='(2050,4550)',
 ROT='0',
 VER='1',
 VALUE='1.00K',
 PACK_TYPE='0402',
 PART_NUMBER='G21796-026',
 LOCATION='R8E2',
 ROOM='DEBUG',
 SEC='1',
 CDS_LIB='mstr_discrete',
 CDS_PART_NAME='RES_0402-1.00K,1%,1/16W,CHIP,GA',
 PRIM_FILE='./archive_libs/mstr_discrete/res/chips/chips.prt';

PART_NAME
 R8E3 'RES_0402-4.75K,1%,1/16W,CHIP,GA':
 ROOM='SB_PU_PD';

SECTION_NUMBER 1
 '@BASEBOARD_FAB2_LIB.BASEBOARD_FAB2(SCH_1):PAGE133_I371@MSTR_DISCRETE.RES(CHIPS)':
 C_PATH='@baseboard_fab2_lib.baseboard_fab2(sch_1):page133_i371@mstr_discrete.re~
s(chips)',
 P_PATH='@baseboard_fab2_lib.baseboard_fab2(sch_1):page133_i371@mstr_discrete.re~
s(chips)',
 PATH='I371',
 DRAWING='@BASEBOARD_FAB2_LIB.BASEBOARD_FAB2(SCH_1):PAGE133',
 WATTAGE='1/16W',
 TOLERANCE='1%',
 SEC_TYPE='0402',
 MATERIAL='CHIP',
 PHYS_PAGE='133',
 XY='(-4700,3475)',
 ROT='0',
 VER='1',
 VALUE='4.75K',
 PACK_TYPE='0402',
 PART_NUMBER='G21796-072',
 LOCATION='R8E3',
 ROOM='SB_PU_PD',
 SEC='1',
 CDS_LIB='mstr_discrete',
 CDS_PART_NAME='RES_0402-4.75K,1%,1/16W,CHIP,GA',
 PRIM_FILE='./archive_libs/mstr_discrete/res/chips/chips.prt';

PART_NAME
 R8E4 'RES_0402-1.00K,1%,1/16W,EMPTY,A':
 ROOM='SB';

SECTION_NUMBER 1
 '@BASEBOARD_FAB2_LIB.BASEBOARD_FAB2(SCH_1):PAGE125_I24@MSTR_DISCRETE.RES(CHIPS)':
 C_PATH='@baseboard_fab2_lib.baseboard_fab2(sch_1):page125_i24@mstr_discrete.res~
(chips)',
 P_PATH='@baseboard_fab2_lib.baseboard_fab2(sch_1):page125_i24@mstr_discrete.res~
(chips)',
 PATH='I24',
 DRAWING='@BASEBOARD_FAB2_LIB.BASEBOARD_FAB2(SCH_1):PAGE125',
 WATTAGE='1/16W',
 TOLERANCE='1%',
 MATERIAL='EMPTY',
 BOM_COST='SB',
 PHYS_PAGE='125',
 XY='(-950,2750)',
 ROT='0',
 VER='2',
 VALUE='1.00K',
 PACK_TYPE='0402',
 PART_NUMBER='G21796-026',
 LOCATION='R8E4',
 ROOM='SB',
 CDS_LIB='mstr_discrete',
 CDS_PART_NAME='RES_0402-1.00K,1%,1/16W,EMPTY,A',
 PRIM_FILE='./archive_libs/mstr_discrete/res/chips/chips.prt';

PART_NAME
 R8E5 'RES_0402-33.2,1%,1/16W,CHIP,G2A':
 ROOM='IO_SLOT';

SECTION_NUMBER 1
 '@BASEBOARD_FAB2_LIB.BASEBOARD_FAB2(SCH_1):PAGE181_I63@MSTR_DISCRETE.RES(CHIPS)':
 C_PATH='@baseboard_fab2_lib.baseboard_fab2(sch_1):page181_i63@mstr_discrete.res~
(chips)',
 P_PATH='@baseboard_fab2_lib.baseboard_fab2(sch_1):page181_i63@mstr_discrete.res~
(chips)',
 PATH='I63',
 DRAWING='@BASEBOARD_FAB2_LIB.BASEBOARD_FAB2(SCH_1):PAGE181',
 WATTAGE='1/16W',
 TOLERANCE='1%',
 SEC_TYPE='0402',
 MATERIAL='CHIP',
 PHYS_PAGE='181',
 XY='(1650,825)',
 ROT='0',
 VER='1',
 VALUE='33.2',
 PACK_TYPE='0402',
 PART_NUMBER='G21796-074',
 LOCATION='R8E5',
 ROOM='IO_SLOT',
 SEC='1',
 CDS_LIB='mstr_discrete',
 CDS_PART_NAME='RES_0402-33.2,1%,1/16W,CHIP,G2A',
 PRIM_FILE='./archive_libs/mstr_discrete/res/chips/chips.prt';

PART_NAME
 R8E6 'RES_0402-1.00K,1%,1/16W,EMPTY,A':
 ROOM='SB';

SECTION_NUMBER 1
 '@BASEBOARD_FAB2_LIB.BASEBOARD_FAB2(SCH_1):PAGE125_I21@MSTR_DISCRETE.RES(CHIPS)':
 C_PATH='@baseboard_fab2_lib.baseboard_fab2(sch_1):page125_i21@mstr_discrete.res~
(chips)',
 P_PATH='@baseboard_fab2_lib.baseboard_fab2(sch_1):page125_i21@mstr_discrete.res~
(chips)',
 PATH='I21',
 DRAWING='@BASEBOARD_FAB2_LIB.BASEBOARD_FAB2(SCH_1):PAGE125',
 WATTAGE='1/16W',
 TOLERANCE='1%',
 SEC_TYPE='0402',
 MATERIAL='EMPTY',
 BOM_COST='SB',
 PHYS_PAGE='125',
 XY='(-950,3150)',
 ROT='0',
 VER='2',
 VALUE='1.00K',
 PACK_TYPE='0402',
 PART_NUMBER='G21796-026',
 LOCATION='R8E6',
 ROOM='SB',
 SEC='1',
 CDS_LIB='mstr_discrete',
 CDS_PART_NAME='RES_0402-1.00K,1%,1/16W,EMPTY,A',
 PRIM_FILE='./archive_libs/mstr_discrete/res/chips/chips.prt';

PART_NAME
 R8E7 'RES_0402-22.1,1.0%,1/16W,CHIP,A':
 ROOM='V_SUPER';

SECTION_NUMBER 1
 '@BASEBOARD_FAB2_LIB.BASEBOARD_FAB2(SCH_1):PAGE196_I90@MSTR_DISCRETE.RES(CHIPS)':
 C_PATH='@baseboard_fab2_lib.baseboard_fab2(sch_1):page196_i90@mstr_discrete.res~
(chips)',
 P_PATH='@baseboard_fab2_lib.baseboard_fab2(sch_1):page196_i90@mstr_discrete.res~
(chips)',
 PATH='I90',
 DRAWING='@BASEBOARD_FAB2_LIB.BASEBOARD_FAB2(SCH_1):PAGE196',
 WATTAGE='1/16W',
 TOLERANCE='1.0%',
 SEC_TYPE='0402',
 MATERIAL='CHIP',
 PHYS_PAGE='196',
 XY='(1325,3000)',
 ROT='0',
 VER='1',
 VALUE='22.1',
 PACK_TYPE='0402',
 PART_NUMBER='G21796-250',
 LOCATION='R8E7',
 ROOM='V_SUPER',
 SEC='1',
 CDS_LIB='mstr_discrete',
 CDS_PART_NAME='RES_0402-22.1,1.0%,1/16W,CHIP,A',
 PRIM_FILE='./archive_libs/mstr_discrete/res/chips/chips.prt';

PART_NAME
 R8E9 'RES_0402-33.2,1%,1/16W,CHIP,G2A':
 ROOM='TPM';

SECTION_NUMBER 1
 '@BASEBOARD_FAB2_LIB.BASEBOARD_FAB2(SCH_1):PAGE184_I88@MSTR_DISCRETE.RES(CHIPS)':
 C_PATH='@baseboard_fab2_lib.baseboard_fab2(sch_1):page184_i88@mstr_discrete.res~
(chips)',
 P_PATH='@baseboard_fab2_lib.baseboard_fab2(sch_1):page184_i88@mstr_discrete.res~
(chips)',
 PATH='I88',
 DRAWING='@BASEBOARD_FAB2_LIB.BASEBOARD_FAB2(SCH_1):PAGE184',
 WATTAGE='1/16W',
 TOLERANCE='1%',
 SEC_TYPE='0402',
 MATERIAL='CHIP',
 BOM_COST='MIO_SECURITY',
 PHYS_PAGE='184',
 XY='(-4750,-3175)',
 ROT='0',
 VER='1',
 VALUE='33.2',
 PACK_TYPE='0402',
 PART_NUMBER='G21796-074',
 LOCATION='R8E9',
 ROOM='TPM',
 SEC='1',
 CDS_LIB='mstr_discrete',
 CDS_PART_NAME='RES_0402-33.2,1%,1/16W,CHIP,G2A',
 PRIM_FILE='./archive_libs/mstr_discrete/res/chips/chips.prt';

PART_NAME
 R8E10 'RES_0402-33.2,1%,1/16W,CHIP,G2A':
 ROOM='TPM';

SECTION_NUMBER 1
 '@BASEBOARD_FAB2_LIB.BASEBOARD_FAB2(SCH_1):PAGE184_I95@MSTR_DISCRETE.RES(CHIPS)':
 C_PATH='@baseboard_fab2_lib.baseboard_fab2(sch_1):page184_i95@mstr_discrete.res~
(chips)',
 P_PATH='@baseboard_fab2_lib.baseboard_fab2(sch_1):page184_i95@mstr_discrete.res~
(chips)',
 PATH='I95',
 DRAWING='@BASEBOARD_FAB2_LIB.BASEBOARD_FAB2(SCH_1):PAGE184',
 WATTAGE='1/16W',
 TOLERANCE='1%',
 SEC_TYPE='0402',
 MATERIAL='CHIP',
 BOM_COST='MIO_SECURITY',
 PHYS_PAGE='184',
 XY='(-4725,-3375)',
 ROT='0',
 VER='1',
 VALUE='33.2',
 PACK_TYPE='0402',
 PART_NUMBER='G21796-074',
 LOCATION='R8E10',
 ROOM='TPM',
 SEC='1',
 CDS_LIB='mstr_discrete',
 CDS_PART_NAME='RES_0402-33.2,1%,1/16W,CHIP,G2A',
 PRIM_FILE='./archive_libs/mstr_discrete/res/chips/chips.prt';

PART_NAME
 R8E11 'RES_0402-0.0,5%,1/16W,EMPTY,G2A':
 ROOM='BMC_MISC';

SECTION_NUMBER 1
 '@BASEBOARD_FAB2_LIB.BASEBOARD_FAB2(SCH_1):PAGE156_I279@MSTR_DISCRETE.RES(CHIPS)':
 C_PATH='@baseboard_fab2_lib.baseboard_fab2(sch_1):page156_i279@mstr_discrete.re~
s(chips)',
 P_PATH='@baseboard_fab2_lib.baseboard_fab2(sch_1):page156_i279@mstr_discrete.re~
s(chips)',
 PATH='I279',
 DRAWING='@BASEBOARD_FAB2_LIB.BASEBOARD_FAB2(SCH_1):PAGE156',
 WATTAGE='1/16W',
 TOLERANCE='5%',
 SEC_TYPE='0402',
 MATERIAL='EMPTY',
 BOM_COST='SM_CONTROLLER',
 PHYS_PAGE='156',
 XY='(-6600,2350)',
 ROT='0',
 VER='1',
 VALUE='0.0',
 PACK_TYPE='0402',
 PART_NUMBER='G21497-005',
 LOCATION='R8E11',
 ROOM='BMC_MISC',
 SEC='1',
 CDS_LIB='mstr_discrete',
 CDS_PART_NAME='RES_0402-0.0,5%,1/16W,EMPTY,G2A',
 PRIM_FILE='./archive_libs/mstr_discrete/res/chips/chips.prt';

PART_NAME
 R8E12 'RES_0402-4.75K,1%,1/16W,EMPTY,A':
 ROOM='IO_SLOT';

SECTION_NUMBER 1
 '@BASEBOARD_FAB2_LIB.BASEBOARD_FAB2(SCH_1):PAGE198_I78@MSTR_DISCRETE.RES(CHIPS)':
 C_PATH='@baseboard_fab2_lib.baseboard_fab2(sch_1):page198_i78@mstr_discrete.res~
(chips)',
 P_PATH='@baseboard_fab2_lib.baseboard_fab2(sch_1):page198_i78@mstr_discrete.res~
(chips)',
 PATH='I78',
 DRAWING='@BASEBOARD_FAB2_LIB.BASEBOARD_FAB2(SCH_1):PAGE198',
 WATTAGE='1/16W',
 TOLERANCE='1%',
 SEC_TYPE='0402',
 MATERIAL='EMPTY',
 BOM_COST='IO_SLOT',
 PHYS_PAGE='198',
 XY='(-6925,3050)',
 ROT='0',
 VER='2',
 VALUE='4.75K',
 PACK_TYPE='0402',
 PART_NUMBER='G21796-072',
 LOCATION='R8E12',
 ROOM='IO_SLOT',
 SEC='1',
 CDS_LIB='mstr_discrete',
 CDS_PART_NAME='RES_0402-4.75K,1%,1/16W,EMPTY,A',
 PRIM_FILE='./archive_libs/mstr_discrete/res/chips/chips.prt';

PART_NAME
 R8E13 'RES_0402-33.2,1%,1/16W,CHIP,G2A':
 ROOM='TPM';

SECTION_NUMBER 1
 '@BASEBOARD_FAB2_LIB.BASEBOARD_FAB2(SCH_1):PAGE184_I93@MSTR_DISCRETE.RES(CHIPS)':
 C_PATH='@baseboard_fab2_lib.baseboard_fab2(sch_1):page184_i93@mstr_discrete.res~
(chips)',
 P_PATH='@baseboard_fab2_lib.baseboard_fab2(sch_1):page184_i93@mstr_discrete.res~
(chips)',
 PATH='I93',
 DRAWING='@BASEBOARD_FAB2_LIB.BASEBOARD_FAB2(SCH_1):PAGE184',
 WATTAGE='1/16W',
 TOLERANCE='1%',
 SEC_TYPE='0402',
 MATERIAL='CHIP',
 BOM_COST='MIO_SECURITY',
 PHYS_PAGE='184',
 XY='(-4725,-3475)',
 ROT='0',
 VER='1',
 VALUE='33.2',
 PACK_TYPE='0402',
 PART_NUMBER='G21796-074',
 LOCATION='R8E13',
 ROOM='TPM',
 SEC='1',
 CDS_LIB='mstr_discrete',
 CDS_PART_NAME='RES_0402-33.2,1%,1/16W,CHIP,G2A',
 PRIM_FILE='./archive_libs/mstr_discrete/res/chips/chips.prt';

PART_NAME
 R8E14 'RES_0402-4.75K,1%,1/16W,CHIP,GA':
 ROOM='SB';

SECTION_NUMBER 1
 '@BASEBOARD_FAB2_LIB.BASEBOARD_FAB2(SCH_1):PAGE136_I133@MSTR_DISCRETE.RES(CHIPS)':
 C_PATH='@baseboard_fab2_lib.baseboard_fab2(sch_1):page136_i133@mstr_discrete.re~
s(chips)',
 P_PATH='@baseboard_fab2_lib.baseboard_fab2(sch_1):page136_i133@mstr_discrete.re~
s(chips)',
 PATH='I133',
 DRAWING='@BASEBOARD_FAB2_LIB.BASEBOARD_FAB2(SCH_1):PAGE136',
 WATTAGE='1/16W',
 TOLERANCE='1%',
 SEC_TYPE='0402',
 MATERIAL='CHIP',
 PHYS_PAGE='136',
 XY='(-550,1900)',
 ROT='0',
 VER='2',
 VALUE='4.75K',
 PACK_TYPE='0402',
 PART_NUMBER='G21796-072',
 LOCATION='R8E14',
 ROOM='SB',
 SEC='1',
 CDS_LIB='mstr_discrete',
 CDS_PART_NAME='RES_0402-4.75K,1%,1/16W,CHIP,GA',
 PRIM_FILE='./archive_libs/mstr_discrete/res/chips/chips.prt';

PART_NAME
 R8E16 'RES_0402-20.0K,1%,1/16W,CHIP,GA':
 ROOM='SB';

SECTION_NUMBER 1
 '@BASEBOARD_FAB2_LIB.BASEBOARD_FAB2(SCH_1):PAGE136_I140@MSTR_DISCRETE.RES(CHIPS)':
 C_PATH='@baseboard_fab2_lib.baseboard_fab2(sch_1):page136_i140@mstr_discrete.re~
s(chips)',
 P_PATH='@baseboard_fab2_lib.baseboard_fab2(sch_1):page136_i140@mstr_discrete.re~
s(chips)',
 PATH='I140',
 DRAWING='@BASEBOARD_FAB2_LIB.BASEBOARD_FAB2(SCH_1):PAGE136',
 WATTAGE='1/16W',
 TOLERANCE='1%',
 SEC_TYPE='0402',
 MATERIAL='CHIP',
 BOM_COST='SB',
 PHYS_PAGE='136',
 XY='(0,3900)',
 ROT='0',
 VER='2',
 VALUE='20.0K',
 PACK_TYPE='0402',
 PART_NUMBER='G21796-040',
 LOCATION='R8E16',
 ROOM='SB',
 SEC='1',
 CDS_LIB='mstr_discrete',
 CDS_PART_NAME='RES_0402-20.0K,1%,1/16W,CHIP,GA',
 PRIM_FILE='./archive_libs/mstr_discrete/res/chips/chips.prt';

PART_NAME
 R8E17 'RES_0402-33.2,1%,1/16W,CHIP,G2A':
 ROOM='PCIE_WAKE_BUFFER';

SECTION_NUMBER 1
 '@BASEBOARD_FAB2_LIB.BASEBOARD_FAB2(SCH_1):PAGE142_I2@MSTR_DISCRETE.RES(CHIPS)':
 C_PATH='@baseboard_fab2_lib.baseboard_fab2(sch_1):page142_i2@mstr_discrete.res(~
chips)',
 P_PATH='@baseboard_fab2_lib.baseboard_fab2(sch_1):page142_i2@mstr_discrete.res(~
chips)',
 PATH='I2',
 DRAWING='@BASEBOARD_FAB2_LIB.BASEBOARD_FAB2(SCH_1):PAGE142',
 WATTAGE='1/16W',
 TOLERANCE='1%',
 SEC_TYPE='0402',
 MATERIAL='CHIP',
 BOM_COST='SB',
 PHYS_PAGE='142',
 XY='(-2600,2250)',
 ROT='0',
 VER='1',
 VALUE='33.2',
 PACK_TYPE='0402',
 PART_NUMBER='G21796-074',
 LOCATION='R8E17',
 ROOM='PCIE_WAKE_BUFFER',
 SEC='1',
 CDS_LIB='mstr_discrete',
 CDS_PART_NAME='RES_0402-33.2,1%,1/16W,CHIP,G2A',
 PRIM_FILE='./archive_libs/mstr_discrete/res/chips/chips.prt';

PART_NAME
 R8E18 'RES_0402-1.0K,0.1%,1/16W,CHIP,A':
 ROOM='P5V_STBY_VR',
 REUSE_ID='34';

SECTION_NUMBER 1
 '@BASEBOARD_FAB2_LIB.BASEBOARD_FAB2(SCH_1):PAGE241_I9@MSTR_DISCRETE.RES(CHIPS)':
 C_PATH='@baseboard_fab2_lib.baseboard_fab2(sch_1):page241_i9@mstr_discrete.res(~
chips)',
 P_PATH='@baseboard_fab2_lib.baseboard_fab2(sch_1):page241_i9@mstr_discrete.res(~
chips)',
 PATH='I9',
 DRAWING='@BASEBOARD_FAB2_LIB.BASEBOARD_FAB2(SCH_1):PAGE241',
 WATTAGE='1/16W',
 TOLERANCE='0.1%',
 SEC_TYPE='0402',
 MATERIAL='CHIP',
 BOM_COST='P5V_STBY_VR',
 PHYS_PAGE='241',
 REUSE_ID='34',
 XY='(2550,3875)',
 ROT='0',
 VER='2',
 VALUE='1.0K',
 PACK_TYPE='0402',
 PART_NUMBER='G85996-004',
 LOCATION='R8E18',
 ROOM='P5V_STBY_VR',
 SEC='1',
 CDS_LIB='mstr_discrete',
 CDS_PART_NAME='RES_0402-1.0K,0.1%,1/16W,CHIP,A',
 PRIM_FILE='./archive_libs/mstr_discrete/res/chips/chips.prt';

PART_NAME
 R8E19 'RES_0402-4.75K,1%,1/16W,EMPTY,A':
 ROOM='BMC_MISC';

SECTION_NUMBER 1
 '@BASEBOARD_FAB2_LIB.BASEBOARD_FAB2(SCH_1):PAGE157_I361@MSTR_DISCRETE.RES(CHIPS)':
 C_PATH='@baseboard_fab2_lib.baseboard_fab2(sch_1):page157_i361@mstr_discrete.re~
s(chips)',
 P_PATH='@baseboard_fab2_lib.baseboard_fab2(sch_1):page157_i361@mstr_discrete.re~
s(chips)',
 PATH='I361',
 DRAWING='@BASEBOARD_FAB2_LIB.BASEBOARD_FAB2(SCH_1):PAGE157',
 WATTAGE='1/16W',
 TOLERANCE='1%',
 SEC_TYPE='0402',
 MATERIAL='EMPTY',
 BOM_COST='SM_CONTROLLER',
 PHYS_PAGE='157',
 XY='(-7175,2200)',
 ROT='0',
 VER='1',
 VALUE='4.75K',
 PACK_TYPE='0402',
 PART_NUMBER='G21796-072',
 LOCATION='R8E19',
 ROOM='BMC_MISC',
 SEC='1',
 CDS_LIB='mstr_discrete',
 CDS_PART_NAME='RES_0402-4.75K,1%,1/16W,EMPTY,A',
 PRIM_FILE='./archive_libs/mstr_discrete/res/chips/chips.prt';

PART_NAME
 R8E20 'RES_0402-33.2,1%,1/16W,CHIP,G2A':
 ROOM='SB';

SECTION_NUMBER 1
 '@BASEBOARD_FAB2_LIB.BASEBOARD_FAB2(SCH_1):PAGE136_I126@MSTR_DISCRETE.RES(CHIPS)':
 C_PATH='@baseboard_fab2_lib.baseboard_fab2(sch_1):page136_i126@mstr_discrete.re~
s(chips)',
 P_PATH='@baseboard_fab2_lib.baseboard_fab2(sch_1):page136_i126@mstr_discrete.re~
s(chips)',
 PATH='I126',
 DRAWING='@BASEBOARD_FAB2_LIB.BASEBOARD_FAB2(SCH_1):PAGE136',
 WATTAGE='1/16W',
 TOLERANCE='1%',
 SEC_TYPE='0402',
 MATERIAL='CHIP',
 BOM_COST='SB',
 PHYS_PAGE='136',
 XY='(1000,2300)',
 ROT='0',
 VER='1',
 VALUE='33.2',
 PACK_TYPE='0402',
 PART_NUMBER='G21796-074',
 LOCATION='R8E20',
 ROOM='SB',
 SEC='1',
 CDS_LIB='mstr_discrete',
 CDS_PART_NAME='RES_0402-33.2,1%,1/16W,CHIP,G2A',
 PRIM_FILE='./archive_libs/mstr_discrete/res/chips/chips.prt';

PART_NAME
 R8E21 'RES_0402-0.0,5%,1/16W,CHIP,G21A':
 ROOM='PCIE_WAKE_BUFFER';

SECTION_NUMBER 1
 '@BASEBOARD_FAB2_LIB.BASEBOARD_FAB2(SCH_1):PAGE142_I33@MSTR_DISCRETE.RES(CHIPS)':
 C_PATH='@baseboard_fab2_lib.baseboard_fab2(sch_1):page142_i33@mstr_discrete.res~
(chips)',
 P_PATH='@baseboard_fab2_lib.baseboard_fab2(sch_1):page142_i33@mstr_discrete.res~
(chips)',
 PATH='I33',
 DRAWING='@BASEBOARD_FAB2_LIB.BASEBOARD_FAB2(SCH_1):PAGE142',
 WATTAGE='1/16W',
 TOLERANCE='5%',
 SEC_TYPE='0402',
 MATERIAL='CHIP',
 PHYS_PAGE='142',
 XY='(-4550,2850)',
 ROT='0',
 VER='1',
 VALUE='0.0',
 PACK_TYPE='0402',
 PART_NUMBER='G21497-005',
 LOCATION='R8E21',
 ROOM='PCIE_WAKE_BUFFER',
 SEC='1',
 CDS_LIB='mstr_discrete',
 CDS_PART_NAME='RES_0402-0.0,5%,1/16W,CHIP,G21A',
 PRIM_FILE='./archive_libs/mstr_discrete/res/chips/chips.prt';

PART_NAME
 R8E22 'RES_0402-4.75K,1%,1/16W,CHIP,GA':
 ROOM='BMC_MISC';

SECTION_NUMBER 1
 '@BASEBOARD_FAB2_LIB.BASEBOARD_FAB2(SCH_1):PAGE156_I215@MSTR_DISCRETE.RES(CHIPS)':
 C_PATH='@baseboard_fab2_lib.baseboard_fab2(sch_1):page156_i215@mstr_discrete.re~
s(chips)',
 P_PATH='@baseboard_fab2_lib.baseboard_fab2(sch_1):page156_i215@mstr_discrete.re~
s(chips)',
 PATH='I215',
 DRAWING='@BASEBOARD_FAB2_LIB.BASEBOARD_FAB2(SCH_1):PAGE156',
 WATTAGE='1/16W',
 TOLERANCE='1%',
 SEC_TYPE='0402',
 MATERIAL='CHIP',
 BOM_COST='SM_CONTROLLER',
 PHYS_PAGE='156',
 XY='(-6825,3025)',
 ROT='0',
 VER='2',
 VALUE='4.75K',
 PACK_TYPE='0402',
 PART_NUMBER='G21796-072',
 LOCATION='R8E22',
 ROOM='BMC_MISC',
 SEC='1',
 CDS_LIB='mstr_discrete',
 CDS_PART_NAME='RES_0402-4.75K,1%,1/16W,CHIP,GA',
 PRIM_FILE='./archive_libs/mstr_discrete/res/chips/chips.prt';

PART_NAME
 R8E23 'RES_0402-4.75K,1%,1/16W,CHIP,GA':
 ROOM='PCIE_WAKE_BUFFER';

SECTION_NUMBER 1
 '@BASEBOARD_FAB2_LIB.BASEBOARD_FAB2(SCH_1):PAGE142_I3@MSTR_DISCRETE.RES(CHIPS)':
 C_PATH='@baseboard_fab2_lib.baseboard_fab2(sch_1):page142_i3@mstr_discrete.res(~
chips)',
 P_PATH='@baseboard_fab2_lib.baseboard_fab2(sch_1):page142_i3@mstr_discrete.res(~
chips)',
 PATH='I3',
 DRAWING='@BASEBOARD_FAB2_LIB.BASEBOARD_FAB2(SCH_1):PAGE142',
 WATTAGE='1/16W',
 TOLERANCE='1%',
 SEC_TYPE='0402',
 MATERIAL='CHIP',
 BOM_COST='SB',
 PHYS_PAGE='142',
 XY='(-2850,2700)',
 ROT='0',
 VER='1',
 VALUE='4.75K',
 PACK_TYPE='0402',
 PART_NUMBER='G21796-072',
 LOCATION='R8E23',
 ROOM='PCIE_WAKE_BUFFER',
 SEC='1',
 CDS_LIB='mstr_discrete',
 CDS_PART_NAME='RES_0402-4.75K,1%,1/16W,CHIP,GA',
 PRIM_FILE='./archive_libs/mstr_discrete/res/chips/chips.prt';

PART_NAME
 R8E24 'RES_0402-33.2,1%,1/16W,CHIP,G2A':
 ROOM='BMC_MISC';

SECTION_NUMBER 1
 '@BASEBOARD_FAB2_LIB.BASEBOARD_FAB2(SCH_1):PAGE156_I214@MSTR_DISCRETE.RES(CHIPS)':
 C_PATH='@baseboard_fab2_lib.baseboard_fab2(sch_1):page156_i214@mstr_discrete.re~
s(chips)',
 P_PATH='@baseboard_fab2_lib.baseboard_fab2(sch_1):page156_i214@mstr_discrete.re~
s(chips)',
 PATH='I214',
 DRAWING='@BASEBOARD_FAB2_LIB.BASEBOARD_FAB2(SCH_1):PAGE156',
 WATTAGE='1/16W',
 TOLERANCE='1%',
 SEC_TYPE='0402',
 MATERIAL='CHIP',
 BOM_COST='SM_CONTROLLER',
 PHYS_PAGE='156',
 XY='(-6575,2775)',
 ROT='0',
 VER='1',
 VALUE='33.2',
 PACK_TYPE='0402',
 PART_NUMBER='G21796-074',
 LOCATION='R8E24',
 ROOM='BMC_MISC',
 SEC='1',
 CDS_LIB='mstr_discrete',
 CDS_PART_NAME='RES_0402-33.2,1%,1/16W,CHIP,G2A',
 PRIM_FILE='./archive_libs/mstr_discrete/res/chips/chips.prt';

PART_NAME
 R8E25 'RES_0402-0.0,5%,1/16W,CHIP,G21A':
 ROOM='PVPP_KLM_VR';

SECTION_NUMBER 1
 '@BASEBOARD_FAB2_LIB.BASEBOARD_FAB2(SCH_1):PAGE240_I144@MSTR_DISCRETE.RES(CHIPS)':
 C_PATH='@baseboard_fab2_lib.baseboard_fab2(sch_1):page240_i144@mstr_discrete.re~
s(chips)',
 P_PATH='@baseboard_fab2_lib.baseboard_fab2(sch_1):page240_i144@mstr_discrete.re~
s(chips)',
 PATH='I144',
 DRAWING='@BASEBOARD_FAB2_LIB.BASEBOARD_FAB2(SCH_1):PAGE240',
 SPOF='TRUE',
 WATTAGE='1/16W',
 TOLERANCE='5%',
 SEC_TYPE='0402',
 MATERIAL='CHIP',
 PHYS_PAGE='240',
 XY='(9525,1800)',
 ROT='5',
 VER='1',
 VALUE='0.0',
 PACK_TYPE='0402',
 PART_NUMBER='G21497-005',
 LOCATION='R8E25',
 ROOM='PVPP_KLM_VR',
 SEC='1',
 CDS_LIB='mstr_discrete',
 CDS_PART_NAME='RES_0402-0.0,5%,1/16W,CHIP,G21A',
 PRIM_FILE='./archive_libs/mstr_discrete/res/chips/chips.prt';

PART_NAME
 R8E26 'RES_0402-0.0,5%,1/16W,CHIP,G21A':
 ROOM='PCIE_WAKE_BUFFER';

SECTION_NUMBER 1
 '@BASEBOARD_FAB2_LIB.BASEBOARD_FAB2(SCH_1):PAGE142_I30@MSTR_DISCRETE.RES(CHIPS)':
 C_PATH='@baseboard_fab2_lib.baseboard_fab2(sch_1):page142_i30@mstr_discrete.res~
(chips)',
 P_PATH='@baseboard_fab2_lib.baseboard_fab2(sch_1):page142_i30@mstr_discrete.res~
(chips)',
 PATH='I30',
 DRAWING='@BASEBOARD_FAB2_LIB.BASEBOARD_FAB2(SCH_1):PAGE142',
 WATTAGE='1/16W',
 TOLERANCE='5%',
 SEC_TYPE='0402',
 MATERIAL='CHIP',
 PHYS_PAGE='142',
 XY='(-4550,2250)',
 ROT='0',
 VER='1',
 VALUE='0.0',
 PACK_TYPE='0402',
 PART_NUMBER='G21497-005',
 LOCATION='R8E26',
 ROOM='PCIE_WAKE_BUFFER',
 SEC='1',
 CDS_LIB='mstr_discrete',
 CDS_PART_NAME='RES_0402-0.0,5%,1/16W,CHIP,G21A',
 PRIM_FILE='./archive_libs/mstr_discrete/res/chips/chips.prt';

PART_NAME
 R8E27 'RES_0402-0.0,5%,1/16W,CHIP,G21A':
 ROOM='PCIE_WAKE_BUFFER';

SECTION_NUMBER 1
 '@BASEBOARD_FAB2_LIB.BASEBOARD_FAB2(SCH_1):PAGE142_I32@MSTR_DISCRETE.RES(CHIPS)':
 C_PATH='@baseboard_fab2_lib.baseboard_fab2(sch_1):page142_i32@mstr_discrete.res~
(chips)',
 P_PATH='@baseboard_fab2_lib.baseboard_fab2(sch_1):page142_i32@mstr_discrete.res~
(chips)',
 PATH='I32',
 DRAWING='@BASEBOARD_FAB2_LIB.BASEBOARD_FAB2(SCH_1):PAGE142',
 WATTAGE='1/16W',
 TOLERANCE='5%',
 SEC_TYPE='0402',
 MATERIAL='CHIP',
 PHYS_PAGE='142',
 XY='(-4550,2650)',
 ROT='0',
 VER='1',
 VALUE='0.0',
 PACK_TYPE='0402',
 PART_NUMBER='G21497-005',
 LOCATION='R8E27',
 ROOM='PCIE_WAKE_BUFFER',
 SEC='1',
 CDS_LIB='mstr_discrete',
 CDS_PART_NAME='RES_0402-0.0,5%,1/16W,CHIP,G21A',
 PRIM_FILE='./archive_libs/mstr_discrete/res/chips/chips.prt';

PART_NAME
 R8E28 'RES_0402-0.0,5%,1/16W,CHIP,G21A':
 ROOM='PCIE_WAKE_BUFFER';

SECTION_NUMBER 1
 '@BASEBOARD_FAB2_LIB.BASEBOARD_FAB2(SCH_1):PAGE142_I31@MSTR_DISCRETE.RES(CHIPS)':
 C_PATH='@baseboard_fab2_lib.baseboard_fab2(sch_1):page142_i31@mstr_discrete.res~
(chips)',
 P_PATH='@baseboard_fab2_lib.baseboard_fab2(sch_1):page142_i31@mstr_discrete.res~
(chips)',
 PATH='I31',
 DRAWING='@BASEBOARD_FAB2_LIB.BASEBOARD_FAB2(SCH_1):PAGE142',
 WATTAGE='1/16W',
 TOLERANCE='5%',
 SEC_TYPE='0402',
 MATERIAL='CHIP',
 PHYS_PAGE='142',
 XY='(-4550,2450)',
 ROT='0',
 VER='1',
 VALUE='0.0',
 PACK_TYPE='0402',
 PART_NUMBER='G21497-005',
 LOCATION='R8E28',
 ROOM='PCIE_WAKE_BUFFER',
 SEC='1',
 CDS_LIB='mstr_discrete',
 CDS_PART_NAME='RES_0402-0.0,5%,1/16W,CHIP,G21A',
 PRIM_FILE='./archive_libs/mstr_discrete/res/chips/chips.prt';

PART_NAME
 R8E29 'RES_0402-0.0,5%,1/16W,EMPTY,G2A':
 ROOM='PCIE_WAKE_BUFFER';

SECTION_NUMBER 1
 '@BASEBOARD_FAB2_LIB.BASEBOARD_FAB2(SCH_1):PAGE142_I18@MSTR_DISCRETE.RES(CHIPS)':
 C_PATH='@baseboard_fab2_lib.baseboard_fab2(sch_1):page142_i18@mstr_discrete.res~
(chips)',
 P_PATH='@baseboard_fab2_lib.baseboard_fab2(sch_1):page142_i18@mstr_discrete.res~
(chips)',
 PATH='I18',
 DRAWING='@BASEBOARD_FAB2_LIB.BASEBOARD_FAB2(SCH_1):PAGE142',
 WATTAGE='1/16W',
 TOLERANCE='5%',
 SEC_TYPE='0402',
 MATERIAL='EMPTY',
 BOM_COST='SB',
 PHYS_PAGE='142',
 XY='(-4550,3100)',
 ROT='0',
 VER='1',
 VALUE='0.0',
 PACK_TYPE='0402',
 PART_NUMBER='G21497-005',
 LOCATION='R8E29',
 ROOM='PCIE_WAKE_BUFFER',
 SEC='1',
 CDS_LIB='mstr_discrete',
 CDS_PART_NAME='RES_0402-0.0,5%,1/16W,EMPTY,G2A',
 PRIM_FILE='./archive_libs/mstr_discrete/res/chips/chips.prt';

PART_NAME
 R8E30 '2K15R2F-1-GP_SMD-RG1-2K15R2F-1A':;

SECTION_NUMBER 1
 '@BASEBOARD_FAB2_LIB.BASEBOARD_FAB2(SCH_1):PAGE142_I35@W_HDL.2K15R2F-1-GP(CHIPS)':
 C_PATH='@baseboard_fab2_lib.baseboard_fab2(sch_1):page142_i35@w_hdl.\2k15r2f-1-~
gp\(chips)',
 P_PATH='@baseboard_fab2_lib.baseboard_fab2(sch_1):page142_i35@w_hdl.\2k15r2f-1-~
gp\(chips)',
 PATH='I35',
 DRAWING='@BASEBOARD_FAB2_LIB.BASEBOARD_FAB2(SCH_1):PAGE142',
 PACK_SIZE='0402',
 RATED='1/16W',
 ATTRIBUTE='2.15K OHM',
 TOLERANCE='1%',
 SEC_TYPE='SMD-RG1',
 PHYS_PAGE='142',
 XY='(-3800,3525)',
 ROT='0',
 VER='1',
 VALUE='2K15R2F-1-GP',
 PACK_TYPE='SMD-RG1',
 PART_NUMBER='64.21515.6DL',
 LOCATION='R8E30',
 SEC='1',
 CDS_LIB='w_hdl',
 CDS_PART_NAME='2K15R2F-1-GP_SMD-RG1-2K15R2F-1A',
 PRIM_FILE='C:/<user>/w_hdl/2k15r2f#2d1#2dgp/chips/chips.prt';

PART_NAME
 R8E31 'RES_0402-23.2K,1%,1/16W,CHIP,GA':
 ROOM='P3V3_STBY_VR',
 REUSE_ID='9';

SECTION_NUMBER 1
 '@BASEBOARD_FAB2_LIB.BASEBOARD_FAB2(SCH_1):PAGE240_I143@MSTR_DISCRETE.RES(CHIPS)':
 C_PATH='@baseboard_fab2_lib.baseboard_fab2(sch_1):page240_i143@mstr_discrete.re~
s(chips)',
 P_PATH='@baseboard_fab2_lib.baseboard_fab2(sch_1):page240_i143@mstr_discrete.re~
s(chips)',
 PATH='I143',
 DRAWING='@BASEBOARD_FAB2_LIB.BASEBOARD_FAB2(SCH_1):PAGE240',
 SPOF='TRUE',
 WATTAGE='1/16W',
 TOLERANCE='1%',
 MATERIAL='CHIP',
 BOM_COST='P3V3_STBY_VR',
 PHYS_PAGE='240',
 REUSE_ID='9',
 XY='(9475,1425)',
 ROT='0',
 VER='2',
 VALUE='23.2K',
 PACK_TYPE='0402',
 PART_NUMBER='G21796-114',
 LOCATION='R8E31',
 ROOM='P3V3_STBY_VR',
 CDS_LIB='mstr_discrete',
 CDS_PART_NAME='RES_0402-23.2K,1%,1/16W,CHIP,GA',
 PRIM_FILE='./archive_libs/mstr_discrete/res/chips/chips.prt';

PART_NAME
 R8E32 'RES_0402-4.75K,1%,1/16W,CHIP,GA':
 ROOM='MIO_CHASSIS';

SECTION_NUMBER 1
 '@BASEBOARD_FAB2_LIB.BASEBOARD_FAB2(SCH_1):PAGE157_I385@MSTR_DISCRETE.RES(CHIPS)':
 C_PATH='@baseboard_fab2_lib.baseboard_fab2(sch_1):page157_i385@mstr_discrete.re~
s(chips)',
 P_PATH='@baseboard_fab2_lib.baseboard_fab2(sch_1):page157_i385@mstr_discrete.re~
s(chips)',
 PATH='I385',
 DRAWING='@BASEBOARD_FAB2_LIB.BASEBOARD_FAB2(SCH_1):PAGE157',
 WATTAGE='1/16W',
 TOLERANCE='1%',
 SEC_TYPE='0402',
 MATERIAL='CHIP',
 BOM_COST='MIO_CHASSIS',
 PHYS_PAGE='157',
 XY='(-3975,2950)',
 ROT='0',
 VER='2',
 VALUE='4.75K',
 PACK_TYPE='0402',
 PART_NUMBER='G21796-072',
 LOCATION='R8E32',
 ROOM='MIO_CHASSIS',
 SEC='1',
 CDS_LIB='mstr_discrete',
 CDS_PART_NAME='RES_0402-4.75K,1%,1/16W,CHIP,GA',
 PRIM_FILE='./archive_libs/mstr_discrete/res/chips/chips.prt';

PART_NAME
 R8E33 'RES_0402-0.0,5%,1/16W,CHIP,G21A':
 ROOM='PVCCIN_CPU0_VR';

SECTION_NUMBER 1
 '@BASEBOARD_FAB2_LIB.BASEBOARD_FAB2(SCH_1):PAGE241_I91@MSTR_DISCRETE.RES(CHIPS)':
 C_PATH='@baseboard_fab2_lib.baseboard_fab2(sch_1):page241_i91@mstr_discrete.res~
(chips)',
 P_PATH='@baseboard_fab2_lib.baseboard_fab2(sch_1):page241_i91@mstr_discrete.res~
(chips)',
 PATH='I91',
 DRAWING='@BASEBOARD_FAB2_LIB.BASEBOARD_FAB2(SCH_1):PAGE241',
 WATTAGE='1/16W',
 TOLERANCE='5%',
 SEC_TYPE='0402',
 MATERIAL='CHIP',
 PHYS_PAGE='241',
 XY='(-1625,3475)',
 ROT='0',
 VER='1',
 VALUE='0.0',
 PACK_TYPE='0402',
 PART_NUMBER='G21497-005',
 LOCATION='R8E33',
 ROOM='PVCCIN_CPU0_VR',
 SEC='1',
 CDS_LIB='mstr_discrete',
 CDS_PART_NAME='RES_0402-0.0,5%,1/16W,CHIP,G21A',
 PRIM_FILE='./archive_libs/mstr_discrete/res/chips/chips.prt';

PART_NAME
 R8E34 'RES_0402-10.0K,1%,1/16W,CHIP,GA':
 ROOM='P3V3_STBY_VR',
 REUSE_ID='7';

SECTION_NUMBER 1
 '@BASEBOARD_FAB2_LIB.BASEBOARD_FAB2(SCH_1):PAGE240_I142@MSTR_DISCRETE.RES(CHIPS)':
 C_PATH='@baseboard_fab2_lib.baseboard_fab2(sch_1):page240_i142@mstr_discrete.re~
s(chips)',
 P_PATH='@baseboard_fab2_lib.baseboard_fab2(sch_1):page240_i142@mstr_discrete.re~
s(chips)',
 PATH='I142',
 DRAWING='@BASEBOARD_FAB2_LIB.BASEBOARD_FAB2(SCH_1):PAGE240',
 SPOF='TRUE',
 WATTAGE='1/16W',
 TOLERANCE='1%',
 MATERIAL='CHIP',
 BOM_COST='P3V3_STBY_VR',
 PHYS_PAGE='240',
 REUSE_ID='7',
 XY='(9475,1100)',
 ROT='0',
 VER='2',
 VALUE='10.0K',
 PACK_TYPE='0402',
 PART_NUMBER='G21796-016',
 LOCATION='R8E34',
 ROOM='P3V3_STBY_VR',
 CDS_LIB='mstr_discrete',
 CDS_PART_NAME='RES_0402-10.0K,1%,1/16W,CHIP,GA',
 PRIM_FILE='./archive_libs/mstr_discrete/res/chips/chips.prt';

PART_NAME
 R8E35 'RES_0402-0.0,5%,1/16W,CHIP,G21A':
 ROOM='P3V3_STBY_VR',
 REUSE_ID='13';

SECTION_NUMBER 1
 '@BASEBOARD_FAB2_LIB.BASEBOARD_FAB2(SCH_1):PAGE240_I127@MSTR_DISCRETE.RES(CHIPS)':
 C_PATH='@baseboard_fab2_lib.baseboard_fab2(sch_1):page240_i127@mstr_discrete.re~
s(chips)',
 P_PATH='@baseboard_fab2_lib.baseboard_fab2(sch_1):page240_i127@mstr_discrete.re~
s(chips)',
 PATH='I127',
 DRAWING='@BASEBOARD_FAB2_LIB.BASEBOARD_FAB2(SCH_1):PAGE240',
 SPOF='TRUE',
 WATTAGE='1/16W',
 TOLERANCE='5%',
 MATERIAL='CHIP',
 BOM_COST='P3V3_STBY_VR',
 PHYS_PAGE='240',
 REUSE_ID='13',
 XY='(7600,3425)',
 ROT='0',
 VER='1',
 VALUE='0.0',
 PACK_TYPE='0402',
 PART_NUMBER='G21497-005',
 LOCATION='R8E35',
 ROOM='P3V3_STBY_VR',
 CDS_LIB='mstr_discrete',
 CDS_PART_NAME='RES_0402-0.0,5%,1/16W,CHIP,G21A',
 PRIM_FILE='./archive_libs/mstr_discrete/res/chips/chips.prt';

PART_NAME
 R8E36 '2K15R2F-1-GP_SMD-RG1-2K15R2F-1A':;

SECTION_NUMBER 1
 '@BASEBOARD_FAB2_LIB.BASEBOARD_FAB2(SCH_1):PAGE142_I34@W_HDL.2K15R2F-1-GP(CHIPS)':
 C_PATH='@baseboard_fab2_lib.baseboard_fab2(sch_1):page142_i34@w_hdl.\2k15r2f-1-~
gp\(chips)',
 P_PATH='@baseboard_fab2_lib.baseboard_fab2(sch_1):page142_i34@w_hdl.\2k15r2f-1-~
gp\(chips)',
 PATH='I34',
 DRAWING='@BASEBOARD_FAB2_LIB.BASEBOARD_FAB2(SCH_1):PAGE142',
 PACK_SIZE='0402',
 RATED='1/16W',
 ATTRIBUTE='2.15K OHM',
 TOLERANCE='1%',
 SEC_TYPE='SMD-RG1',
 PHYS_PAGE='142',
 XY='(-4800,3525)',
 ROT='0',
 VER='1',
 VALUE='2K15R2F-1-GP',
 PACK_TYPE='SMD-RG1',
 PART_NUMBER='64.21515.6DL',
 LOCATION='R8E36',
 SEC='1',
 CDS_LIB='w_hdl',
 CDS_PART_NAME='2K15R2F-1-GP_SMD-RG1-2K15R2F-1A',
 PRIM_FILE='C:/<user>/w_hdl/2k15r2f#2d1#2dgp/chips/chips.prt';

PART_NAME
 R8E37 'RES_0402-0.0,5%,1/16W,CHIP,G21A':
 ROOM='P5V_STBY_VR';

SECTION_NUMBER 1
 '@BASEBOARD_FAB2_LIB.BASEBOARD_FAB2(SCH_1):PAGE241_I78@MSTR_DISCRETE.RES(CHIPS)':
 C_PATH='@baseboard_fab2_lib.baseboard_fab2(sch_1):page241_i78@mstr_discrete.res~
(chips)',
 P_PATH='@baseboard_fab2_lib.baseboard_fab2(sch_1):page241_i78@mstr_discrete.res~
(chips)',
 PATH='I78',
 DRAWING='@BASEBOARD_FAB2_LIB.BASEBOARD_FAB2(SCH_1):PAGE241',
 SPOF='TRUE',
 WATTAGE='1/16W',
 TOLERANCE='5%',
 SEC_TYPE='0402',
 MATERIAL='CHIP',
 BOM_COST='P5V_STBY_VR',
 PHYS_PAGE='241',
 XY='(2075,3650)',
 ROT='0',
 VER='1',
 VALUE='0.0',
 PACK_TYPE='0402',
 PART_NUMBER='G21497-005',
 LOCATION='R8E37',
 ROOM='P5V_STBY_VR',
 SEC='1',
 CDS_LIB='mstr_discrete',
 CDS_PART_NAME='RES_0402-0.0,5%,1/16W,CHIP,G21A',
 PRIM_FILE='./archive_libs/mstr_discrete/res/chips/chips.prt';

PART_NAME
 R8E38 'RES_0402-0.0,5%,1/16W,CHIP,G21A':
 ROOM='P3V3_STBY_VR';

SECTION_NUMBER 1
 '@BASEBOARD_FAB2_LIB.BASEBOARD_FAB2(SCH_1):PAGE240_I140@MSTR_DISCRETE.RES(CHIPS)':
 C_PATH='@baseboard_fab2_lib.baseboard_fab2(sch_1):page240_i140@mstr_discrete.re~
s(chips)',
 P_PATH='@baseboard_fab2_lib.baseboard_fab2(sch_1):page240_i140@mstr_discrete.re~
s(chips)',
 PATH='I140',
 DRAWING='@BASEBOARD_FAB2_LIB.BASEBOARD_FAB2(SCH_1):PAGE240',
 WATTAGE='1/16W',
 TOLERANCE='5%',
 MATERIAL='CHIP',
 BOM_COST='P3V3_STBY_VR',
 PHYS_PAGE='240',
 XY='(9225,925)',
 ROT='0',
 VER='1',
 VALUE='0.0',
 PACK_TYPE='0402',
 PART_NUMBER='G21497-005',
 LOCATION='R8E38',
 ROOM='P3V3_STBY_VR',
 CDS_LIB='mstr_discrete',
 CDS_PART_NAME='RES_0402-0.0,5%,1/16W,CHIP,G21A',
 PRIM_FILE='./archive_libs/mstr_discrete/res/chips/chips.prt';

PART_NAME
 R8E39 'RES_0402-24.9K,1%,1/16W,CHIP,GA':
 ROOM='P5V_STBY_VR',
 REUSE_ID='10';

SECTION_NUMBER 1
 '@BASEBOARD_FAB2_LIB.BASEBOARD_FAB2(SCH_1):PAGE241_I54@MSTR_DISCRETE.RES(CHIPS)':
 C_PATH='@baseboard_fab2_lib.baseboard_fab2(sch_1):page241_i54@mstr_discrete.res~
(chips)',
 P_PATH='@baseboard_fab2_lib.baseboard_fab2(sch_1):page241_i54@mstr_discrete.res~
(chips)',
 PATH='I54',
 DRAWING='@BASEBOARD_FAB2_LIB.BASEBOARD_FAB2(SCH_1):PAGE241',
 WATTAGE='1/16W',
 TOLERANCE='1%',
 SEC_TYPE='0402',
 MATERIAL='CHIP',
 BOM_COST='P5V_STBY_VR',
 PHYS_PAGE='241',
 REUSE_ID='10',
 XY='(-200,2200)',
 ROT='0',
 VER='1',
 VALUE='24.9K',
 PACK_TYPE='0402',
 PART_NUMBER='G21796-254',
 LOCATION='R8E39',
 ROOM='P5V_STBY_VR',
 SEC='1',
 CDS_LIB='mstr_discrete',
 CDS_PART_NAME='RES_0402-24.9K,1%,1/16W,CHIP,GA',
 PRIM_FILE='./archive_libs/mstr_discrete/res/chips/chips.prt';

PART_NAME
 R8E40 'RES_0402-100.0K,1%,1/16W,EMPTYA':
 ROOM='BMC';

SECTION_NUMBER 1
 '@BASEBOARD_FAB2_LIB.BASEBOARD_FAB2(SCH_1):PAGE240_I177@MSTR_DISCRETE.RES(CHIPS)':
 C_PATH='@baseboard_fab2_lib.baseboard_fab2(sch_1):page240_i177@mstr_discrete.re~
s(chips)',
 P_PATH='@baseboard_fab2_lib.baseboard_fab2(sch_1):page240_i177@mstr_discrete.re~
s(chips)',
 PATH='I177',
 DRAWING='@BASEBOARD_FAB2_LIB.BASEBOARD_FAB2(SCH_1):PAGE240',
 WATTAGE='1/16W',
 TOLERANCE='1%',
 SEC_TYPE='0402',
 MATERIAL='EMPTY',
 BOM_COST='SM_CONTROLLER',
 PHYS_PAGE='240',
 XY='(6950,3250)',
 ROT='0',
 VER='2',
 VALUE='100.0K',
 PACK_TYPE='0402',
 PART_NUMBER='G21796-010',
 LOCATION='R8E40',
 ROOM='BMC',
 SEC='1',
 CDS_LIB='mstr_discrete',
 CDS_PART_NAME='RES_0402-100.0K,1%,1/16W,EMPTYA',
 PRIM_FILE='./archive_libs/mstr_discrete/res/chips/chips.prt';

PART_NAME
 R8F1 'RES_0402-10.0K,1%,1/16W,EMPTY,A':
 ROOM='P3V3_STBY_VR';

SECTION_NUMBER 1
 '@BASEBOARD_FAB2_LIB.BASEBOARD_FAB2(SCH_1):PAGE240_I111@MSTR_DISCRETE.RES(CHIPS)':
 C_PATH='@baseboard_fab2_lib.baseboard_fab2(sch_1):page240_i111@mstr_discrete.re~
s(chips)',
 P_PATH='@baseboard_fab2_lib.baseboard_fab2(sch_1):page240_i111@mstr_discrete.re~
s(chips)',
 PATH='I111',
 DRAWING='@BASEBOARD_FAB2_LIB.BASEBOARD_FAB2(SCH_1):PAGE240',
 BOM='SYSB_CPLD',
 WATTAGE='1/16W',
 TOLERANCE='1%',
 MATERIAL='EMPTY',
 BOM_COST='P3V3_STBY_VR',
 PHYS_PAGE='240',
 XY='(5625,2400)',
 ROT='0',
 VER='2',
 VALUE='10.0K',
 PACK_TYPE='0402',
 PART_NUMBER='G21796-016',
 LOCATION='R8F1',
 ROOM='P3V3_STBY_VR',
 CDS_LIB='mstr_discrete',
 CDS_PART_NAME='RES_0402-10.0K,1%,1/16W,EMPTY,A',
 PRIM_FILE='./archive_libs/mstr_discrete/res/chips/chips.prt';

PART_NAME
 R8F2 'RES_0402-0.0,5%,1/16W,CHIP,G21A':
 ROOM='PVCCIN_CPU0_VR';

SECTION_NUMBER 1
 '@BASEBOARD_FAB2_LIB.BASEBOARD_FAB2(SCH_1):PAGE240_I176@MSTR_DISCRETE.RES(CHIPS)':
 C_PATH='@baseboard_fab2_lib.baseboard_fab2(sch_1):page240_i176@mstr_discrete.re~
s(chips)',
 P_PATH='@baseboard_fab2_lib.baseboard_fab2(sch_1):page240_i176@mstr_discrete.re~
s(chips)',
 PATH='I176',
 DRAWING='@BASEBOARD_FAB2_LIB.BASEBOARD_FAB2(SCH_1):PAGE240',
 WATTAGE='1/16W',
 TOLERANCE='5%',
 SEC_TYPE='0402',
 MATERIAL='CHIP',
 PHYS_PAGE='240',
 XY='(6400,2725)',
 ROT='0',
 VER='1',
 VALUE='0.0',
 PACK_TYPE='0402',
 PART_NUMBER='G21497-005',
 LOCATION='R8F2',
 ROOM='PVCCIN_CPU0_VR',
 SEC='1',
 CDS_LIB='mstr_discrete',
 CDS_PART_NAME='RES_0402-0.0,5%,1/16W,CHIP,G21A',
 PRIM_FILE='./archive_libs/mstr_discrete/res/chips/chips.prt';

PART_NAME
 R8F3 'RES_0402-2.2,5%,1/16W,EMPTY,G2A':
 ROOM='P3V3_STBY_VR',
 REUSE_ID='29';

SECTION_NUMBER 1
 '@BASEBOARD_FAB2_LIB.BASEBOARD_FAB2(SCH_1):PAGE240_I148@MSTR_DISCRETE.RES(CHIPS)':
 C_PATH='@baseboard_fab2_lib.baseboard_fab2(sch_1):page240_i148@mstr_discrete.re~
s(chips)',
 P_PATH='@baseboard_fab2_lib.baseboard_fab2(sch_1):page240_i148@mstr_discrete.re~
s(chips)',
 PATH='I148',
 DRAWING='@BASEBOARD_FAB2_LIB.BASEBOARD_FAB2(SCH_1):PAGE240',
 WATTAGE='1/16W',
 TOLERANCE='5%',
 MATERIAL='EMPTY',
 BOM_COST='P3V3_STBY_VR',
 PHYS_PAGE='240',
 REUSE_ID='29',
 XY='(9750,3550)',
 ROT='0',
 VER='2',
 VALUE='2.2',
 PACK_TYPE='0402',
 PART_NUMBER='G21497-016',
 LOCATION='R8F3',
 ROOM='P3V3_STBY_VR',
 CDS_LIB='mstr_discrete',
 CDS_PART_NAME='RES_0402-2.2,5%,1/16W,EMPTY,G2A',
 PRIM_FILE='./archive_libs/mstr_discrete/res/chips/chips.prt';

PART_NAME
 R8F5 'RES_0402-1.00K,1%,1/16W,CHIP,GA':
 ROOM='PVPP_KLM_VR',
 REUSE_ID='21';

SECTION_NUMBER 1
 '@BASEBOARD_FAB2_LIB.BASEBOARD_FAB2(SCH_1):PAGE240_I117@MSTR_DISCRETE.RES(CHIPS)':
 C_PATH='@baseboard_fab2_lib.baseboard_fab2(sch_1):page240_i117@mstr_discrete.re~
s(chips)',
 P_PATH='@baseboard_fab2_lib.baseboard_fab2(sch_1):page240_i117@mstr_discrete.re~
s(chips)',
 PATH='I117',
 DRAWING='@BASEBOARD_FAB2_LIB.BASEBOARD_FAB2(SCH_1):PAGE240',
 WATTAGE='1/16W',
 TOLERANCE='1%',
 SEC_TYPE='0402',
 MATERIAL='CHIP',
 BOM_COST='P3V3_STBY_VR',
 PHYS_PAGE='240',
 REUSE_ID='21',
 XY='(6275,3900)',
 ROT='2',
 VER='2',
 VALUE='1.00K',
 PACK_TYPE='0402',
 PART_NUMBER='G21796-026',
 LOCATION='R8F5',
 ROOM='PVPP_KLM_VR',
 SEC='1',
 CDS_LIB='mstr_discrete',
 CDS_PART_NAME='RES_0402-1.00K,1%,1/16W,CHIP,GA',
 PRIM_FILE='./archive_libs/mstr_discrete/res/chips/chips.prt';

PART_NAME
 R8F6 'RES_0402-0.0,5%,1/16W,CHIP,G21A':
 ROOM='MIO_BIOS_MEM';

SECTION_NUMBER 1
 '@BASEBOARD_FAB2_LIB.BASEBOARD_FAB2(SCH_1):PAGE154_I119@MSTR_DISCRETE.RES(CHIPS)':
 C_PATH='@baseboard_fab2_lib.baseboard_fab2(sch_1):page154_i119@mstr_discrete.re~
s(chips)',
 P_PATH='@baseboard_fab2_lib.baseboard_fab2(sch_1):page154_i119@mstr_discrete.re~
s(chips)',
 PATH='I119',
 DRAWING='@BASEBOARD_FAB2_LIB.BASEBOARD_FAB2(SCH_1):PAGE154',
 WATTAGE='1/16W',
 TOLERANCE='5%',
 MATERIAL='CHIP',
 PHYS_PAGE='154',
 XY='(-6725,3600)',
 ROT='0',
 VER='1',
 VALUE='0.0',
 PACK_TYPE='0402',
 PART_NUMBER='G21497-005',
 LOCATION='R8F6',
 ROOM='MIO_BIOS_MEM',
 CDS_LIB='mstr_discrete',
 CDS_PART_NAME='RES_0402-0.0,5%,1/16W,CHIP,G21A',
 PRIM_FILE='./archive_libs/mstr_discrete/res/chips/chips.prt';

PART_NAME
 R8F7 'RES_0402-33.2,1%,1/16W,CHIP,G2A':
 GROUP='NI_BIOS_ROM2',
 ROOM='MIO_BIOS_MEM';

SECTION_NUMBER 1
 '@BASEBOARD_FAB2_LIB.BASEBOARD_FAB2(SCH_1):PAGE153_I167@MSTR_DISCRETE.RES(CHIPS)':
 C_PATH='@baseboard_fab2_lib.baseboard_fab2(sch_1):page153_i167@mstr_discrete.re~
s(chips)',
 P_PATH='@baseboard_fab2_lib.baseboard_fab2(sch_1):page153_i167@mstr_discrete.re~
s(chips)',
 PATH='I167',
 DRAWING='@BASEBOARD_FAB2_LIB.BASEBOARD_FAB2(SCH_1):PAGE153',
 WATTAGE='1/16W',
 TOLERANCE='1%',
 SEC_TYPE='0402',
 MATERIAL='CHIP',
 PHYS_PAGE='153',
 XY='(-6275,1825)',
 ROT='0',
 VER='1',
 VALUE='33.2',
 PACK_TYPE='0402',
 PART_NUMBER='G21796-074',
 LOCATION='R8F7',
 ROOM='MIO_BIOS_MEM',
 GROUP='NI_BIOS_ROM2',
 SEC='1',
 CDS_LIB='mstr_discrete',
 CDS_PART_NAME='RES_0402-33.2,1%,1/16W,CHIP,G2A',
 PRIM_FILE='./archive_libs/mstr_discrete/res/chips/chips.prt';

PART_NAME
 R8F8 'RES_0402-33.2,1%,1/16W,CHIP,G2A':
 ROOM='MIO_BIOS_MEM';

SECTION_NUMBER 1
 '@BASEBOARD_FAB2_LIB.BASEBOARD_FAB2(SCH_1):PAGE153_I166@MSTR_DISCRETE.RES(CHIPS)':
 C_PATH='@baseboard_fab2_lib.baseboard_fab2(sch_1):page153_i166@mstr_discrete.re~
s(chips)',
 P_PATH='@baseboard_fab2_lib.baseboard_fab2(sch_1):page153_i166@mstr_discrete.re~
s(chips)',
 PATH='I166',
 DRAWING='@BASEBOARD_FAB2_LIB.BASEBOARD_FAB2(SCH_1):PAGE153',
 WATTAGE='1/16W',
 TOLERANCE='1%',
 MATERIAL='CHIP',
 PHYS_PAGE='153',
 XY='(-6550,3825)',
 ROT='0',
 VER='1',
 VALUE='33.2',
 PACK_TYPE='0402',
 PART_NUMBER='G21796-074',
 LOCATION='R8F8',
 ROOM='MIO_BIOS_MEM',
 CDS_LIB='mstr_discrete',
 CDS_PART_NAME='RES_0402-33.2,1%,1/16W,CHIP,G2A',
 PRIM_FILE='./archive_libs/mstr_discrete/res/chips/chips.prt';

PART_NAME
 R8F9 'RES_0402-49.9K,1%,1/16W,CHIP,GA':
 ROOM='V_SUPER';

SECTION_NUMBER 1
 '@BASEBOARD_FAB2_LIB.BASEBOARD_FAB2(SCH_1):PAGE240_I195@MSTR_DISCRETE.RES(CHIPS)':
 C_PATH='@baseboard_fab2_lib.baseboard_fab2(sch_1):page240_i195@mstr_discrete.re~
s(chips)',
 P_PATH='@baseboard_fab2_lib.baseboard_fab2(sch_1):page240_i195@mstr_discrete.re~
s(chips)',
 PATH='I195',
 DRAWING='@BASEBOARD_FAB2_LIB.BASEBOARD_FAB2(SCH_1):PAGE240',
 WATTAGE='1/16W',
 TOLERANCE='1%',
 SEC_TYPE='0402',
 MATERIAL='CHIP',
 PHYS_PAGE='240',
 XY='(6450,1850)',
 ROT='0',
 VER='2',
 VALUE='49.9K',
 PACK_TYPE='0402',
 PART_NUMBER='G21796-048',
 LOCATION='R8F9',
 ROOM='V_SUPER',
 SEC='1',
 CDS_LIB='mstr_discrete',
 CDS_PART_NAME='RES_0402-49.9K,1%,1/16W,CHIP,GA',
 PRIM_FILE='./archive_libs/mstr_discrete/res/chips/chips.prt';

PART_NAME
 R8F10 'RES_0402-22.1,1.0%,1/16W,CHIP,A':
 ROOM='P3V3_STBY_VR';

SECTION_NUMBER 1
 '@BASEBOARD_FAB2_LIB.BASEBOARD_FAB2(SCH_1):PAGE240_I171@MSTR_DISCRETE.RES(CHIPS)':
 C_PATH='@baseboard_fab2_lib.baseboard_fab2(sch_1):page240_i171@mstr_discrete.re~
s(chips)',
 P_PATH='@baseboard_fab2_lib.baseboard_fab2(sch_1):page240_i171@mstr_discrete.re~
s(chips)',
 PATH='I171',
 DRAWING='@BASEBOARD_FAB2_LIB.BASEBOARD_FAB2(SCH_1):PAGE240',
 WATTAGE='1/16W',
 TOLERANCE='1.0%',
 SEC_TYPE='0402',
 MATERIAL='CHIP',
 PHYS_PAGE='240',
 XY='(7175,3825)',
 ROT='0',
 VER='1',
 VALUE='22.1',
 PACK_TYPE='0402',
 PART_NUMBER='G21796-250',
 LOCATION='R8F10',
 ROOM='P3V3_STBY_VR',
 SEC='1',
 CDS_LIB='mstr_discrete',
 CDS_PART_NAME='RES_0402-22.1,1.0%,1/16W,CHIP,A',
 PRIM_FILE='./archive_libs/mstr_discrete/res/chips/chips.prt';

PART_NAME
 R8F11 'RES_0402-0.0,5%,1/16W,CHIP,G21A':
 ROOM='P3V3_STBY_VR';

SECTION_NUMBER 1
 '@BASEBOARD_FAB2_LIB.BASEBOARD_FAB2(SCH_1):PAGE240_I146@MSTR_DISCRETE.RES(CHIPS)':
 C_PATH='@baseboard_fab2_lib.baseboard_fab2(sch_1):page240_i146@mstr_discrete.re~
s(chips)',
 P_PATH='@baseboard_fab2_lib.baseboard_fab2(sch_1):page240_i146@mstr_discrete.re~
s(chips)',
 PATH='I146',
 DRAWING='@BASEBOARD_FAB2_LIB.BASEBOARD_FAB2(SCH_1):PAGE240',
 WATTAGE='1/16W',
 TOLERANCE='5%',
 MATERIAL='CHIP',
 PHYS_PAGE='240',
 XY='(10475,1725)',
 ROT='0',
 VER='1',
 VALUE='0.0',
 PACK_TYPE='0402',
 PART_NUMBER='G21497-005',
 LOCATION='R8F11',
 ROOM='P3V3_STBY_VR',
 CDS_LIB='mstr_discrete',
 CDS_PART_NAME='RES_0402-0.0,5%,1/16W,CHIP,G21A',
 PRIM_FILE='./archive_libs/mstr_discrete/res/chips/chips.prt';

PART_NAME
 R8F12 'RES_0402-33.2,1%,1/16W,CHIP,G2A':
 ROOM='BMC_BOOT_SPI';

SECTION_NUMBER 1
 '@BASEBOARD_FAB2_LIB.BASEBOARD_FAB2(SCH_1):PAGE162_I13@MSTR_DISCRETE.RES(CHIPS)':
 C_PATH='@baseboard_fab2_lib.baseboard_fab2(sch_1):page162_i13@mstr_discrete.res~
(chips)',
 P_PATH='@baseboard_fab2_lib.baseboard_fab2(sch_1):page162_i13@mstr_discrete.res~
(chips)',
 PATH='I13',
 DRAWING='@BASEBOARD_FAB2_LIB.BASEBOARD_FAB2(SCH_1):PAGE162',
 WATTAGE='1/16W',
 TOLERANCE='1%',
 SEC_TYPE='0402',
 MATERIAL='CHIP',
 BOM_COST='SM_MEM',
 PHYS_PAGE='162',
 XY='(5075,2550)',
 ROT='0',
 VER='1',
 VALUE='33.2',
 PACK_TYPE='0402',
 PART_NUMBER='G21796-074',
 LOCATION='R8F12',
 ROOM='BMC_BOOT_SPI',
 SEC='1',
 CDS_LIB='mstr_discrete',
 CDS_PART_NAME='RES_0402-33.2,1%,1/16W,CHIP,G2A',
 PRIM_FILE='./archive_libs/mstr_discrete/res/chips/chips.prt';

PART_NAME
 R8F13 'RES_0402-4.75K,1%,1/16W,CHIP,GA':
 ROOM='BMC_BOOT_SPI';

SECTION_NUMBER 1
 '@BASEBOARD_FAB2_LIB.BASEBOARD_FAB2(SCH_1):PAGE162_I35@MSTR_DISCRETE.RES(CHIPS)':
 C_PATH='@baseboard_fab2_lib.baseboard_fab2(sch_1):page162_i35@mstr_discrete.res~
(chips)',
 P_PATH='@baseboard_fab2_lib.baseboard_fab2(sch_1):page162_i35@mstr_discrete.res~
(chips)',
 PATH='I35',
 DRAWING='@BASEBOARD_FAB2_LIB.BASEBOARD_FAB2(SCH_1):PAGE162',
 WATTAGE='1/16W',
 TOLERANCE='1%',
 SEC_TYPE='0402',
 MATERIAL='CHIP',
 BOM_COST='SM_MEM',
 PHYS_PAGE='162',
 XY='(4550,3325)',
 ROT='2',
 VER='2',
 VALUE='4.75K',
 PACK_TYPE='0402',
 PART_NUMBER='G21796-072',
 LOCATION='R8F13',
 ROOM='BMC_BOOT_SPI',
 SEC='1',
 CDS_LIB='mstr_discrete',
 CDS_PART_NAME='RES_0402-4.75K,1%,1/16W,CHIP,GA',
 PRIM_FILE='./archive_libs/mstr_discrete/res/chips/chips.prt';

PART_NAME
 R8F14 'RES_0402-4.75K,1%,1/16W,CHIP,GA':
 ROOM='BMC_BOOT_SPI';

SECTION_NUMBER 1
 '@BASEBOARD_FAB2_LIB.BASEBOARD_FAB2(SCH_1):PAGE162_I9@MSTR_DISCRETE.RES(CHIPS)':
 C_PATH='@baseboard_fab2_lib.baseboard_fab2(sch_1):page162_i9@mstr_discrete.res(~
chips)',
 P_PATH='@baseboard_fab2_lib.baseboard_fab2(sch_1):page162_i9@mstr_discrete.res(~
chips)',
 PATH='I9',
 DRAWING='@BASEBOARD_FAB2_LIB.BASEBOARD_FAB2(SCH_1):PAGE162',
 WATTAGE='1/16W',
 TOLERANCE='1%',
 SEC_TYPE='0402',
 MATERIAL='CHIP',
 BOM_COST='SM_MEM',
 PHYS_PAGE='162',
 XY='(5100,3325)',
 ROT='2',
 VER='2',
 VALUE='4.75K',
 PACK_TYPE='0402',
 PART_NUMBER='G21796-072',
 LOCATION='R8F14',
 ROOM='BMC_BOOT_SPI',
 SEC='1',
 CDS_LIB='mstr_discrete',
 CDS_PART_NAME='RES_0402-4.75K,1%,1/16W,CHIP,GA',
 PRIM_FILE='./archive_libs/mstr_discrete/res/chips/chips.prt';

PART_NAME
 R8F16 'RES_0402-4.75K,1%,1/16W,EMPTY,A':
 ROOM='BMC_BOOT_SPI';

SECTION_NUMBER 1
 '@BASEBOARD_FAB2_LIB.BASEBOARD_FAB2(SCH_1):PAGE162_I8@MSTR_DISCRETE.RES(CHIPS)':
 C_PATH='@baseboard_fab2_lib.baseboard_fab2(sch_1):page162_i8@mstr_discrete.res(~
chips)',
 P_PATH='@baseboard_fab2_lib.baseboard_fab2(sch_1):page162_i8@mstr_discrete.res(~
chips)',
 PATH='I8',
 DRAWING='@BASEBOARD_FAB2_LIB.BASEBOARD_FAB2(SCH_1):PAGE162',
 WATTAGE='1/16W',
 TOLERANCE='1%',
 SEC_TYPE='0402',
 MATERIAL='EMPTY',
 BOM_COST='SM_MEM',
 PHYS_PAGE='162',
 XY='(5300,3300)',
 ROT='0',
 VER='2',
 VALUE='4.75K',
 PACK_TYPE='0402',
 PART_NUMBER='G21796-072',
 LOCATION='R8F16',
 ROOM='BMC_BOOT_SPI',
 SEC='1',
 CDS_LIB='mstr_discrete',
 CDS_PART_NAME='RES_0402-4.75K,1%,1/16W,EMPTY,A',
 PRIM_FILE='./archive_libs/mstr_discrete/res/chips/chips.prt';

PART_NAME
 R8F18 'RES_0402-0.0,5%,1/16W,CHIP,G21A':
 GROUP='M2_PCIE',
 ROOM='M_2';

SECTION_NUMBER 1
 '@BASEBOARD_FAB2_LIB.BASEBOARD_FAB2(SCH_1):PAGE185_I105@MSTR_DISCRETE.RES(CHIPS)':
 C_PATH='@baseboard_fab2_lib.baseboard_fab2(sch_1):page185_i105@mstr_discrete.re~
s(chips)',
 P_PATH='@baseboard_fab2_lib.baseboard_fab2(sch_1):page185_i105@mstr_discrete.re~
s(chips)',
 PATH='I105',
 DRAWING='@BASEBOARD_FAB2_LIB.BASEBOARD_FAB2(SCH_1):PAGE185',
 WATTAGE='1/16W',
 TOLERANCE='5%',
 SEC_TYPE='0402',
 MATERIAL='CHIP',
 BOM_COST='ST_FLASH',
 PHYS_PAGE='185',
 XY='(-2600,950)',
 ROT='0',
 VER='1',
 VALUE='0.0',
 PACK_TYPE='0402',
 PART_NUMBER='G21497-005',
 LOCATION='R8F18',
 ROOM='M_2',
 GROUP='M2_PCIE',
 SEC='1',
 CDS_LIB='mstr_discrete',
 CDS_PART_NAME='RES_0402-0.0,5%,1/16W,CHIP,G21A',
 PRIM_FILE='./archive_libs/mstr_discrete/res/chips/chips.prt';

PART_NAME
 R8F21 'RES_0402-0.0,5%,1/16W,CHIP,G21A':
 GROUP='M2_PCIE',
 ROOM='M_2';

SECTION_NUMBER 1
 '@BASEBOARD_FAB2_LIB.BASEBOARD_FAB2(SCH_1):PAGE185_I106@MSTR_DISCRETE.RES(CHIPS)':
 C_PATH='@baseboard_fab2_lib.baseboard_fab2(sch_1):page185_i106@mstr_discrete.re~
s(chips)',
 P_PATH='@baseboard_fab2_lib.baseboard_fab2(sch_1):page185_i106@mstr_discrete.re~
s(chips)',
 PATH='I106',
 DRAWING='@BASEBOARD_FAB2_LIB.BASEBOARD_FAB2(SCH_1):PAGE185',
 WATTAGE='1/16W',
 TOLERANCE='5%',
 SEC_TYPE='0402',
 MATERIAL='CHIP',
 BOM_COST='ST_FLASH',
 PHYS_PAGE='185',
 XY='(-2575,500)',
 ROT='0',
 VER='1',
 VALUE='0.0',
 PACK_TYPE='0402',
 PART_NUMBER='G21497-005',
 LOCATION='R8F21',
 ROOM='M_2',
 GROUP='M2_PCIE',
 SEC='1',
 CDS_LIB='mstr_discrete',
 CDS_PART_NAME='RES_0402-0.0,5%,1/16W,CHIP,G21A',
 PRIM_FILE='./archive_libs/mstr_discrete/res/chips/chips.prt';

PART_NAME
 R8F23 'RES_0402-2.21K,1%,1/16W,CHIP,GA':
 ROOM='BMC_MISC';

SECTION_NUMBER 1
 '@BASEBOARD_FAB2_LIB.BASEBOARD_FAB2(SCH_1):PAGE157_I296@MSTR_DISCRETE.RES(CHIPS)':
 C_PATH='@baseboard_fab2_lib.baseboard_fab2(sch_1):page157_i296@mstr_discrete.re~
s(chips)',
 P_PATH='@baseboard_fab2_lib.baseboard_fab2(sch_1):page157_i296@mstr_discrete.re~
s(chips)',
 PATH='I296',
 DRAWING='@BASEBOARD_FAB2_LIB.BASEBOARD_FAB2(SCH_1):PAGE157',
 WATTAGE='1/16W',
 TOLERANCE='1%',
 SEC_TYPE='0402',
 MATERIAL='CHIP',
 BOM_COST='SM_CONTROLLER',
 PHYS_PAGE='157',
 XY='(-7200,4225)',
 ROT='0',
 VER='1',
 VALUE='2.21K',
 PACK_TYPE='0402',
 PART_NUMBER='G21796-112',
 LOCATION='R8F23',
 ROOM='BMC_MISC',
 SEC='1',
 CDS_LIB='mstr_discrete',
 CDS_PART_NAME='RES_0402-2.21K,1%,1/16W,CHIP,GA',
 PRIM_FILE='./archive_libs/mstr_discrete/res/chips/chips.prt';

PART_NAME
 R8F24 'RES_0402-4.75K,1%,1/16W,CHIP,GA':
 ROOM='BMC_MISC';

SECTION_NUMBER 1
 '@BASEBOARD_FAB2_LIB.BASEBOARD_FAB2(SCH_1):PAGE157_I316@MSTR_DISCRETE.RES(CHIPS)':
 C_PATH='@baseboard_fab2_lib.baseboard_fab2(sch_1):page157_i316@mstr_discrete.re~
s(chips)',
 P_PATH='@baseboard_fab2_lib.baseboard_fab2(sch_1):page157_i316@mstr_discrete.re~
s(chips)',
 PATH='I316',
 DRAWING='@BASEBOARD_FAB2_LIB.BASEBOARD_FAB2(SCH_1):PAGE157',
 WATTAGE='1/16W',
 TOLERANCE='1%',
 SEC_TYPE='0402',
 MATERIAL='CHIP',
 BOM_COST='SM_CONTROLLER',
 PHYS_PAGE='157',
 XY='(-7175,3725)',
 ROT='0',
 VER='1',
 VALUE='4.75K',
 PACK_TYPE='0402',
 PART_NUMBER='G21796-072',
 LOCATION='R8F24',
 ROOM='BMC_MISC',
 SEC='1',
 CDS_LIB='mstr_discrete',
 CDS_PART_NAME='RES_0402-4.75K,1%,1/16W,CHIP,GA',
 PRIM_FILE='./archive_libs/mstr_discrete/res/chips/chips.prt';

PART_NAME
 R8F25 'RES_0402-475.0,1%,1/16W,CHIP,GA':
 ROOM='SYS_CLOCK';

SECTION_NUMBER 1
 '@BASEBOARD_FAB2_LIB.BASEBOARD_FAB2(SCH_1):PAGE101_I28@MSTR_DISCRETE.RES(CHIPS)':
 C_PATH='@baseboard_fab2_lib.baseboard_fab2(sch_1):page101_i28@mstr_discrete.res~
(chips)',
 P_PATH='@baseboard_fab2_lib.baseboard_fab2(sch_1):page101_i28@mstr_discrete.res~
(chips)',
 PATH='I28',
 DRAWING='@BASEBOARD_FAB2_LIB.BASEBOARD_FAB2(SCH_1):PAGE101',
 WATTAGE='1/16W',
 TOLERANCE='1%',
 MATERIAL='CHIP',
 BOM_COST='SM_CONTROLLER',
 PHYS_PAGE='101',
 XY='(-4375,3000)',
 ROT='2',
 VER='2',
 VALUE='475.0',
 PACK_TYPE='0402',
 PART_NUMBER='G21796-077',
 LOCATION='R8F25',
 ROOM='SYS_CLOCK',
 CDS_LIB='mstr_discrete',
 CDS_PART_NAME='RES_0402-475.0,1%,1/16W,CHIP,GA',
 PRIM_FILE='./archive_libs/mstr_discrete/res/chips/chips.prt';

PART_NAME
 R8F26 'RES_0402-10.0K,1%,1/16W,CHIP,GA':
 ROOM='BMC_MISC';

SECTION_NUMBER 1
 '@BASEBOARD_FAB2_LIB.BASEBOARD_FAB2(SCH_1):PAGE156_I211@MSTR_DISCRETE.RES(CHIPS)':
 C_PATH='@baseboard_fab2_lib.baseboard_fab2(sch_1):page156_i211@mstr_discrete.re~
s(chips)',
 P_PATH='@baseboard_fab2_lib.baseboard_fab2(sch_1):page156_i211@mstr_discrete.re~
s(chips)',
 PATH='I211',
 DRAWING='@BASEBOARD_FAB2_LIB.BASEBOARD_FAB2(SCH_1):PAGE156',
 WATTAGE='1/16W',
 TOLERANCE='1%',
 SEC_TYPE='0402',
 MATERIAL='CHIP',
 BOM_COST='SM_CONTROLLER',
 PHYS_PAGE='156',
 XY='(-2550,4450)',
 ROT='0',
 VER='2',
 VALUE='10.0K',
 PACK_TYPE='0402',
 PART_NUMBER='G21796-016',
 LOCATION='R8F26',
 ROOM='BMC_MISC',
 SEC='1',
 CDS_LIB='mstr_discrete',
 CDS_PART_NAME='RES_0402-10.0K,1%,1/16W,CHIP,GA',
 PRIM_FILE='./archive_libs/mstr_discrete/res/chips/chips.prt';

PART_NAME
 R8F27 'RES_0402-33.2,1%,1/16W,CHIP,G2A':
 ROOM='SYS_CLOCK';

SECTION_NUMBER 1
 '@BASEBOARD_FAB2_LIB.BASEBOARD_FAB2(SCH_1):PAGE101_I142@MSTR_DISCRETE.RES(CHIPS)':
 C_PATH='@baseboard_fab2_lib.baseboard_fab2(sch_1):page101_i142@mstr_discrete.re~
s(chips)',
 P_PATH='@baseboard_fab2_lib.baseboard_fab2(sch_1):page101_i142@mstr_discrete.re~
s(chips)',
 PATH='I142',
 DRAWING='@BASEBOARD_FAB2_LIB.BASEBOARD_FAB2(SCH_1):PAGE101',
 WATTAGE='1/16W',
 TOLERANCE='1%',
 SEC_TYPE='0402',
 MATERIAL='CHIP',
 BOM_COST='SM_CONTROLLER',
 PHYS_PAGE='101',
 XY='(-3050,2775)',
 ROT='0',
 VER='1',
 VALUE='33.2',
 PACK_TYPE='0402',
 PART_NUMBER='G21796-074',
 LOCATION='R8F27',
 ROOM='SYS_CLOCK',
 SEC='1',
 CDS_LIB='mstr_discrete',
 CDS_PART_NAME='RES_0402-33.2,1%,1/16W,CHIP,G2A',
 PRIM_FILE='./archive_libs/mstr_discrete/res/chips/chips.prt';

PART_NAME
 R8F29 'RES_0402-33.2,1%,1/16W,CHIP,G2A':
 ROOM='SYS_CLOCK';

SECTION_NUMBER 1
 '@BASEBOARD_FAB2_LIB.BASEBOARD_FAB2(SCH_1):PAGE101_I20@MSTR_DISCRETE.RES(CHIPS)':
 C_PATH='@baseboard_fab2_lib.baseboard_fab2(sch_1):page101_i20@mstr_discrete.res~
(chips)',
 P_PATH='@baseboard_fab2_lib.baseboard_fab2(sch_1):page101_i20@mstr_discrete.res~
(chips)',
 PATH='I20',
 DRAWING='@BASEBOARD_FAB2_LIB.BASEBOARD_FAB2(SCH_1):PAGE101',
 WATTAGE='1/16W',
 TOLERANCE='1%',
 SEC_TYPE='0402',
 MATERIAL='CHIP',
 BOM_COST='SM_CONTROLLER',
 PHYS_PAGE='101',
 XY='(-3050,2450)',
 ROT='0',
 VER='1',
 VALUE='33.2',
 PACK_TYPE='0402',
 PART_NUMBER='G21796-074',
 LOCATION='R8F29',
 ROOM='SYS_CLOCK',
 SEC='1',
 CDS_LIB='mstr_discrete',
 CDS_PART_NAME='RES_0402-33.2,1%,1/16W,CHIP,G2A',
 PRIM_FILE='./archive_libs/mstr_discrete/res/chips/chips.prt';

PART_NAME
 R8F34 'RES_0402-4.75K,1%,1/16W,CHIP,GA':
 ROOM='BMC_BOOT_SPI';

SECTION_NUMBER 1
 '@BASEBOARD_FAB2_LIB.BASEBOARD_FAB2(SCH_1):PAGE162_I22@MSTR_DISCRETE.RES(CHIPS)':
 C_PATH='@baseboard_fab2_lib.baseboard_fab2(sch_1):page162_i22@mstr_discrete.res~
(chips)',
 P_PATH='@baseboard_fab2_lib.baseboard_fab2(sch_1):page162_i22@mstr_discrete.res~
(chips)',
 PATH='I22',
 DRAWING='@BASEBOARD_FAB2_LIB.BASEBOARD_FAB2(SCH_1):PAGE162',
 WATTAGE='1/16W',
 TOLERANCE='1%',
 SEC_TYPE='0402',
 MATERIAL='CHIP',
 BOM_COST='SM_MEM',
 PHYS_PAGE='162',
 XY='(4825,3325)',
 ROT='2',
 VER='2',
 VALUE='4.75K',
 PACK_TYPE='0402',
 PART_NUMBER='G21796-072',
 LOCATION='R8F34',
 ROOM='BMC_BOOT_SPI',
 SEC='1',
 CDS_LIB='mstr_discrete',
 CDS_PART_NAME='RES_0402-4.75K,1%,1/16W,CHIP,GA',
 PRIM_FILE='./archive_libs/mstr_discrete/res/chips/chips.prt';

PART_NAME
 R8F35 'RES_0402-1.00K,1%,1/16W,EMPTY,A':
 ROOM='BMC_BOOT_SPI';

SECTION_NUMBER 1
 '@BASEBOARD_FAB2_LIB.BASEBOARD_FAB2(SCH_1):PAGE162_I24@MSTR_DISCRETE.RES(CHIPS)':
 C_PATH='@baseboard_fab2_lib.baseboard_fab2(sch_1):page162_i24@mstr_discrete.res~
(chips)',
 P_PATH='@baseboard_fab2_lib.baseboard_fab2(sch_1):page162_i24@mstr_discrete.res~
(chips)',
 PATH='I24',
 DRAWING='@BASEBOARD_FAB2_LIB.BASEBOARD_FAB2(SCH_1):PAGE162',
 WATTAGE='1/16W',
 TOLERANCE='1%',
 SEC_TYPE='0402',
 MATERIAL='EMPTY',
 BOM_COST='SM_MEM',
 PHYS_PAGE='162',
 XY='(4875,2050)',
 ROT='0',
 VER='2',
 VALUE='1.00K',
 PACK_TYPE='0402',
 PART_NUMBER='G21796-026',
 LOCATION='R8F35',
 ROOM='BMC_BOOT_SPI',
 SEC='1',
 CDS_LIB='mstr_discrete',
 CDS_PART_NAME='RES_0402-1.00K,1%,1/16W,EMPTY,A',
 PRIM_FILE='./archive_libs/mstr_discrete/res/chips/chips.prt';

PART_NAME
 R8F36 'RES_0402-10.0K,1%,1/16W,CHIP,GA':
 ROOM='M_2';

SECTION_NUMBER 1
 '@BASEBOARD_FAB2_LIB.BASEBOARD_FAB2(SCH_1):PAGE185_I136@MSTR_DISCRETE.RES(CHIPS)':
 C_PATH='@baseboard_fab2_lib.baseboard_fab2(sch_1):page185_i136@mstr_discrete.re~
s(chips)',
 P_PATH='@baseboard_fab2_lib.baseboard_fab2(sch_1):page185_i136@mstr_discrete.re~
s(chips)',
 PATH='I136',
 DRAWING='@BASEBOARD_FAB2_LIB.BASEBOARD_FAB2(SCH_1):PAGE185',
 WATTAGE='1/16W',
 TOLERANCE='1%',
 SEC_TYPE='0402',
 MATERIAL='CHIP',
 BOM_COST='ST_FLASH',
 PHYS_PAGE='185',
 XY='(-8000,3500)',
 ROT='0',
 VER='2',
 VALUE='10.0K',
 PACK_TYPE='0402',
 PART_NUMBER='G21796-016',
 LOCATION='R8F36',
 ROOM='M_2',
 SEC='1',
 CDS_LIB='mstr_discrete',
 CDS_PART_NAME='RES_0402-10.0K,1%,1/16W,CHIP,GA',
 PRIM_FILE='./archive_libs/mstr_discrete/res/chips/chips.prt';

PART_NAME
 R8F37 'RES_0402-0.0,5%,1/16W,EMPTY,G2A':;

SECTION_NUMBER 1
 '@BASEBOARD_FAB2_LIB.BASEBOARD_FAB2(SCH_1):PAGE93_I131@MSTR_DISCRETE.RES(CHIPS)':
 C_PATH='@baseboard_fab2_lib.baseboard_fab2(sch_1):page93_i131@mstr_discrete.res~
(chips)',
 P_PATH='@baseboard_fab2_lib.baseboard_fab2(sch_1):page93_i131@mstr_discrete.res~
(chips)',
 PATH='I131',
 DRAWING='@BASEBOARD_FAB2_LIB.BASEBOARD_FAB2(SCH_1):PAGE93',
 WATTAGE='1/16W',
 TOLERANCE='5%',
 SEC_TYPE='0402',
 MATERIAL='EMPTY',
 PHYS_PAGE='93',
 XY='(-2225,1250)',
 ROT='0',
 VER='1',
 VALUE='0.0',
 PACK_TYPE='0402',
 PART_NUMBER='G21497-005',
 LOCATION='R8F37',
 SEC='1',
 CDS_LIB='mstr_discrete',
 CDS_PART_NAME='RES_0402-0.0,5%,1/16W,EMPTY,G2A',
 PRIM_FILE='./archive_libs/mstr_discrete/res/chips/chips.prt';

PART_NAME
 R8F38 'RES_0402-0.0,5%,1/16W,CHIP,G21A':;

SECTION_NUMBER 1
 '@BASEBOARD_FAB2_LIB.BASEBOARD_FAB2(SCH_1):PAGE93_I119@MSTR_DISCRETE.RES(CHIPS)':
 C_PATH='@baseboard_fab2_lib.baseboard_fab2(sch_1):page93_i119@mstr_discrete.res~
(chips)',
 P_PATH='@baseboard_fab2_lib.baseboard_fab2(sch_1):page93_i119@mstr_discrete.res~
(chips)',
 PATH='I119',
 DRAWING='@BASEBOARD_FAB2_LIB.BASEBOARD_FAB2(SCH_1):PAGE93',
 WATTAGE='1/16W',
 TOLERANCE='5%',
 SEC_TYPE='0402',
 MATERIAL='CHIP',
 PHYS_PAGE='93',
 XY='(-2225,1450)',
 ROT='0',
 VER='1',
 VALUE='0.0',
 PACK_TYPE='0402',
 PART_NUMBER='G21497-005',
 LOCATION='R8F38',
 SEC='1',
 CDS_LIB='mstr_discrete',
 CDS_PART_NAME='RES_0402-0.0,5%,1/16W,CHIP,G21A',
 PRIM_FILE='./archive_libs/mstr_discrete/res/chips/chips.prt';

PART_NAME
 R8G1 'RES_0402-22.1,1.0%,1/16W,CHIP,A':
 ROOM='SYS_CLOCK';

SECTION_NUMBER 1
 '@BASEBOARD_FAB2_LIB.BASEBOARD_FAB2(SCH_1):PAGE101_I145@MSTR_DISCRETE.RES(CHIPS)':
 C_PATH='@baseboard_fab2_lib.baseboard_fab2(sch_1):page101_i145@mstr_discrete.re~
s(chips)',
 P_PATH='@baseboard_fab2_lib.baseboard_fab2(sch_1):page101_i145@mstr_discrete.re~
s(chips)',
 PATH='I145',
 DRAWING='@BASEBOARD_FAB2_LIB.BASEBOARD_FAB2(SCH_1):PAGE101',
 WATTAGE='1/16W',
 TOLERANCE='1.0%',
 SEC_TYPE='0402',
 MATERIAL='CHIP',
 BOM_COST='SM_CONTROLLER',
 PHYS_PAGE='101',
 XY='(-3050,1850)',
 ROT='0',
 VER='1',
 VALUE='22.1',
 PACK_TYPE='0402',
 PART_NUMBER='G21796-250',
 LOCATION='R8G1',
 ROOM='SYS_CLOCK',
 SEC='1',
 CDS_LIB='mstr_discrete',
 CDS_PART_NAME='RES_0402-22.1,1.0%,1/16W,CHIP,A',
 PRIM_FILE='./archive_libs/mstr_discrete/res/chips/chips.prt';

PART_NAME
 R8G2 'RES_0402-4.75K,1%,1/16W,CHIP,GA':
 ROOM='BMC_MISC';

SECTION_NUMBER 1
 '@BASEBOARD_FAB2_LIB.BASEBOARD_FAB2(SCH_1):PAGE156_I267@MSTR_DISCRETE.RES(CHIPS)':
 C_PATH='@baseboard_fab2_lib.baseboard_fab2(sch_1):page156_i267@mstr_discrete.re~
s(chips)',
 P_PATH='@baseboard_fab2_lib.baseboard_fab2(sch_1):page156_i267@mstr_discrete.re~
s(chips)',
 PATH='I267',
 DRAWING='@BASEBOARD_FAB2_LIB.BASEBOARD_FAB2(SCH_1):PAGE156',
 WATTAGE='1/16W',
 TOLERANCE='1%',
 SEC_TYPE='0402',
 MATERIAL='CHIP',
 BOM_COST='SM_CONTROLLER',
 PHYS_PAGE='156',
 XY='(-4150,3250)',
 ROT='0',
 VER='2',
 VALUE='4.75K',
 PACK_TYPE='0402',
 PART_NUMBER='G21796-072',
 LOCATION='R8G2',
 ROOM='BMC_MISC',
 SEC='1',
 CDS_LIB='mstr_discrete',
 CDS_PART_NAME='RES_0402-4.75K,1%,1/16W,CHIP,GA',
 PRIM_FILE='./archive_libs/mstr_discrete/res/chips/chips.prt';

PART_NAME
 R8G3 'RES_0402-2.26K,1.0%,1/16W,EMPTA':
 ROOM='SMBUS';

SECTION_NUMBER 1
 '@BASEBOARD_FAB2_LIB.BASEBOARD_FAB2(SCH_1):PAGE159_I210@MSTR_DISCRETE.RES(CHIPS)':
 C_PATH='@baseboard_fab2_lib.baseboard_fab2(sch_1):page159_i210@mstr_discrete.re~
s(chips)',
 P_PATH='@baseboard_fab2_lib.baseboard_fab2(sch_1):page159_i210@mstr_discrete.re~
s(chips)',
 PATH='I210',
 DRAWING='@BASEBOARD_FAB2_LIB.BASEBOARD_FAB2(SCH_1):PAGE159',
 SKU='B',
 WATTAGE='1/16W',
 TOLERANCE='1.0%',
 SEC_TYPE='0402',
 MATERIAL='EMPTY',
 BOM_COST='SM_CONTROLLER',
 PHYS_PAGE='159',
 XY='(-3375,2900)',
 ROT='0',
 VER='2',
 VALUE='2.26K',
 PACK_TYPE='0402',
 PART_NUMBER='G21796-311',
 LOCATION='R8G3',
 ROOM='SMBUS',
 SEC='1',
 CDS_LIB='mstr_discrete',
 CDS_PART_NAME='RES_0402-2.26K,1.0%,1/16W,EMPTA',
 PRIM_FILE='./archive_libs/mstr_discrete/res/chips/chips.prt';

PART_NAME
 R8G4 'RES_0402-20.0,1%,1/16W,CHIP,G2A':
 ROOM='SMBUS';

SECTION_NUMBER 1
 '@BASEBOARD_FAB2_LIB.BASEBOARD_FAB2(SCH_1):PAGE159_I229@MSTR_DISCRETE.RES(CHIPS)':
 C_PATH='@baseboard_fab2_lib.baseboard_fab2(sch_1):page159_i229@mstr_discrete.re~
s(chips)',
 P_PATH='@baseboard_fab2_lib.baseboard_fab2(sch_1):page159_i229@mstr_discrete.re~
s(chips)',
 PATH='I229',
 DRAWING='@BASEBOARD_FAB2_LIB.BASEBOARD_FAB2(SCH_1):PAGE159',
 WATTAGE='1/16W',
 TOLERANCE='1%',
 MATERIAL='CHIP',
 BOM_COST='SM_CONTROLLER',
 PHYS_PAGE='159',
 XY='(-2875,2350)',
 ROT='0',
 VER='1',
 VALUE='20.0',
 PACK_TYPE='0402',
 PART_NUMBER='G21796-173',
 LOCATION='R8G4',
 ROOM='SMBUS',
 CDS_LIB='mstr_discrete',
 CDS_PART_NAME='RES_0402-20.0,1%,1/16W,CHIP,G2A',
 PRIM_FILE='./archive_libs/mstr_discrete/res/chips/chips.prt';

PART_NAME
 R8G5 'RES_0402-20.0,1%,1/16W,CHIP,G2A':
 ROOM='SMBUS';

SECTION_NUMBER 1
 '@BASEBOARD_FAB2_LIB.BASEBOARD_FAB2(SCH_1):PAGE159_I228@MSTR_DISCRETE.RES(CHIPS)':
 C_PATH='@baseboard_fab2_lib.baseboard_fab2(sch_1):page159_i228@mstr_discrete.re~
s(chips)',
 P_PATH='@baseboard_fab2_lib.baseboard_fab2(sch_1):page159_i228@mstr_discrete.re~
s(chips)',
 PATH='I228',
 DRAWING='@BASEBOARD_FAB2_LIB.BASEBOARD_FAB2(SCH_1):PAGE159',
 WATTAGE='1/16W',
 TOLERANCE='1%',
 MATERIAL='CHIP',
 BOM_COST='SM_CONTROLLER',
 PHYS_PAGE='159',
 XY='(-2875,2525)',
 ROT='0',
 VER='1',
 VALUE='20.0',
 PACK_TYPE='0402',
 PART_NUMBER='G21796-173',
 LOCATION='R8G5',
 ROOM='SMBUS',
 CDS_LIB='mstr_discrete',
 CDS_PART_NAME='RES_0402-20.0,1%,1/16W,CHIP,G2A',
 PRIM_FILE='./archive_libs/mstr_discrete/res/chips/chips.prt';

PART_NAME
 R8G6 'RES_0402-2.26K,1.0%,1/16W,EMPTA':
 ROOM='SMBUS';

SECTION_NUMBER 1
 '@BASEBOARD_FAB2_LIB.BASEBOARD_FAB2(SCH_1):PAGE159_I212@MSTR_DISCRETE.RES(CHIPS)':
 C_PATH='@baseboard_fab2_lib.baseboard_fab2(sch_1):page159_i212@mstr_discrete.re~
s(chips)',
 P_PATH='@baseboard_fab2_lib.baseboard_fab2(sch_1):page159_i212@mstr_discrete.re~
s(chips)',
 PATH='I212',
 DRAWING='@BASEBOARD_FAB2_LIB.BASEBOARD_FAB2(SCH_1):PAGE159',
 SKU='B',
 WATTAGE='1/16W',
 TOLERANCE='1.0%',
 SEC_TYPE='0402',
 MATERIAL='EMPTY',
 BOM_COST='SM_CONTROLLER',
 PHYS_PAGE='159',
 XY='(-3725,2900)',
 ROT='0',
 VER='2',
 VALUE='2.26K',
 PACK_TYPE='0402',
 PART_NUMBER='G21796-311',
 LOCATION='R8G6',
 ROOM='SMBUS',
 SEC='1',
 CDS_LIB='mstr_discrete',
 CDS_PART_NAME='RES_0402-2.26K,1.0%,1/16W,EMPTA',
 PRIM_FILE='./archive_libs/mstr_discrete/res/chips/chips.prt';

PART_NAME
 R8G7 'RES_0402-0.0,5%,1/16W,CHIP,G21A':
 ROOM='BMC_DEBUG_HEADER';

SECTION_NUMBER 1
 '@BASEBOARD_FAB2_LIB.BASEBOARD_FAB2(SCH_1):PAGE189_I18@MSTR_DISCRETE.RES(CHIPS)':
 C_PATH='@baseboard_fab2_lib.baseboard_fab2(sch_1):page189_i18@mstr_discrete.res~
(chips)',
 P_PATH='@baseboard_fab2_lib.baseboard_fab2(sch_1):page189_i18@mstr_discrete.res~
(chips)',
 PATH='I18',
 DRAWING='@BASEBOARD_FAB2_LIB.BASEBOARD_FAB2(SCH_1):PAGE189',
 WATTAGE='1/16W',
 TOLERANCE='5%',
 SEC_TYPE='0402',
 MATERIAL='CHIP',
 BOM_COST='DEBUG',
 PHYS_PAGE='189',
 XY='(-125,4650)',
 ROT='0',
 VER='1',
 VALUE='0.0',
 PACK_TYPE='0402',
 PART_NUMBER='G21497-005',
 LOCATION='R8G7',
 ROOM='BMC_DEBUG_HEADER',
 SEC='1',
 CDS_LIB='mstr_discrete',
 CDS_PART_NAME='RES_0402-0.0,5%,1/16W,CHIP,G21A',
 PRIM_FILE='./archive_libs/mstr_discrete/res/chips/chips.prt';

PART_NAME
 R8G8 'RES_0402-0.0,5%,1/16W,CHIP,G21A':
 ROOM='BMC_DEBUG_HEADER';

SECTION_NUMBER 1
 '@BASEBOARD_FAB2_LIB.BASEBOARD_FAB2(SCH_1):PAGE189_I17@MSTR_DISCRETE.RES(CHIPS)':
 C_PATH='@baseboard_fab2_lib.baseboard_fab2(sch_1):page189_i17@mstr_discrete.res~
(chips)',
 P_PATH='@baseboard_fab2_lib.baseboard_fab2(sch_1):page189_i17@mstr_discrete.res~
(chips)',
 PATH='I17',
 DRAWING='@BASEBOARD_FAB2_LIB.BASEBOARD_FAB2(SCH_1):PAGE189',
 WATTAGE='1/16W',
 TOLERANCE='5%',
 SEC_TYPE='0402',
 MATERIAL='CHIP',
 BOM_COST='DEBUG',
 PHYS_PAGE='189',
 XY='(-2100,4050)',
 ROT='0',
 VER='1',
 VALUE='0.0',
 PACK_TYPE='0402',
 PART_NUMBER='G21497-005',
 LOCATION='R8G8',
 ROOM='BMC_DEBUG_HEADER',
 SEC='1',
 CDS_LIB='mstr_discrete',
 CDS_PART_NAME='RES_0402-0.0,5%,1/16W,CHIP,G21A',
 PRIM_FILE='./archive_libs/mstr_discrete/res/chips/chips.prt';

PART_NAME
 R8G9 'RES_0402-0.0,5%,1/16W,EMPTY,G2A':
 ROOM='BMC_DEBUG_HEADER';

SECTION_NUMBER 1
 '@BASEBOARD_FAB2_LIB.BASEBOARD_FAB2(SCH_1):PAGE189_I9@MSTR_DISCRETE.RES(CHIPS)':
 C_PATH='@baseboard_fab2_lib.baseboard_fab2(sch_1):page189_i9@mstr_discrete.res(~
chips)',
 P_PATH='@baseboard_fab2_lib.baseboard_fab2(sch_1):page189_i9@mstr_discrete.res(~
chips)',
 PATH='I9',
 DRAWING='@BASEBOARD_FAB2_LIB.BASEBOARD_FAB2(SCH_1):PAGE189',
 WATTAGE='1/16W',
 TOLERANCE='5%',
 MATERIAL='EMPTY',
 BOM_COST='DEBUG',
 PHYS_PAGE='189',
 XY='(-2100,4600)',
 ROT='0',
 VER='1',
 VALUE='0.0',
 PACK_TYPE='0402',
 PART_NUMBER='G21497-005',
 LOCATION='R8G9',
 ROOM='BMC_DEBUG_HEADER',
 CDS_LIB='mstr_discrete',
 CDS_PART_NAME='RES_0402-0.0,5%,1/16W,EMPTY,G2A',
 PRIM_FILE='./archive_libs/mstr_discrete/res/chips/chips.prt';

PART_NAME
 R8G10 'RES_0402-0.0,5%,1/16W,CHIP,G21A':
 ROOM='BMC_DEBUG_HEADER';

SECTION_NUMBER 1
 '@BASEBOARD_FAB2_LIB.BASEBOARD_FAB2(SCH_1):PAGE189_I7@MSTR_DISCRETE.RES(CHIPS)':
 C_PATH='@baseboard_fab2_lib.baseboard_fab2(sch_1):page189_i7@mstr_discrete.res(~
chips)',
 P_PATH='@baseboard_fab2_lib.baseboard_fab2(sch_1):page189_i7@mstr_discrete.res(~
chips)',
 PATH='I7',
 DRAWING='@BASEBOARD_FAB2_LIB.BASEBOARD_FAB2(SCH_1):PAGE189',
 WATTAGE='1/16W',
 TOLERANCE='5%',
 SEC_TYPE='0402',
 MATERIAL='CHIP',
 BOM_COST='DEBUG',
 PHYS_PAGE='189',
 XY='(-2100,4775)',
 ROT='0',
 VER='1',
 VALUE='0.0',
 PACK_TYPE='0402',
 PART_NUMBER='G21497-005',
 LOCATION='R8G10',
 ROOM='BMC_DEBUG_HEADER',
 SEC='1',
 CDS_LIB='mstr_discrete',
 CDS_PART_NAME='RES_0402-0.0,5%,1/16W,CHIP,G21A',
 PRIM_FILE='./archive_libs/mstr_discrete/res/chips/chips.prt';

PART_NAME
 R8G11 'RES_0402-0.0,5%,1/16W,EMPTY,G2A':
 ROOM='BMC_DEBUG_HEADER';

SECTION_NUMBER 1
 '@BASEBOARD_FAB2_LIB.BASEBOARD_FAB2(SCH_1):PAGE189_I19@MSTR_DISCRETE.RES(CHIPS)':
 C_PATH='@baseboard_fab2_lib.baseboard_fab2(sch_1):page189_i19@mstr_discrete.res~
(chips)',
 P_PATH='@baseboard_fab2_lib.baseboard_fab2(sch_1):page189_i19@mstr_discrete.res~
(chips)',
 PATH='I19',
 DRAWING='@BASEBOARD_FAB2_LIB.BASEBOARD_FAB2(SCH_1):PAGE189',
 WATTAGE='1/16W',
 TOLERANCE='5%',
 SEC_TYPE='0402',
 MATERIAL='EMPTY',
 BOM_COST='DEBUG',
 PHYS_PAGE='189',
 XY='(-2100,3500)',
 ROT='0',
 VER='1',
 VALUE='0.0',
 PACK_TYPE='0402',
 PART_NUMBER='G21497-005',
 LOCATION='R8G11',
 ROOM='BMC_DEBUG_HEADER',
 SEC='1',
 CDS_LIB='mstr_discrete',
 CDS_PART_NAME='RES_0402-0.0,5%,1/16W,EMPTY,G2A',
 PRIM_FILE='./archive_libs/mstr_discrete/res/chips/chips.prt';

PART_NAME
 R8G12 'RES_0402-0.0,5%,1/16W,EMPTY,G2A':
 ROOM='BMC_DEBUG_HEADER';

SECTION_NUMBER 1
 '@BASEBOARD_FAB2_LIB.BASEBOARD_FAB2(SCH_1):PAGE189_I21@MSTR_DISCRETE.RES(CHIPS)':
 C_PATH='@baseboard_fab2_lib.baseboard_fab2(sch_1):page189_i21@mstr_discrete.res~
(chips)',
 P_PATH='@baseboard_fab2_lib.baseboard_fab2(sch_1):page189_i21@mstr_discrete.res~
(chips)',
 PATH='I21',
 DRAWING='@BASEBOARD_FAB2_LIB.BASEBOARD_FAB2(SCH_1):PAGE189',
 WATTAGE='1/16W',
 TOLERANCE='5%',
 SEC_TYPE='0402',
 MATERIAL='EMPTY',
 BOM_COST='DEBUG',
 PHYS_PAGE='189',
 XY='(-2100,3675)',
 ROT='0',
 VER='1',
 VALUE='0.0',
 PACK_TYPE='0402',
 PART_NUMBER='G21497-005',
 LOCATION='R8G12',
 ROOM='BMC_DEBUG_HEADER',
 SEC='1',
 CDS_LIB='mstr_discrete',
 CDS_PART_NAME='RES_0402-0.0,5%,1/16W,EMPTY,G2A',
 PRIM_FILE='./archive_libs/mstr_discrete/res/chips/chips.prt';

PART_NAME
 R8G13 'RES_0402-0.0,5%,1/16W,CHIP,G21A':
 ROOM='BMC_DEBUG_HEADER';

SECTION_NUMBER 1
 '@BASEBOARD_FAB2_LIB.BASEBOARD_FAB2(SCH_1):PAGE189_I23@MSTR_DISCRETE.RES(CHIPS)':
 C_PATH='@baseboard_fab2_lib.baseboard_fab2(sch_1):page189_i23@mstr_discrete.res~
(chips)',
 P_PATH='@baseboard_fab2_lib.baseboard_fab2(sch_1):page189_i23@mstr_discrete.res~
(chips)',
 PATH='I23',
 DRAWING='@BASEBOARD_FAB2_LIB.BASEBOARD_FAB2(SCH_1):PAGE189',
 WATTAGE='1/16W',
 TOLERANCE='5%',
 SEC_TYPE='0402',
 MATERIAL='CHIP',
 BOM_COST='DEBUG',
 PHYS_PAGE='189',
 XY='(-125,4450)',
 ROT='0',
 VER='1',
 VALUE='0.0',
 PACK_TYPE='0402',
 PART_NUMBER='G21497-005',
 LOCATION='R8G13',
 ROOM='BMC_DEBUG_HEADER',
 SEC='1',
 CDS_LIB='mstr_discrete',
 CDS_PART_NAME='RES_0402-0.0,5%,1/16W,CHIP,G21A',
 PRIM_FILE='./archive_libs/mstr_discrete/res/chips/chips.prt';

PART_NAME
 R8G14 'RES_0402-0.0,5%,1/16W,CHIP,G21A':
 ROOM='BMC_DEBUG_HEADER';

SECTION_NUMBER 1
 '@BASEBOARD_FAB2_LIB.BASEBOARD_FAB2(SCH_1):PAGE189_I20@MSTR_DISCRETE.RES(CHIPS)':
 C_PATH='@baseboard_fab2_lib.baseboard_fab2(sch_1):page189_i20@mstr_discrete.res~
(chips)',
 P_PATH='@baseboard_fab2_lib.baseboard_fab2(sch_1):page189_i20@mstr_discrete.res~
(chips)',
 PATH='I20',
 DRAWING='@BASEBOARD_FAB2_LIB.BASEBOARD_FAB2(SCH_1):PAGE189',
 WATTAGE='1/16W',
 TOLERANCE='5%',
 SEC_TYPE='0402',
 MATERIAL='CHIP',
 BOM_COST='DEBUG',
 PHYS_PAGE='189',
 XY='(-2100,3350)',
 ROT='0',
 VER='1',
 VALUE='0.0',
 PACK_TYPE='0402',
 PART_NUMBER='G21497-005',
 LOCATION='R8G14',
 ROOM='BMC_DEBUG_HEADER',
 SEC='1',
 CDS_LIB='mstr_discrete',
 CDS_PART_NAME='RES_0402-0.0,5%,1/16W,CHIP,G21A',
 PRIM_FILE='./archive_libs/mstr_discrete/res/chips/chips.prt';

PART_NAME
 R8G15 'RES_0402-0.0,5%,1/16W,EMPTY,G2A':
 ROOM='BMC_DEBUG_HEADER';

SECTION_NUMBER 1
 '@BASEBOARD_FAB2_LIB.BASEBOARD_FAB2(SCH_1):PAGE189_I24@MSTR_DISCRETE.RES(CHIPS)':
 C_PATH='@baseboard_fab2_lib.baseboard_fab2(sch_1):page189_i24@mstr_discrete.res~
(chips)',
 P_PATH='@baseboard_fab2_lib.baseboard_fab2(sch_1):page189_i24@mstr_discrete.res~
(chips)',
 PATH='I24',
 DRAWING='@BASEBOARD_FAB2_LIB.BASEBOARD_FAB2(SCH_1):PAGE189',
 WATTAGE='1/16W',
 TOLERANCE='5%',
 SEC_TYPE='0402',
 MATERIAL='EMPTY',
 BOM_COST='DEBUG',
 PHYS_PAGE='189',
 XY='(-2100,2975)',
 ROT='0',
 VER='1',
 VALUE='0.0',
 PACK_TYPE='0402',
 PART_NUMBER='G21497-005',
 LOCATION='R8G15',
 ROOM='BMC_DEBUG_HEADER',
 SEC='1',
 CDS_LIB='mstr_discrete',
 CDS_PART_NAME='RES_0402-0.0,5%,1/16W,EMPTY,G2A',
 PRIM_FILE='./archive_libs/mstr_discrete/res/chips/chips.prt';

PART_NAME
 R8G16 'RES_0402-0.0,5%,1/16W,EMPTY,G2A':
 ROOM='BMC_DEBUG_HEADER';

SECTION_NUMBER 1
 '@BASEBOARD_FAB2_LIB.BASEBOARD_FAB2(SCH_1):PAGE189_I22@MSTR_DISCRETE.RES(CHIPS)':
 C_PATH='@baseboard_fab2_lib.baseboard_fab2(sch_1):page189_i22@mstr_discrete.res~
(chips)',
 P_PATH='@baseboard_fab2_lib.baseboard_fab2(sch_1):page189_i22@mstr_discrete.res~
(chips)',
 PATH='I22',
 DRAWING='@BASEBOARD_FAB2_LIB.BASEBOARD_FAB2(SCH_1):PAGE189',
 WATTAGE='1/16W',
 TOLERANCE='5%',
 SEC_TYPE='0402',
 MATERIAL='EMPTY',
 BOM_COST='DEBUG',
 PHYS_PAGE='189',
 XY='(-2100,2800)',
 ROT='0',
 VER='1',
 VALUE='0.0',
 PACK_TYPE='0402',
 PART_NUMBER='G21497-005',
 LOCATION='R8G16',
 ROOM='BMC_DEBUG_HEADER',
 SEC='1',
 CDS_LIB='mstr_discrete',
 CDS_PART_NAME='RES_0402-0.0,5%,1/16W,EMPTY,G2A',
 PRIM_FILE='./archive_libs/mstr_discrete/res/chips/chips.prt';

PART_NAME
 R8G17 'RES_0402-0.0,5%,1/16W,CHIP,G21A':
 ROOM='BMC_DEBUG_HEADER';

SECTION_NUMBER 1
 '@BASEBOARD_FAB2_LIB.BASEBOARD_FAB2(SCH_1):PAGE189_I25@MSTR_DISCRETE.RES(CHIPS)':
 C_PATH='@baseboard_fab2_lib.baseboard_fab2(sch_1):page189_i25@mstr_discrete.res~
(chips)',
 P_PATH='@baseboard_fab2_lib.baseboard_fab2(sch_1):page189_i25@mstr_discrete.res~
(chips)',
 PATH='I25',
 DRAWING='@BASEBOARD_FAB2_LIB.BASEBOARD_FAB2(SCH_1):PAGE189',
 WATTAGE='1/16W',
 TOLERANCE='5%',
 SEC_TYPE='0402',
 MATERIAL='CHIP',
 BOM_COST='DEBUG',
 PHYS_PAGE='189',
 XY='(-2100,2625)',
 ROT='0',
 VER='1',
 VALUE='0.0',
 PACK_TYPE='0402',
 PART_NUMBER='G21497-005',
 LOCATION='R8G17',
 ROOM='BMC_DEBUG_HEADER',
 SEC='1',
 CDS_LIB='mstr_discrete',
 CDS_PART_NAME='RES_0402-0.0,5%,1/16W,CHIP,G21A',
 PRIM_FILE='./archive_libs/mstr_discrete/res/chips/chips.prt';

PART_NAME
 R8G18 'RES_0402-0.0,5%,1/16W,CHIP,G21A':
 ROOM='BMC_DEBUG_HEADER';

SECTION_NUMBER 1
 '@BASEBOARD_FAB2_LIB.BASEBOARD_FAB2(SCH_1):PAGE189_I26@MSTR_DISCRETE.RES(CHIPS)':
 C_PATH='@baseboard_fab2_lib.baseboard_fab2(sch_1):page189_i26@mstr_discrete.res~
(chips)',
 P_PATH='@baseboard_fab2_lib.baseboard_fab2(sch_1):page189_i26@mstr_discrete.res~
(chips)',
 PATH='I26',
 DRAWING='@BASEBOARD_FAB2_LIB.BASEBOARD_FAB2(SCH_1):PAGE189',
 WATTAGE='1/16W',
 TOLERANCE='5%',
 SEC_TYPE='0402',
 MATERIAL='CHIP',
 BOM_COST='DEBUG',
 PHYS_PAGE='189',
 XY='(-125,4250)',
 ROT='0',
 VER='1',
 VALUE='0.0',
 PACK_TYPE='0402',
 PART_NUMBER='G21497-005',
 LOCATION='R8G18',
 ROOM='BMC_DEBUG_HEADER',
 SEC='1',
 CDS_LIB='mstr_discrete',
 CDS_PART_NAME='RES_0402-0.0,5%,1/16W,CHIP,G21A',
 PRIM_FILE='./archive_libs/mstr_discrete/res/chips/chips.prt';

PART_NAME
 R8G19 'RES_0402-0.0,5%,1/16W,CHIP,G21A':
 ROOM='BMC_DEBUG_HEADER';

SECTION_NUMBER 1
 '@BASEBOARD_FAB2_LIB.BASEBOARD_FAB2(SCH_1):PAGE189_I64@MSTR_DISCRETE.RES(CHIPS)':
 C_PATH='@baseboard_fab2_lib.baseboard_fab2(sch_1):page189_i64@mstr_discrete.res~
(chips)',
 P_PATH='@baseboard_fab2_lib.baseboard_fab2(sch_1):page189_i64@mstr_discrete.res~
(chips)',
 PATH='I64',
 DRAWING='@BASEBOARD_FAB2_LIB.BASEBOARD_FAB2(SCH_1):PAGE189',
 WATTAGE='1/16W',
 TOLERANCE='5%',
 SEC_TYPE='0402',
 MATERIAL='CHIP',
 BOM_COST='DEBUG',
 PHYS_PAGE='189',
 XY='(2425,3175)',
 ROT='0',
 VER='1',
 VALUE='0.0',
 PACK_TYPE='0402',
 PART_NUMBER='G21497-005',
 LOCATION='R8G19',
 ROOM='BMC_DEBUG_HEADER',
 SEC='1',
 CDS_LIB='mstr_discrete',
 CDS_PART_NAME='RES_0402-0.0,5%,1/16W,CHIP,G21A',
 PRIM_FILE='./archive_libs/mstr_discrete/res/chips/chips.prt';

PART_NAME
 R8G20 'RES_0402-10.0K,1%,1/16W,CHIP,GA':
 ROOM='BMC_DEBUG_HEADER';

SECTION_NUMBER 1
 '@BASEBOARD_FAB2_LIB.BASEBOARD_FAB2(SCH_1):PAGE189_I50@MSTR_DISCRETE.RES(CHIPS)':
 C_PATH='@baseboard_fab2_lib.baseboard_fab2(sch_1):page189_i50@mstr_discrete.res~
(chips)',
 P_PATH='@baseboard_fab2_lib.baseboard_fab2(sch_1):page189_i50@mstr_discrete.res~
(chips)',
 PATH='I50',
 DRAWING='@BASEBOARD_FAB2_LIB.BASEBOARD_FAB2(SCH_1):PAGE189',
 WATTAGE='1/16W',
 TOLERANCE='1%',
 MATERIAL='CHIP',
 PHYS_PAGE='189',
 XY='(3200,3500)',
 ROT='0',
 VER='2',
 VALUE='10.0K',
 PACK_TYPE='0402',
 PART_NUMBER='G21796-016',
 LOCATION='R8G20',
 ROOM='BMC_DEBUG_HEADER',
 CDS_LIB='mstr_discrete',
 CDS_PART_NAME='RES_0402-10.0K,1%,1/16W,CHIP,GA',
 PRIM_FILE='./archive_libs/mstr_discrete/res/chips/chips.prt';

PART_NAME
 R8G21 'RES_0402-0.0,5%,1/16W,CHIP,G21A':
 ROOM='BMC_DEBUG_HEADER';

SECTION_NUMBER 1
 '@BASEBOARD_FAB2_LIB.BASEBOARD_FAB2(SCH_1):PAGE189_I65@MSTR_DISCRETE.RES(CHIPS)':
 C_PATH='@baseboard_fab2_lib.baseboard_fab2(sch_1):page189_i65@mstr_discrete.res~
(chips)',
 P_PATH='@baseboard_fab2_lib.baseboard_fab2(sch_1):page189_i65@mstr_discrete.res~
(chips)',
 PATH='I65',
 DRAWING='@BASEBOARD_FAB2_LIB.BASEBOARD_FAB2(SCH_1):PAGE189',
 WATTAGE='1/16W',
 TOLERANCE='5%',
 SEC_TYPE='0402',
 MATERIAL='CHIP',
 BOM_COST='DEBUG',
 PHYS_PAGE='189',
 XY='(2525,3025)',
 ROT='0',
 VER='1',
 VALUE='0.0',
 PACK_TYPE='0402',
 PART_NUMBER='G21497-005',
 LOCATION='R8G21',
 ROOM='BMC_DEBUG_HEADER',
 SEC='1',
 CDS_LIB='mstr_discrete',
 CDS_PART_NAME='RES_0402-0.0,5%,1/16W,CHIP,G21A',
 PRIM_FILE='./archive_libs/mstr_discrete/res/chips/chips.prt';

PART_NAME
 R8G22 'RES_0402-0.0,5%,1/16W,CHIP,G21A':
 ROOM='BMC_DEBUG_HEADER';

SECTION_NUMBER 1
 '@BASEBOARD_FAB2_LIB.BASEBOARD_FAB2(SCH_1):PAGE189_I66@MSTR_DISCRETE.RES(CHIPS)':
 C_PATH='@baseboard_fab2_lib.baseboard_fab2(sch_1):page189_i66@mstr_discrete.res~
(chips)',
 P_PATH='@baseboard_fab2_lib.baseboard_fab2(sch_1):page189_i66@mstr_discrete.res~
(chips)',
 PATH='I66',
 DRAWING='@BASEBOARD_FAB2_LIB.BASEBOARD_FAB2(SCH_1):PAGE189',
 WATTAGE='1/16W',
 TOLERANCE='5%',
 SEC_TYPE='0402',
 MATERIAL='CHIP',
 BOM_COST='DEBUG',
 PHYS_PAGE='189',
 XY='(2850,2925)',
 ROT='0',
 VER='1',
 VALUE='0.0',
 PACK_TYPE='0402',
 PART_NUMBER='G21497-005',
 LOCATION='R8G22',
 ROOM='BMC_DEBUG_HEADER',
 SEC='1',
 CDS_LIB='mstr_discrete',
 CDS_PART_NAME='RES_0402-0.0,5%,1/16W,CHIP,G21A',
 PRIM_FILE='./archive_libs/mstr_discrete/res/chips/chips.prt';

PART_NAME
 R8G23 'RES_0402-4.75K,1%,1/16W,CHIP,GA':
 ROOM='BMC_DEBUG_HEADER';

SECTION_NUMBER 1
 '@BASEBOARD_FAB2_LIB.BASEBOARD_FAB2(SCH_1):PAGE189_I56@MSTR_DISCRETE.RES(CHIPS)':
 C_PATH='@baseboard_fab2_lib.baseboard_fab2(sch_1):page189_i56@mstr_discrete.res~
(chips)',
 P_PATH='@baseboard_fab2_lib.baseboard_fab2(sch_1):page189_i56@mstr_discrete.res~
(chips)',
 PATH='I56',
 DRAWING='@BASEBOARD_FAB2_LIB.BASEBOARD_FAB2(SCH_1):PAGE189',
 WATTAGE='1/16W',
 TOLERANCE='1%',
 SEC_TYPE='0402',
 MATERIAL='CHIP',
 PHYS_PAGE='189',
 XY='(3200,2700)',
 ROT='0',
 VER='2',
 VALUE='4.75K',
 PACK_TYPE='0402',
 PART_NUMBER='G21796-072',
 LOCATION='R8G23',
 ROOM='BMC_DEBUG_HEADER',
 SEC='1',
 CDS_LIB='mstr_discrete',
 CDS_PART_NAME='RES_0402-4.75K,1%,1/16W,CHIP,GA',
 PRIM_FILE='./archive_libs/mstr_discrete/res/chips/chips.prt';

PART_NAME
 R8G24 'RES_0402-22.1,1.0%,1/16W,CHIP,A':
 ROOM='SYS_CLOCK';

SECTION_NUMBER 1
 '@BASEBOARD_FAB2_LIB.BASEBOARD_FAB2(SCH_1):PAGE101_I143@MSTR_DISCRETE.RES(CHIPS)':
 C_PATH='@baseboard_fab2_lib.baseboard_fab2(sch_1):page101_i143@mstr_discrete.re~
s(chips)',
 P_PATH='@baseboard_fab2_lib.baseboard_fab2(sch_1):page101_i143@mstr_discrete.re~
s(chips)',
 PATH='I143',
 DRAWING='@BASEBOARD_FAB2_LIB.BASEBOARD_FAB2(SCH_1):PAGE101',
 WATTAGE='1/16W',
 TOLERANCE='1.0%',
 SEC_TYPE='0402',
 MATERIAL='CHIP',
 BOM_COST='SM_CONTROLLER',
 PHYS_PAGE='101',
 XY='(-3050,2150)',
 ROT='0',
 VER='1',
 VALUE='22.1',
 PACK_TYPE='0402',
 PART_NUMBER='G21796-250',
 LOCATION='R8G24',
 ROOM='SYS_CLOCK',
 SEC='1',
 CDS_LIB='mstr_discrete',
 CDS_PART_NAME='RES_0402-22.1,1.0%,1/16W,CHIP,A',
 PRIM_FILE='./archive_libs/mstr_discrete/res/chips/chips.prt';

PART_NAME
 R8G25 'RES_0402-22.1,1.0%,1/16W,CHIP,A':
 GROUP='NI_I210&RJ45',
 ROOM='SYS_CLOCK';

SECTION_NUMBER 1
 '@BASEBOARD_FAB2_LIB.BASEBOARD_FAB2(SCH_1):PAGE101_I144@MSTR_DISCRETE.RES(CHIPS)':
 C_PATH='@baseboard_fab2_lib.baseboard_fab2(sch_1):page101_i144@mstr_discrete.re~
s(chips)',
 P_PATH='@baseboard_fab2_lib.baseboard_fab2(sch_1):page101_i144@mstr_discrete.re~
s(chips)',
 PATH='I144',
 DRAWING='@BASEBOARD_FAB2_LIB.BASEBOARD_FAB2(SCH_1):PAGE101',
 WATTAGE='1/16W',
 TOLERANCE='1.0%',
 SEC_TYPE='0402',
 MATERIAL='CHIP',
 BOM_COST='SM_CONTROLLER',
 PHYS_PAGE='101',
 XY='(-3050,2000)',
 ROT='0',
 VER='1',
 VALUE='22.1',
 PACK_TYPE='0402',
 PART_NUMBER='G21796-250',
 LOCATION='R8G25',
 ROOM='SYS_CLOCK',
 GROUP='NI_I210&RJ45',
 SEC='1',
 CDS_LIB='mstr_discrete',
 CDS_PART_NAME='RES_0402-22.1,1.0%,1/16W,CHIP,A',
 PRIM_FILE='./archive_libs/mstr_discrete/res/chips/chips.prt';

PART_NAME
 R8N1 'RES_0402-1.8K,1%,1/16W,CHIP,G2A':
 ROOM='CPU1';

SECTION_NUMBER 1
 '@BASEBOARD_FAB2_LIB.BASEBOARD_FAB2(SCH_1):PAGE55_I157@MSTR_DISCRETE.RES(CHIPS)':
 C_PATH='@baseboard_fab2_lib.baseboard_fab2(sch_1):page55_i157@mstr_discrete.res~
(chips)',
 P_PATH='@baseboard_fab2_lib.baseboard_fab2(sch_1):page55_i157@mstr_discrete.res~
(chips)',
 PATH='I157',
 DRAWING='@BASEBOARD_FAB2_LIB.BASEBOARD_FAB2(SCH_1):PAGE55',
 WATTAGE='1/16W',
 TOLERANCE='1%',
 SEC_TYPE='0402',
 MATERIAL='CHIP',
 BOM_COST='PROC_SOCKET',
 PHYS_PAGE='55',
 XY='(12600,2300)',
 ROT='0',
 VER='2',
 VALUE='1.8K',
 PACK_TYPE='0402',
 PART_NUMBER='G21796-336',
 LOCATION='R8N1',
 ROOM='CPU1',
 SEC='1',
 CDS_LIB='mstr_discrete',
 CDS_PART_NAME='RES_0402-1.8K,1%,1/16W,CHIP,G2A',
 PRIM_FILE='./archive_libs/mstr_discrete/res/chips/chips.prt';

PART_NAME
 R8N2 'RES_0402-10.0K,1%,1/16W,CHIP,GA':
 ROOM='CPU1';

SECTION_NUMBER 1
 '@BASEBOARD_FAB2_LIB.BASEBOARD_FAB2(SCH_1):PAGE55_I161@MSTR_DISCRETE.RES(CHIPS)':
 C_PATH='@baseboard_fab2_lib.baseboard_fab2(sch_1):page55_i161@mstr_discrete.res~
(chips)',
 P_PATH='@baseboard_fab2_lib.baseboard_fab2(sch_1):page55_i161@mstr_discrete.res~
(chips)',
 PATH='I161',
 DRAWING='@BASEBOARD_FAB2_LIB.BASEBOARD_FAB2(SCH_1):PAGE55',
 WATTAGE='1/16W',
 TOLERANCE='1%',
 SEC_TYPE='0402',
 MATERIAL='CHIP',
 BOM_COST='PROC_SOCKET',
 PHYS_PAGE='55',
 XY='(13600,2300)',
 ROT='0',
 VER='2',
 VALUE='10.0K',
 PACK_TYPE='0402',
 PART_NUMBER='G21796-016',
 LOCATION='R8N2',
 ROOM='CPU1',
 SEC='1',
 CDS_LIB='mstr_discrete',
 CDS_PART_NAME='RES_0402-10.0K,1%,1/16W,CHIP,GA',
 PRIM_FILE='./archive_libs/mstr_discrete/res/chips/chips.prt';

PART_NAME
 R8N3 'RES_0402-10.0K,1%,1/16W,CHIP,GA':
 ROOM='CPU1';

SECTION_NUMBER 1
 '@BASEBOARD_FAB2_LIB.BASEBOARD_FAB2(SCH_1):PAGE55_I159@MSTR_DISCRETE.RES(CHIPS)':
 C_PATH='@baseboard_fab2_lib.baseboard_fab2(sch_1):page55_i159@mstr_discrete.res~
(chips)',
 P_PATH='@baseboard_fab2_lib.baseboard_fab2(sch_1):page55_i159@mstr_discrete.res~
(chips)',
 PATH='I159',
 DRAWING='@BASEBOARD_FAB2_LIB.BASEBOARD_FAB2(SCH_1):PAGE55',
 WATTAGE='1/16W',
 TOLERANCE='1%',
 SEC_TYPE='0402',
 MATERIAL='CHIP',
 BOM_COST='PROC_SOCKET',
 PHYS_PAGE='55',
 XY='(13100,2300)',
 ROT='0',
 VER='2',
 VALUE='10.0K',
 PACK_TYPE='0402',
 PART_NUMBER='G21796-016',
 LOCATION='R8N3',
 ROOM='CPU1',
 SEC='1',
 CDS_LIB='mstr_discrete',
 CDS_PART_NAME='RES_0402-10.0K,1%,1/16W,CHIP,GA',
 PRIM_FILE='./archive_libs/mstr_discrete/res/chips/chips.prt';

PART_NAME
 R8N4 'RES_0402-1.8K,1%,1/16W,CHIP,G2A':
 ROOM='CPU1';

SECTION_NUMBER 1
 '@BASEBOARD_FAB2_LIB.BASEBOARD_FAB2(SCH_1):PAGE55_I158@MSTR_DISCRETE.RES(CHIPS)':
 C_PATH='@baseboard_fab2_lib.baseboard_fab2(sch_1):page55_i158@mstr_discrete.res~
(chips)',
 P_PATH='@baseboard_fab2_lib.baseboard_fab2(sch_1):page55_i158@mstr_discrete.res~
(chips)',
 PATH='I158',
 DRAWING='@BASEBOARD_FAB2_LIB.BASEBOARD_FAB2(SCH_1):PAGE55',
 WATTAGE='1/16W',
 TOLERANCE='1%',
 SEC_TYPE='0402',
 MATERIAL='CHIP',
 BOM_COST='PROC_SOCKET',
 PHYS_PAGE='55',
 XY='(12850,2300)',
 ROT='0',
 VER='2',
 VALUE='1.8K',
 PACK_TYPE='0402',
 PART_NUMBER='G21796-336',
 LOCATION='R8N4',
 ROOM='CPU1',
 SEC='1',
 CDS_LIB='mstr_discrete',
 CDS_PART_NAME='RES_0402-1.8K,1%,1/16W,CHIP,G2A',
 PRIM_FILE='./archive_libs/mstr_discrete/res/chips/chips.prt';

PART_NAME
 R8N5 'RES_0402-10.0K,1%,1/16W,CHIP,GA':
 ROOM='CPU1';

SECTION_NUMBER 1
 '@BASEBOARD_FAB2_LIB.BASEBOARD_FAB2(SCH_1):PAGE55_I160@MSTR_DISCRETE.RES(CHIPS)':
 C_PATH='@baseboard_fab2_lib.baseboard_fab2(sch_1):page55_i160@mstr_discrete.res~
(chips)',
 P_PATH='@baseboard_fab2_lib.baseboard_fab2(sch_1):page55_i160@mstr_discrete.res~
(chips)',
 PATH='I160',
 DRAWING='@BASEBOARD_FAB2_LIB.BASEBOARD_FAB2(SCH_1):PAGE55',
 WATTAGE='1/16W',
 TOLERANCE='1%',
 SEC_TYPE='0402',
 MATERIAL='CHIP',
 BOM_COST='PROC_SOCKET',
 PHYS_PAGE='55',
 XY='(13350,2300)',
 ROT='0',
 VER='2',
 VALUE='10.0K',
 PACK_TYPE='0402',
 PART_NUMBER='G21796-016',
 LOCATION='R8N5',
 ROOM='CPU1',
 SEC='1',
 CDS_LIB='mstr_discrete',
 CDS_PART_NAME='RES_0402-10.0K,1%,1/16W,CHIP,GA',
 PRIM_FILE='./archive_libs/mstr_discrete/res/chips/chips.prt';

PART_NAME
 R8P1 'RES_0402-49.9,1%,1/16W,CHIP,G2A':
 ROOM='CPU1';

SECTION_NUMBER 1
 '@BASEBOARD_FAB2_LIB.BASEBOARD_FAB2(SCH_1):PAGE90_I85@MSTR_DISCRETE.RES(CHIPS)':
 C_PATH='@baseboard_fab2_lib.baseboard_fab2(sch_1):page90_i85@mstr_discrete.res(~
chips)',
 P_PATH='@baseboard_fab2_lib.baseboard_fab2(sch_1):page90_i85@mstr_discrete.res(~
chips)',
 PATH='I85',
 DRAWING='@BASEBOARD_FAB2_LIB.BASEBOARD_FAB2(SCH_1):PAGE90',
 WATTAGE='1/16W',
 TOLERANCE='1%',
 SEC_TYPE='0402',
 MATERIAL='CHIP',
 PHYS_PAGE='90',
 XY='(325,2475)',
 ROT='0',
 VER='1',
 VALUE='49.9',
 PACK_TYPE='0402',
 PART_NUMBER='G21796-047',
 LOCATION='R8P1',
 ROOM='CPU1',
 SEC='1',
 CDS_LIB='mstr_discrete',
 CDS_PART_NAME='RES_0402-49.9,1%,1/16W,CHIP,G2A',
 PRIM_FILE='./archive_libs/mstr_discrete/res/chips/chips.prt';

PART_NAME
 R8P2 'RES_0402-49.9,1%,1/16W,CHIP,G2A':
 ROOM='CPU1';

SECTION_NUMBER 1
 '@BASEBOARD_FAB2_LIB.BASEBOARD_FAB2(SCH_1):PAGE90_I86@MSTR_DISCRETE.RES(CHIPS)':
 C_PATH='@baseboard_fab2_lib.baseboard_fab2(sch_1):page90_i86@mstr_discrete.res(~
chips)',
 P_PATH='@baseboard_fab2_lib.baseboard_fab2(sch_1):page90_i86@mstr_discrete.res(~
chips)',
 PATH='I86',
 DRAWING='@BASEBOARD_FAB2_LIB.BASEBOARD_FAB2(SCH_1):PAGE90',
 WATTAGE='1/16W',
 TOLERANCE='1%',
 SEC_TYPE='0402',
 MATERIAL='CHIP',
 PHYS_PAGE='90',
 XY='(325,2350)',
 ROT='0',
 VER='1',
 VALUE='49.9',
 PACK_TYPE='0402',
 PART_NUMBER='G21796-047',
 LOCATION='R8P2',
 ROOM='CPU1',
 SEC='1',
 CDS_LIB='mstr_discrete',
 CDS_PART_NAME='RES_0402-49.9,1%,1/16W,CHIP,G2A',
 PRIM_FILE='./archive_libs/mstr_discrete/res/chips/chips.prt';

PART_NAME
 R8P3 'RES_0402-49.9,1%,1/16W,CHIP,G2A':
 ROOM='CPU1';

SECTION_NUMBER 1
 '@BASEBOARD_FAB2_LIB.BASEBOARD_FAB2(SCH_1):PAGE56_I173@MSTR_DISCRETE.RES(CHIPS)':
 C_PATH='@baseboard_fab2_lib.baseboard_fab2(sch_1):page56_i173@mstr_discrete.res~
(chips)',
 P_PATH='@baseboard_fab2_lib.baseboard_fab2(sch_1):page56_i173@mstr_discrete.res~
(chips)',
 PATH='I173',
 DRAWING='@BASEBOARD_FAB2_LIB.BASEBOARD_FAB2(SCH_1):PAGE56',
 WATTAGE='1/16W',
 TOLERANCE='1%',
 SEC_TYPE='0402',
 MATERIAL='CHIP',
 PHYS_PAGE='56',
 XY='(-650,2750)',
 ROT='0',
 VER='2',
 VALUE='49.9',
 PACK_TYPE='0402',
 PART_NUMBER='G21796-047',
 LOCATION='R8P3',
 ROOM='CPU1',
 SEC='1',
 CDS_LIB='mstr_discrete',
 CDS_PART_NAME='RES_0402-49.9,1%,1/16W,CHIP,G2A',
 PRIM_FILE='./archive_libs/mstr_discrete/res/chips/chips.prt';

PART_NAME
 R8R1 'RES_0402-49.9,1%,1/16W,CHIP,G2A':
 ROOM='CPU1';

SECTION_NUMBER 1
 '@BASEBOARD_FAB2_LIB.BASEBOARD_FAB2(SCH_1):PAGE56_I174@MSTR_DISCRETE.RES(CHIPS)':
 C_PATH='@baseboard_fab2_lib.baseboard_fab2(sch_1):page56_i174@mstr_discrete.res~
(chips)',
 P_PATH='@baseboard_fab2_lib.baseboard_fab2(sch_1):page56_i174@mstr_discrete.res~
(chips)',
 PATH='I174',
 DRAWING='@BASEBOARD_FAB2_LIB.BASEBOARD_FAB2(SCH_1):PAGE56',
 WATTAGE='1/16W',
 TOLERANCE='1%',
 SEC_TYPE='0402',
 MATERIAL='CHIP',
 PHYS_PAGE='56',
 XY='(-375,2750)',
 ROT='0',
 VER='2',
 VALUE='49.9',
 PACK_TYPE='0402',
 PART_NUMBER='G21796-047',
 LOCATION='R8R1',
 ROOM='CPU1',
 SEC='1',
 CDS_LIB='mstr_discrete',
 CDS_PART_NAME='RES_0402-49.9,1%,1/16W,CHIP,G2A',
 PRIM_FILE='./archive_libs/mstr_discrete/res/chips/chips.prt';

PART_NAME
 R8W1 'RES_0402-0.0,5%,1/16W,CHIP,G21A':
 ROOM='PVCCIN_CPU0_VR';

SECTION_NUMBER 1
 '@BASEBOARD_FAB2_LIB.BASEBOARD_FAB2(SCH_1):PAGE249_I34@MSTR_DISCRETE.RES(CHIPS)':
 C_PATH='@baseboard_fab2_lib.baseboard_fab2(sch_1):page249_i34@mstr_discrete.res~
(chips)',
 P_PATH='@baseboard_fab2_lib.baseboard_fab2(sch_1):page249_i34@mstr_discrete.res~
(chips)',
 PATH='I34',
 DRAWING='@BASEBOARD_FAB2_LIB.BASEBOARD_FAB2(SCH_1):PAGE249',
 POP='NOPOP',
 WATTAGE='1/16W',
 TOLERANCE='5%',
 SEC_TYPE='0402',
 MATERIAL='CHIP',
 PHYS_PAGE='249',
 XY='(-6150,3350)',
 ROT='0',
 VER='1',
 VALUE='0.0',
 PACK_TYPE='0402',
 PART_NUMBER='G21497-005',
 LOCATION='R8W1',
 ROOM='PVCCIN_CPU0_VR',
 SEC='1',
 CDS_LIB='mstr_discrete',
 CDS_PART_NAME='RES_0402-0.0,5%,1/16W,CHIP,G21A',
 PRIM_FILE='./archive_libs/mstr_discrete/res/chips/chips.prt';

PART_NAME
 R8W2 'RES_0402-1.00K,1%,1/16W,CHIP,GA':
 ROOM='PVNN_PCH_STBY';

SECTION_NUMBER 1
 '@BASEBOARD_FAB2_LIB.BASEBOARD_FAB2(SCH_1):PAGE235_I247@MSTR_DISCRETE.RES(CHIPS)':
 C_PATH='@baseboard_fab2_lib.baseboard_fab2(sch_1):page235_i247@mstr_discrete.re~
s(chips)',
 P_PATH='@baseboard_fab2_lib.baseboard_fab2(sch_1):page235_i247@mstr_discrete.re~
s(chips)',
 PATH='I247',
 DRAWING='@BASEBOARD_FAB2_LIB.BASEBOARD_FAB2(SCH_1):PAGE235',
 WATTAGE='1/16W',
 TOLERANCE='1%',
 SEC_TYPE='0402',
 MATERIAL='CHIP',
 PHYS_PAGE='235',
 XY='(-11100,4600)',
 ROT='0',
 VER='2',
 VALUE='1.00K',
 PACK_TYPE='0402',
 PART_NUMBER='G21796-026',
 LOCATION='R8W2',
 ROOM='PVNN_PCH_STBY',
 SEC='1',
 CDS_LIB='mstr_discrete',
 CDS_PART_NAME='RES_0402-1.00K,1%,1/16W,CHIP,GA',
 PRIM_FILE='./archive_libs/mstr_discrete/res/chips/chips.prt';

PART_NAME
 R8W3 'RES_0402-1.00K,1%,1/16W,CHIP,GA':
 ROOM='PVNN_PCH_STBY';

SECTION_NUMBER 1
 '@BASEBOARD_FAB2_LIB.BASEBOARD_FAB2(SCH_1):PAGE235_I248@MSTR_DISCRETE.RES(CHIPS)':
 C_PATH='@baseboard_fab2_lib.baseboard_fab2(sch_1):page235_i248@mstr_discrete.re~
s(chips)',
 P_PATH='@baseboard_fab2_lib.baseboard_fab2(sch_1):page235_i248@mstr_discrete.re~
s(chips)',
 PATH='I248',
 DRAWING='@BASEBOARD_FAB2_LIB.BASEBOARD_FAB2(SCH_1):PAGE235',
 WATTAGE='1/16W',
 TOLERANCE='1%',
 SEC_TYPE='0402',
 MATERIAL='CHIP',
 PHYS_PAGE='235',
 XY='(-11800,3750)',
 ROT='0',
 VER='2',
 VALUE='1.00K',
 PACK_TYPE='0402',
 PART_NUMBER='G21796-026',
 LOCATION='R8W3',
 ROOM='PVNN_PCH_STBY',
 SEC='1',
 CDS_LIB='mstr_discrete',
 CDS_PART_NAME='RES_0402-1.00K,1%,1/16W,CHIP,GA',
 PRIM_FILE='./archive_libs/mstr_discrete/res/chips/chips.prt';

PART_NAME
 R8W4 'RES_0402-20.0,1%,1/16W,CHIP,G2A':
 ROOM='SMBUS';

SECTION_NUMBER 1
 '@BASEBOARD_FAB2_LIB.BASEBOARD_FAB2(SCH_1):PAGE138_I195@MSTR_DISCRETE.RES(CHIPS)':
 C_PATH='@baseboard_fab2_lib.baseboard_fab2(sch_1):page138_i195@mstr_discrete.re~
s(chips)',
 P_PATH='@baseboard_fab2_lib.baseboard_fab2(sch_1):page138_i195@mstr_discrete.re~
s(chips)',
 PATH='I195',
 DRAWING='@BASEBOARD_FAB2_LIB.BASEBOARD_FAB2(SCH_1):PAGE138',
 WATTAGE='1/16W',
 TOLERANCE='1%',
 SEC_TYPE='0402',
 MATERIAL='CHIP',
 BOM_COST='SM_CONTROLLER',
 PHYS_PAGE='138',
 XY='(-4000,2950)',
 ROT='0',
 VER='1',
 VALUE='20.0',
 PACK_TYPE='0402',
 PART_NUMBER='G21796-173',
 LOCATION='R8W4',
 ROOM='SMBUS',
 SEC='1',
 CDS_LIB='mstr_discrete',
 CDS_PART_NAME='RES_0402-20.0,1%,1/16W,CHIP,G2A',
 PRIM_FILE='./archive_libs/mstr_discrete/res/chips/chips.prt';

PART_NAME
 R8W5 'RES_0402-20.0,1%,1/16W,CHIP,G2A':
 ROOM='SMBUS';

SECTION_NUMBER 1
 '@BASEBOARD_FAB2_LIB.BASEBOARD_FAB2(SCH_1):PAGE138_I194@MSTR_DISCRETE.RES(CHIPS)':
 C_PATH='@baseboard_fab2_lib.baseboard_fab2(sch_1):page138_i194@mstr_discrete.re~
s(chips)',
 P_PATH='@baseboard_fab2_lib.baseboard_fab2(sch_1):page138_i194@mstr_discrete.re~
s(chips)',
 PATH='I194',
 DRAWING='@BASEBOARD_FAB2_LIB.BASEBOARD_FAB2(SCH_1):PAGE138',
 WATTAGE='1/16W',
 TOLERANCE='1%',
 SEC_TYPE='0402',
 MATERIAL='CHIP',
 BOM_COST='SM_CONTROLLER',
 PHYS_PAGE='138',
 XY='(-4000,2800)',
 ROT='0',
 VER='1',
 VALUE='20.0',
 PACK_TYPE='0402',
 PART_NUMBER='G21796-173',
 LOCATION='R8W5',
 ROOM='SMBUS',
 SEC='1',
 CDS_LIB='mstr_discrete',
 CDS_PART_NAME='RES_0402-20.0,1%,1/16W,CHIP,G2A',
 PRIM_FILE='./archive_libs/mstr_discrete/res/chips/chips.prt';

PART_NAME
 R8W6 'RES_0402-1.37K,1%,1/16W,CHIP,GA':
 ROOM='SMBUS';

SECTION_NUMBER 1
 '@BASEBOARD_FAB2_LIB.BASEBOARD_FAB2(SCH_1):PAGE138_I205@MSTR_DISCRETE.RES(CHIPS)':
 C_PATH='@baseboard_fab2_lib.baseboard_fab2(sch_1):page138_i205@mstr_discrete.re~
s(chips)',
 P_PATH='@baseboard_fab2_lib.baseboard_fab2(sch_1):page138_i205@mstr_discrete.re~
s(chips)',
 PATH='I205',
 DRAWING='@BASEBOARD_FAB2_LIB.BASEBOARD_FAB2(SCH_1):PAGE138',
 WATTAGE='1/16W',
 TOLERANCE='1%',
 SEC_TYPE='0402',
 MATERIAL='CHIP',
 BOM_COST='SM_CONTROLLER',
 PHYS_PAGE='138',
 XY='(-575,2600)',
 ROT='0',
 VER='2',
 VALUE='1.37K',
 PACK_TYPE='0402',
 PART_NUMBER='G21796-095',
 LOCATION='R8W6',
 ROOM='SMBUS',
 SEC='1',
 CDS_LIB='mstr_discrete',
 CDS_PART_NAME='RES_0402-1.37K,1%,1/16W,CHIP,GA',
 PRIM_FILE='./archive_libs/mstr_discrete/res/chips/chips.prt';

PART_NAME
 R8W7 'RES_0402-1.37K,1%,1/16W,CHIP,GA':
 ROOM='SMBUS';

SECTION_NUMBER 1
 '@BASEBOARD_FAB2_LIB.BASEBOARD_FAB2(SCH_1):PAGE138_I202@MSTR_DISCRETE.RES(CHIPS)':
 C_PATH='@baseboard_fab2_lib.baseboard_fab2(sch_1):page138_i202@mstr_discrete.re~
s(chips)',
 P_PATH='@baseboard_fab2_lib.baseboard_fab2(sch_1):page138_i202@mstr_discrete.re~
s(chips)',
 PATH='I202',
 DRAWING='@BASEBOARD_FAB2_LIB.BASEBOARD_FAB2(SCH_1):PAGE138',
 WATTAGE='1/16W',
 TOLERANCE='1%',
 SEC_TYPE='0402',
 MATERIAL='CHIP',
 BOM_COST='SM_CONTROLLER',
 PHYS_PAGE='138',
 XY='(-200,2550)',
 ROT='0',
 VER='2',
 VALUE='1.37K',
 PACK_TYPE='0402',
 PART_NUMBER='G21796-095',
 LOCATION='R8W7',
 ROOM='SMBUS',
 SEC='1',
 CDS_LIB='mstr_discrete',
 CDS_PART_NAME='RES_0402-1.37K,1%,1/16W,CHIP,GA',
 PRIM_FILE='./archive_libs/mstr_discrete/res/chips/chips.prt';

PART_NAME
 R8W8 'RES_0402-1.00K,1%,1/16W,CHIP,GA':
 ROOM='PVNN_PCH_STBY';

SECTION_NUMBER 1
 '@BASEBOARD_FAB2_LIB.BASEBOARD_FAB2(SCH_1):PAGE235_I249@MSTR_DISCRETE.RES(CHIPS)':
 C_PATH='@baseboard_fab2_lib.baseboard_fab2(sch_1):page235_i249@mstr_discrete.re~
s(chips)',
 P_PATH='@baseboard_fab2_lib.baseboard_fab2(sch_1):page235_i249@mstr_discrete.re~
s(chips)',
 PATH='I249',
 DRAWING='@BASEBOARD_FAB2_LIB.BASEBOARD_FAB2(SCH_1):PAGE235',
 WATTAGE='1/16W',
 TOLERANCE='1%',
 SEC_TYPE='0402',
 MATERIAL='CHIP',
 PHYS_PAGE='235',
 XY='(-8750,4950)',
 ROT='0',
 VER='2',
 VALUE='1.00K',
 PACK_TYPE='0402',
 PART_NUMBER='G21796-026',
 LOCATION='R8W8',
 ROOM='PVNN_PCH_STBY',
 SEC='1',
 CDS_LIB='mstr_discrete',
 CDS_PART_NAME='RES_0402-1.00K,1%,1/16W,CHIP,GA',
 PRIM_FILE='./archive_libs/mstr_discrete/res/chips/chips.prt';

PART_NAME
 R8W9 'RES_0402-4.75K,1%,1/16W,CHIP,GA':
 ROOM='NVDIMM';

SECTION_NUMBER 1
 '@BASEBOARD_FAB2_LIB.BASEBOARD_FAB2(SCH_1):PAGE89_I49@MSTR_DISCRETE.RES(CHIPS)':
 C_PATH='@baseboard_fab2_lib.baseboard_fab2(sch_1):page89_i49@mstr_discrete.res(~
chips)',
 P_PATH='@baseboard_fab2_lib.baseboard_fab2(sch_1):page89_i49@mstr_discrete.res(~
chips)',
 PATH='I49',
 DRAWING='@BASEBOARD_FAB2_LIB.BASEBOARD_FAB2(SCH_1):PAGE89',
 WATTAGE='1/16W',
 TOLERANCE='1%',
 SEC_TYPE='0402',
 MATERIAL='CHIP',
 PHYS_PAGE='89',
 XY='(2200,3250)',
 ROT='0',
 VER='2',
 VALUE='4.75K',
 PACK_TYPE='0402',
 PART_NUMBER='G21796-072',
 LOCATION='R8W9',
 ROOM='NVDIMM',
 SEC='1',
 CDS_LIB='mstr_discrete',
 CDS_PART_NAME='RES_0402-4.75K,1%,1/16W,CHIP,GA',
 PRIM_FILE='./archive_libs/mstr_discrete/res/chips/chips.prt';

PART_NAME
 R8W10 'RES_0402-0.0,5%,1/16W,CHIP,G21A':
 ROOM='BMC_DEBUG_HEADER';

SECTION_NUMBER 1
 '@BASEBOARD_FAB2_LIB.BASEBOARD_FAB2(SCH_1):PAGE245_I56@MSTR_DISCRETE.RES(CHIPS)':
 C_PATH='@baseboard_fab2_lib.baseboard_fab2(sch_1):page245_i56@mstr_discrete.res~
(chips)',
 P_PATH='@baseboard_fab2_lib.baseboard_fab2(sch_1):page245_i56@mstr_discrete.res~
(chips)',
 PATH='I56',
 DRAWING='@BASEBOARD_FAB2_LIB.BASEBOARD_FAB2(SCH_1):PAGE245',
 WATTAGE='1/16W',
 TOLERANCE='5%',
 SEC_TYPE='0402',
 MATERIAL='CHIP',
 BOM_COST='DEBUG',
 PHYS_PAGE='245',
 XY='(-2700,3175)',
 ROT='0',
 VER='1',
 VALUE='0.0',
 PACK_TYPE='0402',
 PART_NUMBER='G21497-005',
 LOCATION='R8W10',
 ROOM='BMC_DEBUG_HEADER',
 SEC='1',
 CDS_LIB='mstr_discrete',
 CDS_PART_NAME='RES_0402-0.0,5%,1/16W,CHIP,G21A',
 PRIM_FILE='./archive_libs/mstr_discrete/res/chips/chips.prt';

PART_NAME
 R8W11 'RES_0402-0.0,5%,1/16W,CHIP,G21A':
 ROOM='BMC_DEBUG_HEADER';

SECTION_NUMBER 1
 '@BASEBOARD_FAB2_LIB.BASEBOARD_FAB2(SCH_1):PAGE245_I57@MSTR_DISCRETE.RES(CHIPS)':
 C_PATH='@baseboard_fab2_lib.baseboard_fab2(sch_1):page245_i57@mstr_discrete.res~
(chips)',
 P_PATH='@baseboard_fab2_lib.baseboard_fab2(sch_1):page245_i57@mstr_discrete.res~
(chips)',
 PATH='I57',
 DRAWING='@BASEBOARD_FAB2_LIB.BASEBOARD_FAB2(SCH_1):PAGE245',
 WATTAGE='1/16W',
 TOLERANCE='5%',
 SEC_TYPE='0402',
 MATERIAL='CHIP',
 BOM_COST='DEBUG',
 PHYS_PAGE='245',
 XY='(-2700,3125)',
 ROT='0',
 VER='1',
 VALUE='0.0',
 PACK_TYPE='0402',
 PART_NUMBER='G21497-005',
 LOCATION='R8W11',
 ROOM='BMC_DEBUG_HEADER',
 SEC='1',
 CDS_LIB='mstr_discrete',
 CDS_PART_NAME='RES_0402-0.0,5%,1/16W,CHIP,G21A',
 PRIM_FILE='./archive_libs/mstr_discrete/res/chips/chips.prt';

PART_NAME
 R8W12 'RES_0402-0.0,5%,1/16W,CHIP,G21A':
 ROOM='BMC_DEBUG_HEADER';

SECTION_NUMBER 1
 '@BASEBOARD_FAB2_LIB.BASEBOARD_FAB2(SCH_1):PAGE245_I58@MSTR_DISCRETE.RES(CHIPS)':
 C_PATH='@baseboard_fab2_lib.baseboard_fab2(sch_1):page245_i58@mstr_discrete.res~
(chips)',
 P_PATH='@baseboard_fab2_lib.baseboard_fab2(sch_1):page245_i58@mstr_discrete.res~
(chips)',
 PATH='I58',
 DRAWING='@BASEBOARD_FAB2_LIB.BASEBOARD_FAB2(SCH_1):PAGE245',
 WATTAGE='1/16W',
 TOLERANCE='5%',
 SEC_TYPE='0402',
 MATERIAL='CHIP',
 BOM_COST='DEBUG',
 PHYS_PAGE='245',
 XY='(-2700,3025)',
 ROT='0',
 VER='1',
 VALUE='0.0',
 PACK_TYPE='0402',
 PART_NUMBER='G21497-005',
 LOCATION='R8W12',
 ROOM='BMC_DEBUG_HEADER',
 SEC='1',
 CDS_LIB='mstr_discrete',
 CDS_PART_NAME='RES_0402-0.0,5%,1/16W,CHIP,G21A',
 PRIM_FILE='./archive_libs/mstr_discrete/res/chips/chips.prt';

PART_NAME
 R8W13 'RES_0402-0.0,5%,1/16W,CHIP,G21A':
 ROOM='BMC_DEBUG_HEADER';

SECTION_NUMBER 1
 '@BASEBOARD_FAB2_LIB.BASEBOARD_FAB2(SCH_1):PAGE245_I59@MSTR_DISCRETE.RES(CHIPS)':
 C_PATH='@baseboard_fab2_lib.baseboard_fab2(sch_1):page245_i59@mstr_discrete.res~
(chips)',
 P_PATH='@baseboard_fab2_lib.baseboard_fab2(sch_1):page245_i59@mstr_discrete.res~
(chips)',
 PATH='I59',
 DRAWING='@BASEBOARD_FAB2_LIB.BASEBOARD_FAB2(SCH_1):PAGE245',
 WATTAGE='1/16W',
 TOLERANCE='5%',
 SEC_TYPE='0402',
 MATERIAL='CHIP',
 BOM_COST='DEBUG',
 PHYS_PAGE='245',
 XY='(-6500,3225)',
 ROT='0',
 VER='1',
 VALUE='0.0',
 PACK_TYPE='0402',
 PART_NUMBER='G21497-005',
 LOCATION='R8W13',
 ROOM='BMC_DEBUG_HEADER',
 SEC='1',
 CDS_LIB='mstr_discrete',
 CDS_PART_NAME='RES_0402-0.0,5%,1/16W,CHIP,G21A',
 PRIM_FILE='./archive_libs/mstr_discrete/res/chips/chips.prt';

PART_NAME
 R8W14 'RES_0402-0.0,5%,1/16W,CHIP,G21A':
 ROOM='BMC_DEBUG_HEADER';

SECTION_NUMBER 1
 '@BASEBOARD_FAB2_LIB.BASEBOARD_FAB2(SCH_1):PAGE245_I60@MSTR_DISCRETE.RES(CHIPS)':
 C_PATH='@baseboard_fab2_lib.baseboard_fab2(sch_1):page245_i60@mstr_discrete.res~
(chips)',
 P_PATH='@baseboard_fab2_lib.baseboard_fab2(sch_1):page245_i60@mstr_discrete.res~
(chips)',
 PATH='I60',
 DRAWING='@BASEBOARD_FAB2_LIB.BASEBOARD_FAB2(SCH_1):PAGE245',
 WATTAGE='1/16W',
 TOLERANCE='5%',
 SEC_TYPE='0402',
 MATERIAL='CHIP',
 BOM_COST='DEBUG',
 PHYS_PAGE='245',
 XY='(-6500,3175)',
 ROT='0',
 VER='1',
 VALUE='0.0',
 PACK_TYPE='0402',
 PART_NUMBER='G21497-005',
 LOCATION='R8W14',
 ROOM='BMC_DEBUG_HEADER',
 SEC='1',
 CDS_LIB='mstr_discrete',
 CDS_PART_NAME='RES_0402-0.0,5%,1/16W,CHIP,G21A',
 PRIM_FILE='./archive_libs/mstr_discrete/res/chips/chips.prt';

PART_NAME
 R8W15 'RES_0402-4.75K,1%,1/16W,CHIP,GA':
 ROOM='BMC_MISC';

SECTION_NUMBER 1
 '@BASEBOARD_FAB2_LIB.BASEBOARD_FAB2(SCH_1):PAGE245_I78@MSTR_DISCRETE.RES(CHIPS)':
 C_PATH='@baseboard_fab2_lib.baseboard_fab2(sch_1):page245_i78@mstr_discrete.res~
(chips)',
 P_PATH='@baseboard_fab2_lib.baseboard_fab2(sch_1):page245_i78@mstr_discrete.res~
(chips)',
 PATH='I78',
 DRAWING='@BASEBOARD_FAB2_LIB.BASEBOARD_FAB2(SCH_1):PAGE245',
 WATTAGE='1/16W',
 TOLERANCE='1%',
 SEC_TYPE='0402',
 MATERIAL='CHIP',
 BOM_COST='SM_CONTROLLER',
 PHYS_PAGE='245',
 XY='(-5500,2150)',
 ROT='0',
 VER='2',
 VALUE='4.75K',
 PACK_TYPE='0402',
 PART_NUMBER='G21796-072',
 LOCATION='R8W15',
 ROOM='BMC_MISC',
 SEC='1',
 CDS_LIB='mstr_discrete',
 CDS_PART_NAME='RES_0402-4.75K,1%,1/16W,CHIP,GA',
 PRIM_FILE='./archive_libs/mstr_discrete/res/chips/chips.prt';

PART_NAME
 R9A1 'RES_0402-1.00K,1%,1/16W,EMPTY,A':
 ROOM='DEBUG';

SECTION_NUMBER 1
 '@BASEBOARD_FAB2_LIB.BASEBOARD_FAB2(SCH_1):PAGE111_I95@MSTR_DISCRETE.RES(CHIPS)':
 C_PATH='@baseboard_fab2_lib.baseboard_fab2(sch_1):page111_i95@mstr_discrete.res~
(chips)',
 P_PATH='@baseboard_fab2_lib.baseboard_fab2(sch_1):page111_i95@mstr_discrete.res~
(chips)',
 PATH='I95',
 DRAWING='@BASEBOARD_FAB2_LIB.BASEBOARD_FAB2(SCH_1):PAGE111',
 WATTAGE='1/16W',
 TOLERANCE='1%',
 SEC_TYPE='0402',
 MATERIAL='EMPTY',
 PHYS_PAGE='111',
 XY='(-1850,2700)',
 ROT='2',
 VER='2',
 VALUE='1.00K',
 PACK_TYPE='0402',
 PART_NUMBER='G21796-026',
 LOCATION='R9A1',
 ROOM='DEBUG',
 SEC='1',
 CDS_LIB='mstr_discrete',
 CDS_PART_NAME='RES_0402-1.00K,1%,1/16W,EMPTY,A',
 PRIM_FILE='./archive_libs/mstr_discrete/res/chips/chips.prt';

PART_NAME
 R9A2 'RES_0402-33.2,1%,1/16W,EMPTY,GA':
 ROOM='DEBUG';

SECTION_NUMBER 1
 '@BASEBOARD_FAB2_LIB.BASEBOARD_FAB2(SCH_1):PAGE111_I83@MSTR_DISCRETE.RES(CHIPS)':
 C_PATH='@baseboard_fab2_lib.baseboard_fab2(sch_1):page111_i83@mstr_discrete.res~
(chips)',
 P_PATH='@baseboard_fab2_lib.baseboard_fab2(sch_1):page111_i83@mstr_discrete.res~
(chips)',
 PATH='I83',
 DRAWING='@BASEBOARD_FAB2_LIB.BASEBOARD_FAB2(SCH_1):PAGE111',
 WATTAGE='1/16W',
 TOLERANCE='1%',
 SEC_TYPE='0402',
 MATERIAL='EMPTY',
 PHYS_PAGE='111',
 XY='(-2925,2675)',
 ROT='0',
 VER='2',
 VALUE='33.2',
 PACK_TYPE='0402',
 PART_NUMBER='G21796-074',
 LOCATION='R9A2',
 ROOM='DEBUG',
 SEC='1',
 CDS_LIB='mstr_discrete',
 CDS_PART_NAME='RES_0402-33.2,1%,1/16W,EMPTY,GA',
 PRIM_FILE='./archive_libs/mstr_discrete/res/chips/chips.prt';

PART_NAME
 R9A3 'RES_0402-0.0,5%,1/16W,CHIP,G21A':
 ROOM='DEBUG';

SECTION_NUMBER 1
 '@BASEBOARD_FAB2_LIB.BASEBOARD_FAB2(SCH_1):PAGE111_I74@MSTR_DISCRETE.RES(CHIPS)':
 C_PATH='@baseboard_fab2_lib.baseboard_fab2(sch_1):page111_i74@mstr_discrete.res~
(chips)',
 P_PATH='@baseboard_fab2_lib.baseboard_fab2(sch_1):page111_i74@mstr_discrete.res~
(chips)',
 PATH='I74',
 DRAWING='@BASEBOARD_FAB2_LIB.BASEBOARD_FAB2(SCH_1):PAGE111',
 WATTAGE='1/16W',
 TOLERANCE='5%',
 SEC_TYPE='0402',
 MATERIAL='CHIP',
 PHYS_PAGE='111',
 XY='(-1900,3100)',
 ROT='0',
 VER='1',
 VALUE='0.0',
 PACK_TYPE='0402',
 PART_NUMBER='G21497-005',
 LOCATION='R9A3',
 ROOM='DEBUG',
 SEC='1',
 CDS_LIB='mstr_discrete',
 CDS_PART_NAME='RES_0402-0.0,5%,1/16W,CHIP,G21A',
 PRIM_FILE='./archive_libs/mstr_discrete/res/chips/chips.prt';

PART_NAME
 R9A4 'RES_0402-475.0,1%,1/16W,CHIP,GA':
 ROOM='DEBUG';

SECTION_NUMBER 1
 '@BASEBOARD_FAB2_LIB.BASEBOARD_FAB2(SCH_1):PAGE111_I55@MSTR_DISCRETE.RES(CHIPS)':
 C_PATH='@baseboard_fab2_lib.baseboard_fab2(sch_1):page111_i55@mstr_discrete.res~
(chips)',
 P_PATH='@baseboard_fab2_lib.baseboard_fab2(sch_1):page111_i55@mstr_discrete.res~
(chips)',
 PATH='I55',
 DRAWING='@BASEBOARD_FAB2_LIB.BASEBOARD_FAB2(SCH_1):PAGE111',
 WATTAGE='1/16W',
 TOLERANCE='1%',
 SEC_TYPE='0402',
 MATERIAL='CHIP',
 BOM_COST='DEBUG',
 PHYS_PAGE='111',
 XY='(-1400,1450)',
 ROT='0',
 VER='1',
 VALUE='475.0',
 PACK_TYPE='0402',
 PART_NUMBER='G21796-077',
 LOCATION='R9A4',
 ROOM='DEBUG',
 SEC='1',
 CDS_LIB='mstr_discrete',
 CDS_PART_NAME='RES_0402-475.0,1%,1/16W,CHIP,GA',
 PRIM_FILE='./archive_libs/mstr_discrete/res/chips/chips.prt';

PART_NAME
 R9A5 'RES_0402-20.0K,1%,1/16W,CHIP,GA':
 ROOM='SB';

SECTION_NUMBER 1
 '@BASEBOARD_FAB2_LIB.BASEBOARD_FAB2(SCH_1):PAGE155_I198@MSTR_DISCRETE.RES(CHIPS)':
 C_PATH='@baseboard_fab2_lib.baseboard_fab2(sch_1):page155_i198@mstr_discrete.re~
s(chips)',
 P_PATH='@baseboard_fab2_lib.baseboard_fab2(sch_1):page155_i198@mstr_discrete.re~
s(chips)',
 PATH='I198',
 DRAWING='@BASEBOARD_FAB2_LIB.BASEBOARD_FAB2(SCH_1):PAGE155',
 WATTAGE='1/16W',
 TOLERANCE='1%',
 SEC_TYPE='0402',
 MATERIAL='CHIP',
 BOM_COST='SB',
 PHYS_PAGE='155',
 XY='(-3350,1050)',
 ROT='0',
 VER='2',
 VALUE='20.0K',
 PACK_TYPE='0402',
 PART_NUMBER='G21796-040',
 LOCATION='R9A5',
 ROOM='SB',
 SEC='1',
 CDS_LIB='mstr_discrete',
 CDS_PART_NAME='RES_0402-20.0K,1%,1/16W,CHIP,GA',
 PRIM_FILE='./archive_libs/mstr_discrete/res/chips/chips.prt';

PART_NAME
 R9A7 'RES_0402-2.21K,1%,1/16W,CHIP,GA':
 ROOM='BMC_DEBUG_HEADER';

SECTION_NUMBER 1
 '@BASEBOARD_FAB2_LIB.BASEBOARD_FAB2(SCH_1):PAGE155_I80@MSTR_DISCRETE.RES(CHIPS)':
 C_PATH='@baseboard_fab2_lib.baseboard_fab2(sch_1):page155_i80@mstr_discrete.res~
(chips)',
 P_PATH='@baseboard_fab2_lib.baseboard_fab2(sch_1):page155_i80@mstr_discrete.res~
(chips)',
 PATH='I80',
 DRAWING='@BASEBOARD_FAB2_LIB.BASEBOARD_FAB2(SCH_1):PAGE155',
 WATTAGE='1/16W',
 TOLERANCE='1%',
 SEC_TYPE='0402',
 MATERIAL='CHIP',
 BOM_COST='DEBUG',
 PHYS_PAGE='155',
 XY='(-1450,1725)',
 ROT='0',
 VER='2',
 VALUE='2.21K',
 PACK_TYPE='0402',
 PART_NUMBER='G21796-112',
 LOCATION='R9A7',
 ROOM='BMC_DEBUG_HEADER',
 SEC='1',
 CDS_LIB='mstr_discrete',
 CDS_PART_NAME='RES_0402-2.21K,1%,1/16W,CHIP,GA',
 PRIM_FILE='./archive_libs/mstr_discrete/res/chips/chips.prt';

PART_NAME
 R9A8 'RES_0402-0.0,5%,1/16W,CHIP,G21A':
 ROOM='BMC_DEBUG_HEADER';

SECTION_NUMBER 1
 '@BASEBOARD_FAB2_LIB.BASEBOARD_FAB2(SCH_1):PAGE155_I53@MSTR_DISCRETE.RES(CHIPS)':
 C_PATH='@baseboard_fab2_lib.baseboard_fab2(sch_1):page155_i53@mstr_discrete.res~
(chips)',
 P_PATH='@baseboard_fab2_lib.baseboard_fab2(sch_1):page155_i53@mstr_discrete.res~
(chips)',
 PATH='I53',
 DRAWING='@BASEBOARD_FAB2_LIB.BASEBOARD_FAB2(SCH_1):PAGE155',
 WATTAGE='1/16W',
 TOLERANCE='5%',
 SEC_TYPE='0402',
 MATERIAL='CHIP',
 BOM_COST='DEBUG',
 PHYS_PAGE='155',
 XY='(-1125,1400)',
 ROT='0',
 VER='1',
 VALUE='0.0',
 PACK_TYPE='0402',
 PART_NUMBER='G21497-005',
 LOCATION='R9A8',
 ROOM='BMC_DEBUG_HEADER',
 SEC='1',
 CDS_LIB='mstr_discrete',
 CDS_PART_NAME='RES_0402-0.0,5%,1/16W,CHIP,G21A',
 PRIM_FILE='./archive_libs/mstr_discrete/res/chips/chips.prt';

PART_NAME
 R9A9 'RES_0402-100.0,1%,1/16W,CHIP,GA':
 ROOM='MIO_CHASSIS';

SECTION_NUMBER 1
 '@BASEBOARD_FAB2_LIB.BASEBOARD_FAB2(SCH_1):PAGE175_I95@MSTR_DISCRETE.RES(CHIPS)':
 C_PATH='@baseboard_fab2_lib.baseboard_fab2(sch_1):page175_i95@mstr_discrete.res~
(chips)',
 P_PATH='@baseboard_fab2_lib.baseboard_fab2(sch_1):page175_i95@mstr_discrete.res~
(chips)',
 PATH='I95',
 DRAWING='@BASEBOARD_FAB2_LIB.BASEBOARD_FAB2(SCH_1):PAGE175',
 WATTAGE='1/16W',
 TOLERANCE='1%',
 SEC_TYPE='0402',
 MATERIAL='CHIP',
 BOM_COST='MIO_CHASSIS',
 PHYS_PAGE='175',
 XY='(-2225,2675)',
 ROT='0',
 VER='1',
 VALUE='100.0',
 PACK_TYPE='0402',
 PART_NUMBER='G21796-017',
 LOCATION='R9A9',
 ROOM='MIO_CHASSIS',
 SEC='1',
 CDS_LIB='mstr_discrete',
 CDS_PART_NAME='RES_0402-100.0,1%,1/16W,CHIP,GA',
 PRIM_FILE='./archive_libs/mstr_discrete/res/chips/chips.prt';

PART_NAME
 R9A11 'RES_0402-150.0,1%,1/16W,CHIP,GA':
 ROOM='DEBUG';

SECTION_NUMBER 1
 '@BASEBOARD_FAB2_LIB.BASEBOARD_FAB2(SCH_1):PAGE112_I78@MSTR_DISCRETE.RES(CHIPS)':
 C_PATH='@baseboard_fab2_lib.baseboard_fab2(sch_1):page112_i78@mstr_discrete.res~
(chips)',
 P_PATH='@baseboard_fab2_lib.baseboard_fab2(sch_1):page112_i78@mstr_discrete.res~
(chips)',
 PATH='I78',
 DRAWING='@BASEBOARD_FAB2_LIB.BASEBOARD_FAB2(SCH_1):PAGE112',
 WATTAGE='1/16W',
 TOLERANCE='1%',
 SEC_TYPE='0402',
 MATERIAL='CHIP',
 PHYS_PAGE='112',
 XY='(-1950,4425)',
 ROT='0',
 VER='2',
 VALUE='150.0',
 PACK_TYPE='0402',
 PART_NUMBER='G21796-009',
 LOCATION='R9A11',
 ROOM='DEBUG',
 SEC='1',
 CDS_LIB='mstr_discrete',
 CDS_PART_NAME='RES_0402-150.0,1%,1/16W,CHIP,GA',
 PRIM_FILE='./archive_libs/mstr_discrete/res/chips/chips.prt';

PART_NAME
 R9A12 'RES_0402-2.21K,1%,1/16W,CHIP,GA':
 ROOM='SB';

SECTION_NUMBER 1
 '@BASEBOARD_FAB2_LIB.BASEBOARD_FAB2(SCH_1):PAGE135_I117@MSTR_DISCRETE.RES(CHIPS)':
 C_PATH='@baseboard_fab2_lib.baseboard_fab2(sch_1):page135_i117@mstr_discrete.re~
s(chips)',
 P_PATH='@baseboard_fab2_lib.baseboard_fab2(sch_1):page135_i117@mstr_discrete.re~
s(chips)',
 PATH='I117',
 DRAWING='@BASEBOARD_FAB2_LIB.BASEBOARD_FAB2(SCH_1):PAGE135',
 WATTAGE='1/16W',
 TOLERANCE='1%',
 MATERIAL='CHIP',
 BOM_COST='SB',
 PHYS_PAGE='135',
 XY='(-3875,4900)',
 ROT='1',
 VER='1',
 VALUE='2.21K',
 PACK_TYPE='0402',
 PART_NUMBER='G21796-112',
 LOCATION='R9A12',
 ROOM='SB',
 CDS_LIB='mstr_discrete',
 CDS_PART_NAME='RES_0402-2.21K,1%,1/16W,CHIP,GA',
 PRIM_FILE='./archive_libs/mstr_discrete/res/chips/chips.prt';

PART_NAME
 R9A13 'RES_0402-33.2,1%,1/16W,CHIP,G2A':
 ROOM='SB';

SECTION_NUMBER 1
 '@BASEBOARD_FAB2_LIB.BASEBOARD_FAB2(SCH_1):PAGE135_I118@MSTR_DISCRETE.RES(CHIPS)':
 C_PATH='@baseboard_fab2_lib.baseboard_fab2(sch_1):page135_i118@mstr_discrete.re~
s(chips)',
 P_PATH='@baseboard_fab2_lib.baseboard_fab2(sch_1):page135_i118@mstr_discrete.re~
s(chips)',
 PATH='I118',
 DRAWING='@BASEBOARD_FAB2_LIB.BASEBOARD_FAB2(SCH_1):PAGE135',
 WATTAGE='1/16W',
 TOLERANCE='1%',
 MATERIAL='CHIP',
 BOM_COST='SB',
 PHYS_PAGE='135',
 XY='(-3650,4500)',
 ROT='0',
 VER='1',
 VALUE='33.2',
 PACK_TYPE='0402',
 PART_NUMBER='G21796-074',
 LOCATION='R9A13',
 ROOM='SB',
 CDS_LIB='mstr_discrete',
 CDS_PART_NAME='RES_0402-33.2,1%,1/16W,CHIP,G2A',
 PRIM_FILE='./archive_libs/mstr_discrete/res/chips/chips.prt';

PART_NAME
 R9A14 'RES_0402-1.00K,1%,1/16W,CHIP,GA':
 ROOM='DEBUG';

SECTION_NUMBER 1
 '@BASEBOARD_FAB2_LIB.BASEBOARD_FAB2(SCH_1):PAGE111_I11@MSTR_DISCRETE.RES(CHIPS)':
 C_PATH='@baseboard_fab2_lib.baseboard_fab2(sch_1):page111_i11@mstr_discrete.res~
(chips)',
 P_PATH='@baseboard_fab2_lib.baseboard_fab2(sch_1):page111_i11@mstr_discrete.res~
(chips)',
 PATH='I11',
 DRAWING='@BASEBOARD_FAB2_LIB.BASEBOARD_FAB2(SCH_1):PAGE111',
 WATTAGE='1/16W',
 TOLERANCE='1%',
 SEC_TYPE='0402',
 MATERIAL='CHIP',
 BOM_COST='DEBUG',
 PHYS_PAGE='111',
 XY='(2725,1700)',
 ROT='0',
 VER='1',
 VALUE='1.00K',
 PACK_TYPE='0402',
 PART_NUMBER='G21796-026',
 LOCATION='R9A14',
 ROOM='DEBUG',
 SEC='1',
 CDS_LIB='mstr_discrete',
 CDS_PART_NAME='RES_0402-1.00K,1%,1/16W,CHIP,GA',
 PRIM_FILE='./archive_libs/mstr_discrete/res/chips/chips.prt';

PART_NAME
 R9A15 'RES_0402-1.00K,1%,1/16W,CHIP,GA':
 ROOM='DEBUG';

SECTION_NUMBER 1
 '@BASEBOARD_FAB2_LIB.BASEBOARD_FAB2(SCH_1):PAGE111_I60@MSTR_DISCRETE.RES(CHIPS)':
 C_PATH='@baseboard_fab2_lib.baseboard_fab2(sch_1):page111_i60@mstr_discrete.res~
(chips)',
 P_PATH='@baseboard_fab2_lib.baseboard_fab2(sch_1):page111_i60@mstr_discrete.res~
(chips)',
 PATH='I60',
 DRAWING='@BASEBOARD_FAB2_LIB.BASEBOARD_FAB2(SCH_1):PAGE111',
 WATTAGE='1/16W',
 TOLERANCE='1%',
 SEC_TYPE='0402',
 MATERIAL='CHIP',
 BOM_COST='DEBUG',
 PHYS_PAGE='111',
 XY='(-2175,3700)',
 ROT='0',
 VER='1',
 VALUE='1.00K',
 PACK_TYPE='0402',
 PART_NUMBER='G21796-026',
 LOCATION='R9A15',
 ROOM='DEBUG',
 SEC='1',
 CDS_LIB='mstr_discrete',
 CDS_PART_NAME='RES_0402-1.00K,1%,1/16W,CHIP,GA',
 PRIM_FILE='./archive_libs/mstr_discrete/res/chips/chips.prt';

PART_NAME
 R9A16 'RES_0402-2.21K,1%,1/16W,CHIP,GA':
 ROOM='SB';

SECTION_NUMBER 1
 '@BASEBOARD_FAB2_LIB.BASEBOARD_FAB2(SCH_1):PAGE135_I129@MSTR_DISCRETE.RES(CHIPS)':
 C_PATH='@baseboard_fab2_lib.baseboard_fab2(sch_1):page135_i129@mstr_discrete.re~
s(chips)',
 P_PATH='@baseboard_fab2_lib.baseboard_fab2(sch_1):page135_i129@mstr_discrete.re~
s(chips)',
 PATH='I129',
 DRAWING='@BASEBOARD_FAB2_LIB.BASEBOARD_FAB2(SCH_1):PAGE135',
 WATTAGE='1/16W',
 TOLERANCE='1%',
 MATERIAL='CHIP',
 BOM_COST='SB',
 PHYS_PAGE='135',
 XY='(-4275,4900)',
 ROT='1',
 VER='1',
 VALUE='2.21K',
 PACK_TYPE='0402',
 PART_NUMBER='G21796-112',
 LOCATION='R9A16',
 ROOM='SB',
 CDS_LIB='mstr_discrete',
 CDS_PART_NAME='RES_0402-2.21K,1%,1/16W,CHIP,GA',
 PRIM_FILE='./archive_libs/mstr_discrete/res/chips/chips.prt';

PART_NAME
 R9A17 'RES_0402-1.00K,1%,1/16W,CHIP,GA':
 ROOM='DEBUG';

SECTION_NUMBER 1
 '@BASEBOARD_FAB2_LIB.BASEBOARD_FAB2(SCH_1):PAGE111_I57@MSTR_DISCRETE.RES(CHIPS)':
 C_PATH='@baseboard_fab2_lib.baseboard_fab2(sch_1):page111_i57@mstr_discrete.res~
(chips)',
 P_PATH='@baseboard_fab2_lib.baseboard_fab2(sch_1):page111_i57@mstr_discrete.res~
(chips)',
 PATH='I57',
 DRAWING='@BASEBOARD_FAB2_LIB.BASEBOARD_FAB2(SCH_1):PAGE111',
 WATTAGE='1/16W',
 TOLERANCE='1%',
 SEC_TYPE='0402',
 MATERIAL='CHIP',
 BOM_COST='DEBUG',
 PHYS_PAGE='111',
 XY='(-1400,500)',
 ROT='0',
 VER='1',
 VALUE='1.00K',
 PACK_TYPE='0402',
 PART_NUMBER='G21796-026',
 LOCATION='R9A17',
 ROOM='DEBUG',
 SEC='1',
 CDS_LIB='mstr_discrete',
 CDS_PART_NAME='RES_0402-1.00K,1%,1/16W,CHIP,GA',
 PRIM_FILE='./archive_libs/mstr_discrete/res/chips/chips.prt';

PART_NAME
 R9A18 'RES_0402-4.75K,1%,1/16W,CHIP,GA':
 ROOM='SB';

SECTION_NUMBER 1
 '@BASEBOARD_FAB2_LIB.BASEBOARD_FAB2(SCH_1):PAGE119_I183@MSTR_DISCRETE.RES(CHIPS)':
 C_PATH='@baseboard_fab2_lib.baseboard_fab2(sch_1):page119_i183@mstr_discrete.re~
s(chips)',
 P_PATH='@baseboard_fab2_lib.baseboard_fab2(sch_1):page119_i183@mstr_discrete.re~
s(chips)',
 PATH='I183',
 DRAWING='@BASEBOARD_FAB2_LIB.BASEBOARD_FAB2(SCH_1):PAGE119',
 WATTAGE='1/16W',
 TOLERANCE='1%',
 SEC_TYPE='0402',
 MATERIAL='CHIP',
 BOM_COST='SB',
 PHYS_PAGE='119',
 XY='(-4725,1350)',
 ROT='0',
 VER='2',
 VALUE='4.75K',
 PACK_TYPE='0402',
 PART_NUMBER='G21796-072',
 LOCATION='R9A18',
 ROOM='SB',
 SEC='1',
 CDS_LIB='mstr_discrete',
 CDS_PART_NAME='RES_0402-4.75K,1%,1/16W,CHIP,GA',
 PRIM_FILE='./archive_libs/mstr_discrete/res/chips/chips.prt';

PART_NAME
 R9A20 'RES_0402-221,1.0%,1/16W,CHIP,GA':
 ROOM='SB';

SECTION_NUMBER 1
 '@BASEBOARD_FAB2_LIB.BASEBOARD_FAB2(SCH_1):PAGE119_I178@MSTR_DISCRETE.RES(CHIPS)':
 C_PATH='@baseboard_fab2_lib.baseboard_fab2(sch_1):page119_i178@mstr_discrete.re~
s(chips)',
 P_PATH='@baseboard_fab2_lib.baseboard_fab2(sch_1):page119_i178@mstr_discrete.re~
s(chips)',
 PATH='I178',
 DRAWING='@BASEBOARD_FAB2_LIB.BASEBOARD_FAB2(SCH_1):PAGE119',
 WATTAGE='1/16W',
 TOLERANCE='1.0%',
 SEC_TYPE='0402',
 MATERIAL='CHIP',
 BOM_COST='SB',
 PHYS_PAGE='119',
 XY='(-2900,1525)',
 ROT='0',
 VER='1',
 VALUE='221',
 PACK_TYPE='0402',
 PART_NUMBER='G21796-271',
 LOCATION='R9A20',
 ROOM='SB',
 SEC='1',
 CDS_LIB='mstr_discrete',
 CDS_PART_NAME='RES_0402-221,1.0%,1/16W,CHIP,GA',
 PRIM_FILE='./archive_libs/mstr_discrete/res/chips/chips.prt';

PART_NAME
 R9A21 'RES_0402-4.75K,1%,1/16W,CHIP,GA':
 ROOM='SB';

SECTION_NUMBER 1
 '@BASEBOARD_FAB2_LIB.BASEBOARD_FAB2(SCH_1):PAGE119_I186@MSTR_DISCRETE.RES(CHIPS)':
 C_PATH='@baseboard_fab2_lib.baseboard_fab2(sch_1):page119_i186@mstr_discrete.re~
s(chips)',
 P_PATH='@baseboard_fab2_lib.baseboard_fab2(sch_1):page119_i186@mstr_discrete.re~
s(chips)',
 PATH='I186',
 DRAWING='@BASEBOARD_FAB2_LIB.BASEBOARD_FAB2(SCH_1):PAGE119',
 WATTAGE='1/16W',
 TOLERANCE='1%',
 SEC_TYPE='0402',
 MATERIAL='CHIP',
 BOM_COST='SB',
 PHYS_PAGE='119',
 XY='(-5175,900)',
 ROT='0',
 VER='2',
 VALUE='4.75K',
 PACK_TYPE='0402',
 PART_NUMBER='G21796-072',
 LOCATION='R9A21',
 ROOM='SB',
 SEC='1',
 CDS_LIB='mstr_discrete',
 CDS_PART_NAME='RES_0402-4.75K,1%,1/16W,CHIP,GA',
 PRIM_FILE='./archive_libs/mstr_discrete/res/chips/chips.prt';

PART_NAME
 R9B4 'RES_0402-49.9,1%,1/16W,CHIP,G2A':
 ROOM='TEMP_SENSORS';

SECTION_NUMBER 1
 '@BASEBOARD_FAB2_LIB.BASEBOARD_FAB2(SCH_1):PAGE167_I6@MSTR_DISCRETE.RES(CHIPS)':
 C_PATH='@baseboard_fab2_lib.baseboard_fab2(sch_1):page167_i6@mstr_discrete.res(~
chips)',
 P_PATH='@baseboard_fab2_lib.baseboard_fab2(sch_1):page167_i6@mstr_discrete.res(~
chips)',
 PATH='I6',
 DRAWING='@BASEBOARD_FAB2_LIB.BASEBOARD_FAB2(SCH_1):PAGE167',
 WATTAGE='1/16W',
 TOLERANCE='1%',
 SEC_TYPE='0402',
 MATERIAL='CHIP',
 BOM_COST='SM_THERM',
 PHYS_PAGE='167',
 XY='(-5150,4775)',
 ROT='0',
 VER='1',
 VALUE='49.9',
 PACK_TYPE='0402',
 PART_NUMBER='G21796-047',
 LOCATION='R9B4',
 ROOM='TEMP_SENSORS',
 SEC='1',
 CDS_LIB='mstr_discrete',
 CDS_PART_NAME='RES_0402-49.9,1%,1/16W,CHIP,G2A',
 PRIM_FILE='./archive_libs/mstr_discrete/res/chips/chips.prt';

PART_NAME
 R9B5 'RES_0402-49.9,1%,1/16W,CHIP,G2A':
 ROOM='TEMP_SENSORS';

SECTION_NUMBER 1
 '@BASEBOARD_FAB2_LIB.BASEBOARD_FAB2(SCH_1):PAGE167_I5@MSTR_DISCRETE.RES(CHIPS)':
 C_PATH='@baseboard_fab2_lib.baseboard_fab2(sch_1):page167_i5@mstr_discrete.res(~
chips)',
 P_PATH='@baseboard_fab2_lib.baseboard_fab2(sch_1):page167_i5@mstr_discrete.res(~
chips)',
 PATH='I5',
 DRAWING='@BASEBOARD_FAB2_LIB.BASEBOARD_FAB2(SCH_1):PAGE167',
 WATTAGE='1/16W',
 TOLERANCE='1%',
 SEC_TYPE='0402',
 MATERIAL='CHIP',
 BOM_COST='SM_THERM',
 PHYS_PAGE='167',
 XY='(-5150,4450)',
 ROT='0',
 VER='1',
 VALUE='49.9',
 PACK_TYPE='0402',
 PART_NUMBER='G21796-047',
 LOCATION='R9B5',
 ROOM='TEMP_SENSORS',
 SEC='1',
 CDS_LIB='mstr_discrete',
 CDS_PART_NAME='RES_0402-49.9,1%,1/16W,CHIP,G2A',
 PRIM_FILE='./archive_libs/mstr_discrete/res/chips/chips.prt';

PART_NAME
 R9B6 'RES_0402-1.00K,1%,1/16W,CHIP,GA':
 ROOM='TEMP_SENSORS';

SECTION_NUMBER 1
 '@BASEBOARD_FAB2_LIB.BASEBOARD_FAB2(SCH_1):PAGE167_I35@MSTR_DISCRETE.RES(CHIPS)':
 C_PATH='@baseboard_fab2_lib.baseboard_fab2(sch_1):page167_i35@mstr_discrete.res~
(chips)',
 P_PATH='@baseboard_fab2_lib.baseboard_fab2(sch_1):page167_i35@mstr_discrete.res~
(chips)',
 PATH='I35',
 DRAWING='@BASEBOARD_FAB2_LIB.BASEBOARD_FAB2(SCH_1):PAGE167',
 WATTAGE='1/16W',
 TOLERANCE='1%',
 SEC_TYPE='0402',
 MATERIAL='CHIP',
 BOM_COST='SM_THERM',
 PHYS_PAGE='167',
 XY='(-5475,4150)',
 ROT='0',
 VER='1',
 VALUE='1.00K',
 PACK_TYPE='0402',
 PART_NUMBER='G21796-026',
 LOCATION='R9B6',
 ROOM='TEMP_SENSORS',
 SEC='1',
 CDS_LIB='mstr_discrete',
 CDS_PART_NAME='RES_0402-1.00K,1%,1/16W,CHIP,GA',
 PRIM_FILE='./archive_libs/mstr_discrete/res/chips/chips.prt';

PART_NAME
 R9B7 '887R2F-L-GP_SMD-RG-887R2F-L-GPA':;

SECTION_NUMBER 1
 '@BASEBOARD_FAB2_LIB.BASEBOARD_FAB2(SCH_1):PAGE186_I358@W_HDL.887R2F-L-GP(CHIPS)':
 C_PATH='@baseboard_fab2_lib.baseboard_fab2(sch_1):page186_i358@w_hdl.\887r2f-l-~
gp\(chips)',
 P_PATH='@baseboard_fab2_lib.baseboard_fab2(sch_1):page186_i358@w_hdl.\887r2f-l-~
gp\(chips)',
 PATH='I358',
 DRAWING='@BASEBOARD_FAB2_LIB.BASEBOARD_FAB2(SCH_1):PAGE186',
 PACK_SIZE='0402',
 RATED='1/16W',
 ATTRIBUTE='887OHM',
 TOLERANCE='1%',
 SEC_TYPE='SMD-RG',
 PHYS_PAGE='186',
 XY='(6300,3675)',
 ROT='0',
 VER='1',
 VALUE='887R2F-L-GP',
 PACK_TYPE='SMD-RG',
 PART_NUMBER='64.88705.6DL',
 LOCATION='R9B7',
 SEC='1',
 CDS_LIB='w_hdl',
 CDS_PART_NAME='887R2F-L-GP_SMD-RG-887R2F-L-GPA',
 PRIM_FILE='C:/<user>/w_hdl/887r2f#2dl#2dgp/chips/chips.prt';

PART_NAME
 R9B8 'RES_0402-1.00K,1%,1/16W,CHIP,GA':
 ROOM='TEMP_SENSORS';

SECTION_NUMBER 1
 '@BASEBOARD_FAB2_LIB.BASEBOARD_FAB2(SCH_1):PAGE167_I10@MSTR_DISCRETE.RES(CHIPS)':
 C_PATH='@baseboard_fab2_lib.baseboard_fab2(sch_1):page167_i10@mstr_discrete.res~
(chips)',
 P_PATH='@baseboard_fab2_lib.baseboard_fab2(sch_1):page167_i10@mstr_discrete.res~
(chips)',
 PATH='I10',
 DRAWING='@BASEBOARD_FAB2_LIB.BASEBOARD_FAB2(SCH_1):PAGE167',
 WATTAGE='1/16W',
 TOLERANCE='1%',
 SEC_TYPE='0402',
 MATERIAL='CHIP',
 BOM_COST='SM_THERM',
 PHYS_PAGE='167',
 XY='(-4775,4075)',
 ROT='0',
 VER='2',
 VALUE='1.00K',
 PACK_TYPE='0402',
 PART_NUMBER='G21796-026',
 LOCATION='R9B8',
 ROOM='TEMP_SENSORS',
 SEC='1',
 CDS_LIB='mstr_discrete',
 CDS_PART_NAME='RES_0402-1.00K,1%,1/16W,CHIP,GA',
 PRIM_FILE='./archive_libs/mstr_discrete/res/chips/chips.prt';

PART_NAME
 R9B9 'RES_0402-1.00K,1%,1/16W,CHIP,GA':
 GROUP='MCP';

SECTION_NUMBER 1
 '@BASEBOARD_FAB2_LIB.BASEBOARD_FAB2(SCH_1):PAGE113_I179@MSTR_DISCRETE.RES(CHIPS)':
 C_PATH='@baseboard_fab2_lib.baseboard_fab2(sch_1):page113_i179@mstr_discrete.re~
s(chips)',
 P_PATH='@baseboard_fab2_lib.baseboard_fab2(sch_1):page113_i179@mstr_discrete.re~
s(chips)',
 PATH='I179',
 DRAWING='@BASEBOARD_FAB2_LIB.BASEBOARD_FAB2(SCH_1):PAGE113',
 WATTAGE='1/16W',
 TOLERANCE='1%',
 SEC_TYPE='0402',
 MATERIAL='CHIP',
 PHYS_PAGE='113',
 XY='(2600,4150)',
 ROT='2',
 VER='2',
 VALUE='1.00K',
 PACK_TYPE='0402',
 PART_NUMBER='G21796-026',
 LOCATION='R9B9',
 GROUP='MCP',
 SEC='1',
 CDS_LIB='mstr_discrete',
 CDS_PART_NAME='RES_0402-1.00K,1%,1/16W,CHIP,GA',
 PRIM_FILE='./archive_libs/mstr_discrete/res/chips/chips.prt';

PART_NAME
 R9B10 'RES_0402-49.9,1%,1/16W,CHIP,G2A':
 ROOM='DEBUG';

SECTION_NUMBER 1
 '@BASEBOARD_FAB2_LIB.BASEBOARD_FAB2(SCH_1):PAGE113_I180@MSTR_DISCRETE.RES(CHIPS)':
 C_PATH='@baseboard_fab2_lib.baseboard_fab2(sch_1):page113_i180@mstr_discrete.re~
s(chips)',
 P_PATH='@baseboard_fab2_lib.baseboard_fab2(sch_1):page113_i180@mstr_discrete.re~
s(chips)',
 PATH='I180',
 DRAWING='@BASEBOARD_FAB2_LIB.BASEBOARD_FAB2(SCH_1):PAGE113',
 POP='NOPOP',
 WATTAGE='1/16W',
 TOLERANCE='1%',
 SEC_TYPE='0402',
 MATERIAL='CHIP',
 BOM_COST='DEBUG',
 PHYS_PAGE='113',
 XY='(2800,4400)',
 ROT='0',
 VER='1',
 VALUE='49.9',
 PACK_TYPE='0402',
 PART_NUMBER='G21796-047',
 LOCATION='R9B10',
 ROOM='DEBUG',
 SEC='1',
 CDS_LIB='mstr_discrete',
 CDS_PART_NAME='RES_0402-49.9,1%,1/16W,CHIP,G2A',
 PRIM_FILE='./archive_libs/mstr_discrete/res/chips/chips.prt';

PART_NAME
 R9B11 'RES_0402-0.0,5%,1/16W,CHIP,G21A':
 GROUP='MCP';

SECTION_NUMBER 1
 '@BASEBOARD_FAB2_LIB.BASEBOARD_FAB2(SCH_1):PAGE113_I239@MSTR_DISCRETE.RES(CHIPS)':
 C_PATH='@baseboard_fab2_lib.baseboard_fab2(sch_1):page113_i239@mstr_discrete.re~
s(chips)',
 P_PATH='@baseboard_fab2_lib.baseboard_fab2(sch_1):page113_i239@mstr_discrete.re~
s(chips)',
 PATH='I239',
 DRAWING='@BASEBOARD_FAB2_LIB.BASEBOARD_FAB2(SCH_1):PAGE113',
 WATTAGE='1/16W',
 TOLERANCE='5%',
 SEC_TYPE='0402',
 MATERIAL='CHIP',
 PHYS_PAGE='113',
 XY='(-2600,4625)',
 ROT='0',
 VER='1',
 VALUE='0.0',
 PACK_TYPE='0402',
 PART_NUMBER='G21497-005',
 LOCATION='R9B11',
 GROUP='MCP',
 SEC='1',
 CDS_LIB='mstr_discrete',
 CDS_PART_NAME='RES_0402-0.0,5%,1/16W,CHIP,G21A',
 PRIM_FILE='./archive_libs/mstr_discrete/res/chips/chips.prt';

PART_NAME
 R9B12 'RES_0402-1.00K,1%,1/16W,CHIP,GA':
 GROUP='MCP',
 ROOM='DEBUG';

SECTION_NUMBER 1
 '@BASEBOARD_FAB2_LIB.BASEBOARD_FAB2(SCH_1):PAGE113_I203@MSTR_DISCRETE.RES(CHIPS)':
 C_PATH='@baseboard_fab2_lib.baseboard_fab2(sch_1):page113_i203@mstr_discrete.re~
s(chips)',
 P_PATH='@baseboard_fab2_lib.baseboard_fab2(sch_1):page113_i203@mstr_discrete.re~
s(chips)',
 PATH='I203',
 DRAWING='@BASEBOARD_FAB2_LIB.BASEBOARD_FAB2(SCH_1):PAGE113',
 WATTAGE='1/16W',
 TOLERANCE='1%',
 SEC_TYPE='0402',
 MATERIAL='CHIP',
 BOM_COST='DEBUG',
 PHYS_PAGE='113',
 XY='(3425,1025)',
 ROT='0',
 VER='2',
 VALUE='1.00K',
 PACK_TYPE='0402',
 PART_NUMBER='G21796-026',
 LOCATION='R9B12',
 ROOM='DEBUG',
 GROUP='MCP',
 SEC='1',
 CDS_LIB='mstr_discrete',
 CDS_PART_NAME='RES_0402-1.00K,1%,1/16W,CHIP,GA',
 PRIM_FILE='./archive_libs/mstr_discrete/res/chips/chips.prt';

PART_NAME
 R9B13 'RES_0402-0.0,5%,1/16W,CHIP,G21A':
 GROUP='MCP';

SECTION_NUMBER 1
 '@BASEBOARD_FAB2_LIB.BASEBOARD_FAB2(SCH_1):PAGE113_I240@MSTR_DISCRETE.RES(CHIPS)':
 C_PATH='@baseboard_fab2_lib.baseboard_fab2(sch_1):page113_i240@mstr_discrete.re~
s(chips)',
 P_PATH='@baseboard_fab2_lib.baseboard_fab2(sch_1):page113_i240@mstr_discrete.re~
s(chips)',
 PATH='I240',
 DRAWING='@BASEBOARD_FAB2_LIB.BASEBOARD_FAB2(SCH_1):PAGE113',
 WATTAGE='1/16W',
 TOLERANCE='5%',
 SEC_TYPE='0402',
 MATERIAL='CHIP',
 PHYS_PAGE='113',
 XY='(-2600,4375)',
 ROT='0',
 VER='1',
 VALUE='0.0',
 PACK_TYPE='0402',
 PART_NUMBER='G21497-005',
 LOCATION='R9B13',
 GROUP='MCP',
 SEC='1',
 CDS_LIB='mstr_discrete',
 CDS_PART_NAME='RES_0402-0.0,5%,1/16W,CHIP,G21A',
 PRIM_FILE='./archive_libs/mstr_discrete/res/chips/chips.prt';

PART_NAME
 R9B14 'RES_0402-1.00K,1%,1/16W,CHIP,GA':
 GROUP='MCP',
 ROOM='DEBUG';

SECTION_NUMBER 1
 '@BASEBOARD_FAB2_LIB.BASEBOARD_FAB2(SCH_1):PAGE113_I168@MSTR_DISCRETE.RES(CHIPS)':
 C_PATH='@baseboard_fab2_lib.baseboard_fab2(sch_1):page113_i168@mstr_discrete.re~
s(chips)',
 P_PATH='@baseboard_fab2_lib.baseboard_fab2(sch_1):page113_i168@mstr_discrete.re~
s(chips)',
 PATH='I168',
 DRAWING='@BASEBOARD_FAB2_LIB.BASEBOARD_FAB2(SCH_1):PAGE113',
 WATTAGE='1/16W',
 TOLERANCE='1%',
 SEC_TYPE='0402',
 MATERIAL='CHIP',
 PHYS_PAGE='113',
 XY='(-2600,4150)',
 ROT='0',
 VER='1',
 VALUE='1.00K',
 PACK_TYPE='0402',
 PART_NUMBER='G21796-026',
 LOCATION='R9B14',
 ROOM='DEBUG',
 GROUP='MCP',
 SEC='1',
 CDS_LIB='mstr_discrete',
 CDS_PART_NAME='RES_0402-1.00K,1%,1/16W,CHIP,GA',
 PRIM_FILE='./archive_libs/mstr_discrete/res/chips/chips.prt';

PART_NAME
 R9E1 'RES_0402-10.0K,1%,1/16W,CHIP,GA':
 GROUP='NI_I210&RJ45',
 ROOM='NIC_SPRV';

SECTION_NUMBER 1
 '@BASEBOARD_FAB2_LIB.BASEBOARD_FAB2(SCH_1):PAGE139_I179@MSTR_DISCRETE.RES(CHIPS)':
 C_PATH='@baseboard_fab2_lib.baseboard_fab2(sch_1):page139_i179@mstr_discrete.re~
s(chips)',
 P_PATH='@baseboard_fab2_lib.baseboard_fab2(sch_1):page139_i179@mstr_discrete.re~
s(chips)',
 PATH='I179',
 DRAWING='@BASEBOARD_FAB2_LIB.BASEBOARD_FAB2(SCH_1):PAGE139',
 WATTAGE='1/16W',
 TOLERANCE='1%',
 SEC_TYPE='0402',
 MATERIAL='CHIP',
 BOM_COST='NT_GBE_BASE',
 PHYS_PAGE='139',
 XY='(-7750,3125)',
 ROT='0',
 VER='2',
 VALUE='10.0K',
 PACK_TYPE='0402',
 PART_NUMBER='G21796-016',
 LOCATION='R9E1',
 ROOM='NIC_SPRV',
 GROUP='NI_I210&RJ45',
 SEC='1',
 CDS_LIB='mstr_discrete',
 CDS_PART_NAME='RES_0402-10.0K,1%,1/16W,CHIP,GA',
 PRIM_FILE='./archive_libs/mstr_discrete/res/chips/chips.prt';

PART_NAME
 R9E2 'RES_0402-10.0K,1%,1/16W,CHIP,GA':
 GROUP='NI_I210&RJ45',
 ROOM='NIC_SPRV';

SECTION_NUMBER 1
 '@BASEBOARD_FAB2_LIB.BASEBOARD_FAB2(SCH_1):PAGE139_I177@MSTR_DISCRETE.RES(CHIPS)':
 C_PATH='@baseboard_fab2_lib.baseboard_fab2(sch_1):page139_i177@mstr_discrete.re~
s(chips)',
 P_PATH='@baseboard_fab2_lib.baseboard_fab2(sch_1):page139_i177@mstr_discrete.re~
s(chips)',
 PATH='I177',
 DRAWING='@BASEBOARD_FAB2_LIB.BASEBOARD_FAB2(SCH_1):PAGE139',
 WATTAGE='1/16W',
 TOLERANCE='1%',
 SEC_TYPE='0402',
 MATERIAL='CHIP',
 BOM_COST='NT_GBE_BASE',
 PHYS_PAGE='139',
 XY='(-7200,3125)',
 ROT='0',
 VER='2',
 VALUE='10.0K',
 PACK_TYPE='0402',
 PART_NUMBER='G21796-016',
 LOCATION='R9E2',
 ROOM='NIC_SPRV',
 GROUP='NI_I210&RJ45',
 SEC='1',
 CDS_LIB='mstr_discrete',
 CDS_PART_NAME='RES_0402-10.0K,1%,1/16W,CHIP,GA',
 PRIM_FILE='./archive_libs/mstr_discrete/res/chips/chips.prt';

PART_NAME
 R9E3 'RES_0402-10.0K,1%,1/16W,CHIP,GA':
 GROUP='NI_I210&RJ45',
 ROOM='NIC_SPRV';

SECTION_NUMBER 1
 '@BASEBOARD_FAB2_LIB.BASEBOARD_FAB2(SCH_1):PAGE139_I178@MSTR_DISCRETE.RES(CHIPS)':
 C_PATH='@baseboard_fab2_lib.baseboard_fab2(sch_1):page139_i178@mstr_discrete.re~
s(chips)',
 P_PATH='@baseboard_fab2_lib.baseboard_fab2(sch_1):page139_i178@mstr_discrete.re~
s(chips)',
 PATH='I178',
 DRAWING='@BASEBOARD_FAB2_LIB.BASEBOARD_FAB2(SCH_1):PAGE139',
 WATTAGE='1/16W',
 TOLERANCE='1%',
 SEC_TYPE='0402',
 MATERIAL='CHIP',
 BOM_COST='NT_GBE_BASE',
 PHYS_PAGE='139',
 XY='(-7475,3125)',
 ROT='0',
 VER='2',
 VALUE='10.0K',
 PACK_TYPE='0402',
 PART_NUMBER='G21796-016',
 LOCATION='R9E3',
 ROOM='NIC_SPRV',
 GROUP='NI_I210&RJ45',
 SEC='1',
 CDS_LIB='mstr_discrete',
 CDS_PART_NAME='RES_0402-10.0K,1%,1/16W,CHIP,GA',
 PRIM_FILE='./archive_libs/mstr_discrete/res/chips/chips.prt';

PART_NAME
 R9E4 'RES_0402-10.0K,1%,1/16W,CHIP,GA':
 ROOM='NIC_SPRV';

SECTION_NUMBER 1
 '@BASEBOARD_FAB2_LIB.BASEBOARD_FAB2(SCH_1):PAGE139_I200@MSTR_DISCRETE.RES(CHIPS)':
 C_PATH='@baseboard_fab2_lib.baseboard_fab2(sch_1):page139_i200@mstr_discrete.re~
s(chips)',
 P_PATH='@baseboard_fab2_lib.baseboard_fab2(sch_1):page139_i200@mstr_discrete.re~
s(chips)',
 PATH='I200',
 DRAWING='@BASEBOARD_FAB2_LIB.BASEBOARD_FAB2(SCH_1):PAGE139',
 WATTAGE='1/16W',
 TOLERANCE='1%',
 SEC_TYPE='0402',
 MATERIAL='CHIP',
 BOM_COST='NT_GBE_BASE',
 PHYS_PAGE='139',
 XY='(-6925,550)',
 ROT='0',
 VER='2',
 VALUE='10.0K',
 PACK_TYPE='0402',
 PART_NUMBER='G21796-016',
 LOCATION='R9E4',
 ROOM='NIC_SPRV',
 SEC='1',
 CDS_LIB='mstr_discrete',
 CDS_PART_NAME='RES_0402-10.0K,1%,1/16W,CHIP,GA',
 PRIM_FILE='./archive_libs/mstr_discrete/res/chips/chips.prt';

PART_NAME
 R9E5 'RES_0402-33.2,1%,1/16W,CHIP,G2A':
 GROUP='NI_I210&RJ45',
 ROOM='NIC_SPRV';

SECTION_NUMBER 1
 '@BASEBOARD_FAB2_LIB.BASEBOARD_FAB2(SCH_1):PAGE139_I129@MSTR_DISCRETE.RES(CHIPS)':
 C_PATH='@baseboard_fab2_lib.baseboard_fab2(sch_1):page139_i129@mstr_discrete.re~
s(chips)',
 P_PATH='@baseboard_fab2_lib.baseboard_fab2(sch_1):page139_i129@mstr_discrete.re~
s(chips)',
 PATH='I129',
 DRAWING='@BASEBOARD_FAB2_LIB.BASEBOARD_FAB2(SCH_1):PAGE139',
 WATTAGE='1/16W',
 TOLERANCE='1%',
 SEC_TYPE='0402',
 MATERIAL='CHIP',
 BOM_COST='NT_GBE_BASE',
 PHYS_PAGE='139',
 XY='(-1850,2325)',
 ROT='0',
 VER='1',
 VALUE='33.2',
 PACK_TYPE='0402',
 PART_NUMBER='G21796-074',
 LOCATION='R9E5',
 ROOM='NIC_SPRV',
 GROUP='NI_I210&RJ45',
 SEC='1',
 CDS_LIB='mstr_discrete',
 CDS_PART_NAME='RES_0402-33.2,1%,1/16W,CHIP,G2A',
 PRIM_FILE='./archive_libs/mstr_discrete/res/chips/chips.prt';

PART_NAME
 R9E6 'RES_0402-33.2,1%,1/16W,CHIP,G2A':
 GROUP='NI_I210&RJ45',
 ROOM='NIC_SPRV';

SECTION_NUMBER 1
 '@BASEBOARD_FAB2_LIB.BASEBOARD_FAB2(SCH_1):PAGE140_I17@MSTR_DISCRETE.RES(CHIPS)':
 C_PATH='@baseboard_fab2_lib.baseboard_fab2(sch_1):page140_i17@mstr_discrete.res~
(chips)',
 P_PATH='@baseboard_fab2_lib.baseboard_fab2(sch_1):page140_i17@mstr_discrete.res~
(chips)',
 PATH='I17',
 DRAWING='@BASEBOARD_FAB2_LIB.BASEBOARD_FAB2(SCH_1):PAGE140',
 WATTAGE='1/16W',
 TOLERANCE='1%',
 SEC_TYPE='0402',
 MATERIAL='CHIP',
 BOM_COST='NT_GBE_BASE',
 PHYS_PAGE='140',
 XY='(-1400,2750)',
 ROT='0',
 VER='1',
 VALUE='33.2',
 PACK_TYPE='0402',
 PART_NUMBER='G21796-074',
 LOCATION='R9E6',
 ROOM='NIC_SPRV',
 GROUP='NI_I210&RJ45',
 SEC='1',
 CDS_LIB='mstr_discrete',
 CDS_PART_NAME='RES_0402-33.2,1%,1/16W,CHIP,G2A',
 PRIM_FILE='./archive_libs/mstr_discrete/res/chips/chips.prt';

PART_NAME
 R9E7 'RES_0402-3.32K,1%,1/16W,CHIP,GA':
 ROOM='NIC_SPRV';

SECTION_NUMBER 1
 '@BASEBOARD_FAB2_LIB.BASEBOARD_FAB2(SCH_1):PAGE139_I193@MSTR_DISCRETE.RES(CHIPS)':
 C_PATH='@baseboard_fab2_lib.baseboard_fab2(sch_1):page139_i193@mstr_discrete.re~
s(chips)',
 P_PATH='@baseboard_fab2_lib.baseboard_fab2(sch_1):page139_i193@mstr_discrete.re~
s(chips)',
 PATH='I193',
 DRAWING='@BASEBOARD_FAB2_LIB.BASEBOARD_FAB2(SCH_1):PAGE139',
 WATTAGE='1/16W',
 TOLERANCE='1%',
 MATERIAL='CHIP',
 BOM_COST='NT_GBE_BASE',
 PHYS_PAGE='139',
 XY='(-1000,4475)',
 ROT='0',
 VER='2',
 VALUE='3.32K',
 PACK_TYPE='0402',
 PART_NUMBER='G21796-027',
 LOCATION='R9E7',
 ROOM='NIC_SPRV',
 CDS_LIB='mstr_discrete',
 CDS_PART_NAME='RES_0402-3.32K,1%,1/16W,CHIP,GA',
 PRIM_FILE='./archive_libs/mstr_discrete/res/chips/chips.prt';

PART_NAME
 R9E8 'RES_0402-33.2,1%,1/16W,CHIP,G2A':
 GROUP='NI_I210&RJ45',
 ROOM='NIC_SPRV';

SECTION_NUMBER 1
 '@BASEBOARD_FAB2_LIB.BASEBOARD_FAB2(SCH_1):PAGE139_I130@MSTR_DISCRETE.RES(CHIPS)':
 C_PATH='@baseboard_fab2_lib.baseboard_fab2(sch_1):page139_i130@mstr_discrete.re~
s(chips)',
 P_PATH='@baseboard_fab2_lib.baseboard_fab2(sch_1):page139_i130@mstr_discrete.re~
s(chips)',
 PATH='I130',
 DRAWING='@BASEBOARD_FAB2_LIB.BASEBOARD_FAB2(SCH_1):PAGE139',
 WATTAGE='1/16W',
 TOLERANCE='1%',
 SEC_TYPE='0402',
 MATERIAL='CHIP',
 BOM_COST='NT_GBE_BASE',
 PHYS_PAGE='139',
 XY='(-2400,2275)',
 ROT='0',
 VER='1',
 VALUE='33.2',
 PACK_TYPE='0402',
 PART_NUMBER='G21796-074',
 LOCATION='R9E8',
 ROOM='NIC_SPRV',
 GROUP='NI_I210&RJ45',
 SEC='1',
 CDS_LIB='mstr_discrete',
 CDS_PART_NAME='RES_0402-33.2,1%,1/16W,CHIP,G2A',
 PRIM_FILE='./archive_libs/mstr_discrete/res/chips/chips.prt';

PART_NAME
 R9E9 'RES_0402-33.2,1%,1/16W,CHIP,G2A':
 GROUP='NI_I210&RJ45',
 ROOM='NIC_SPRV';

SECTION_NUMBER 1
 '@BASEBOARD_FAB2_LIB.BASEBOARD_FAB2(SCH_1):PAGE139_I128@MSTR_DISCRETE.RES(CHIPS)':
 C_PATH='@baseboard_fab2_lib.baseboard_fab2(sch_1):page139_i128@mstr_discrete.re~
s(chips)',
 P_PATH='@baseboard_fab2_lib.baseboard_fab2(sch_1):page139_i128@mstr_discrete.re~
s(chips)',
 PATH='I128',
 DRAWING='@BASEBOARD_FAB2_LIB.BASEBOARD_FAB2(SCH_1):PAGE139',
 WATTAGE='1/16W',
 TOLERANCE='1%',
 SEC_TYPE='0402',
 MATERIAL='CHIP',
 BOM_COST='NT_GBE_BASE',
 PHYS_PAGE='139',
 XY='(-2400,2375)',
 ROT='0',
 VER='1',
 VALUE='33.2',
 PACK_TYPE='0402',
 PART_NUMBER='G21796-074',
 LOCATION='R9E9',
 ROOM='NIC_SPRV',
 GROUP='NI_I210&RJ45',
 SEC='1',
 CDS_LIB='mstr_discrete',
 CDS_PART_NAME='RES_0402-33.2,1%,1/16W,CHIP,G2A',
 PRIM_FILE='./archive_libs/mstr_discrete/res/chips/chips.prt';

PART_NAME
 R9E10 'RES_0402-200.0,1%,1/16W,CHIP,GA':
 ROOM='IO_SLOT';

SECTION_NUMBER 1
 '@BASEBOARD_FAB2_LIB.BASEBOARD_FAB2(SCH_1):PAGE187_I145@MSTR_DISCRETE.RES(CHIPS)':
 C_PATH='@baseboard_fab2_lib.baseboard_fab2(sch_1):page187_i145@mstr_discrete.re~
s(chips)',
 P_PATH='@baseboard_fab2_lib.baseboard_fab2(sch_1):page187_i145@mstr_discrete.re~
s(chips)',
 PATH='I145',
 DRAWING='@BASEBOARD_FAB2_LIB.BASEBOARD_FAB2(SCH_1):PAGE187',
 WATTAGE='1/16W',
 TOLERANCE='1%',
 SEC_TYPE='0402',
 MATERIAL='CHIP',
 PHYS_PAGE='187',
 XY='(2275,2200)',
 ROT='0',
 VER='1',
 VALUE='200.0',
 PACK_TYPE='0402',
 PART_NUMBER='G21796-004',
 LOCATION='R9E10',
 ROOM='IO_SLOT',
 SEC='1',
 CDS_LIB='mstr_discrete',
 CDS_PART_NAME='RES_0402-200.0,1%,1/16W,CHIP,GA',
 PRIM_FILE='./archive_libs/mstr_discrete/res/chips/chips.prt';

PART_NAME
 R9E11 'RES_0402-200.0,1%,1/16W,CHIP,GA':
 ROOM='IO_SLOT';

SECTION_NUMBER 1
 '@BASEBOARD_FAB2_LIB.BASEBOARD_FAB2(SCH_1):PAGE187_I150@MSTR_DISCRETE.RES(CHIPS)':
 C_PATH='@baseboard_fab2_lib.baseboard_fab2(sch_1):page187_i150@mstr_discrete.re~
s(chips)',
 P_PATH='@baseboard_fab2_lib.baseboard_fab2(sch_1):page187_i150@mstr_discrete.re~
s(chips)',
 PATH='I150',
 DRAWING='@BASEBOARD_FAB2_LIB.BASEBOARD_FAB2(SCH_1):PAGE187',
 WATTAGE='1/16W',
 TOLERANCE='1%',
 SEC_TYPE='0402',
 MATERIAL='CHIP',
 PHYS_PAGE='187',
 XY='(1725,2150)',
 ROT='0',
 VER='1',
 VALUE='200.0',
 PACK_TYPE='0402',
 PART_NUMBER='G21796-004',
 LOCATION='R9E11',
 ROOM='IO_SLOT',
 SEC='1',
 CDS_LIB='mstr_discrete',
 CDS_PART_NAME='RES_0402-200.0,1%,1/16W,CHIP,GA',
 PRIM_FILE='./archive_libs/mstr_discrete/res/chips/chips.prt';

PART_NAME
 R9E12 'RES_0402-200.0,1%,1/16W,CHIP,GA':
 ROOM='IO_SLOT';

SECTION_NUMBER 1
 '@BASEBOARD_FAB2_LIB.BASEBOARD_FAB2(SCH_1):PAGE187_I153@MSTR_DISCRETE.RES(CHIPS)':
 C_PATH='@baseboard_fab2_lib.baseboard_fab2(sch_1):page187_i153@mstr_discrete.re~
s(chips)',
 P_PATH='@baseboard_fab2_lib.baseboard_fab2(sch_1):page187_i153@mstr_discrete.re~
s(chips)',
 PATH='I153',
 DRAWING='@BASEBOARD_FAB2_LIB.BASEBOARD_FAB2(SCH_1):PAGE187',
 WATTAGE='1/16W',
 TOLERANCE='1%',
 SEC_TYPE='0402',
 MATERIAL='CHIP',
 PHYS_PAGE='187',
 XY='(1275,2100)',
 ROT='0',
 VER='1',
 VALUE='200.0',
 PACK_TYPE='0402',
 PART_NUMBER='G21796-004',
 LOCATION='R9E12',
 ROOM='IO_SLOT',
 SEC='1',
 CDS_LIB='mstr_discrete',
 CDS_PART_NAME='RES_0402-200.0,1%,1/16W,CHIP,GA',
 PRIM_FILE='./archive_libs/mstr_discrete/res/chips/chips.prt';

PART_NAME
 R9E13 'RES_0402-10.0K,1%,1/16W,CHIP,GA':
 ROOM='NIC_SPRV';

SECTION_NUMBER 1
 '@BASEBOARD_FAB2_LIB.BASEBOARD_FAB2(SCH_1):PAGE139_I212@MSTR_DISCRETE.RES(CHIPS)':
 C_PATH='@baseboard_fab2_lib.baseboard_fab2(sch_1):page139_i212@mstr_discrete.re~
s(chips)',
 P_PATH='@baseboard_fab2_lib.baseboard_fab2(sch_1):page139_i212@mstr_discrete.re~
s(chips)',
 PATH='I212',
 DRAWING='@BASEBOARD_FAB2_LIB.BASEBOARD_FAB2(SCH_1):PAGE139',
 WATTAGE='1/16W',
 TOLERANCE='1%',
 MATERIAL='CHIP',
 BOM_COST='NT_GBE_BASE',
 PHYS_PAGE='139',
 XY='(-1900,1650)',
 ROT='0',
 VER='2',
 VALUE='10.0K',
 PACK_TYPE='0402',
 PART_NUMBER='G21796-016',
 LOCATION='R9E13',
 ROOM='NIC_SPRV',
 CDS_LIB='mstr_discrete',
 CDS_PART_NAME='RES_0402-10.0K,1%,1/16W,CHIP,GA',
 PRIM_FILE='./archive_libs/mstr_discrete/res/chips/chips.prt';

PART_NAME
 R9E14 'RES_0402-0.0,5%,1/16W,EMPTY,G2A':
 ROOM='NV_DIMM';

SECTION_NUMBER 1
 '@BASEBOARD_FAB2_LIB.BASEBOARD_FAB2(SCH_1):PAGE157_I393@MSTR_DISCRETE.RES(CHIPS)':
 C_PATH='@baseboard_fab2_lib.baseboard_fab2(sch_1):page157_i393@mstr_discrete.re~
s(chips)',
 P_PATH='@baseboard_fab2_lib.baseboard_fab2(sch_1):page157_i393@mstr_discrete.re~
s(chips)',
 PATH='I393',
 DRAWING='@BASEBOARD_FAB2_LIB.BASEBOARD_FAB2(SCH_1):PAGE157',
 WATTAGE='1/16W',
 TOLERANCE='5%',
 SEC_TYPE='0402',
 MATERIAL='EMPTY',
 BOM_COST='MEM_NV',
 PHYS_PAGE='157',
 XY='(-1450,875)',
 ROT='0',
 VER='1',
 VALUE='0.0',
 PACK_TYPE='0402',
 PART_NUMBER='G21497-005',
 LOCATION='R9E14',
 ROOM='NV_DIMM',
 SEC='1',
 CDS_LIB='mstr_discrete',
 CDS_PART_NAME='RES_0402-0.0,5%,1/16W,EMPTY,G2A',
 PRIM_FILE='./archive_libs/mstr_discrete/res/chips/chips.prt';

PART_NAME
 R9E16 'RES_0402-33.2,1%,1/16W,CHIP,G2A':
 GROUP='NI_I210&RJ45',
 ROOM='SB';

SECTION_NUMBER 1
 '@BASEBOARD_FAB2_LIB.BASEBOARD_FAB2(SCH_1):PAGE139_I235@MSTR_DISCRETE.RES(CHIPS)':
 C_PATH='@baseboard_fab2_lib.baseboard_fab2(sch_1):page139_i235@mstr_discrete.re~
s(chips)',
 P_PATH='@baseboard_fab2_lib.baseboard_fab2(sch_1):page139_i235@mstr_discrete.re~
s(chips)',
 PATH='I235',
 DRAWING='@BASEBOARD_FAB2_LIB.BASEBOARD_FAB2(SCH_1):PAGE139',
 WATTAGE='1/16W',
 TOLERANCE='1%',
 SEC_TYPE='0402',
 MATERIAL='CHIP',
 PHYS_PAGE='139',
 XY='(-2075,2725)',
 ROT='0',
 VER='1',
 VALUE='33.2',
 PACK_TYPE='0402',
 PART_NUMBER='G21796-074',
 LOCATION='R9E16',
 ROOM='SB',
 GROUP='NI_I210&RJ45',
 SEC='1',
 CDS_LIB='mstr_discrete',
 CDS_PART_NAME='RES_0402-33.2,1%,1/16W,CHIP,G2A',
 PRIM_FILE='./archive_libs/mstr_discrete/res/chips/chips.prt';

PART_NAME
 R9E17 'RES_0402-22.1,1.0%,1/16W,CHIP,A':
 GROUP='NI_I210&RJ45',
 ROOM='BMC';

SECTION_NUMBER 1
 '@BASEBOARD_FAB2_LIB.BASEBOARD_FAB2(SCH_1):PAGE139_I229@MSTR_DISCRETE.RES(CHIPS)':
 C_PATH='@baseboard_fab2_lib.baseboard_fab2(sch_1):page139_i229@mstr_discrete.re~
s(chips)',
 P_PATH='@baseboard_fab2_lib.baseboard_fab2(sch_1):page139_i229@mstr_discrete.re~
s(chips)',
 PATH='I229',
 DRAWING='@BASEBOARD_FAB2_LIB.BASEBOARD_FAB2(SCH_1):PAGE139',
 WATTAGE='1/16W',
 TOLERANCE='1.0%',
 SEC_TYPE='0402',
 MATERIAL='CHIP',
 BOM_COST='SM_CONTROLLER',
 PHYS_PAGE='139',
 XY='(-1900,2450)',
 ROT='0',
 VER='1',
 VALUE='22.1',
 PACK_TYPE='0402',
 PART_NUMBER='G21796-250',
 LOCATION='R9E17',
 ROOM='BMC',
 GROUP='NI_I210&RJ45',
 SEC='1',
 CDS_LIB='mstr_discrete',
 CDS_PART_NAME='RES_0402-22.1,1.0%,1/16W,CHIP,A',
 PRIM_FILE='./archive_libs/mstr_discrete/res/chips/chips.prt';

PART_NAME
 R9E18 'RES_0402-0.0,5%,1/16W,CHIP,G21A':
 GROUP='NI_I210&RJ45',
 ROOM='NIC_SPRV';

SECTION_NUMBER 1
 '@BASEBOARD_FAB2_LIB.BASEBOARD_FAB2(SCH_1):PAGE139_I201@MSTR_DISCRETE.RES(CHIPS)':
 C_PATH='@baseboard_fab2_lib.baseboard_fab2(sch_1):page139_i201@mstr_discrete.re~
s(chips)',
 P_PATH='@baseboard_fab2_lib.baseboard_fab2(sch_1):page139_i201@mstr_discrete.re~
s(chips)',
 PATH='I201',
 DRAWING='@BASEBOARD_FAB2_LIB.BASEBOARD_FAB2(SCH_1):PAGE139',
 WATTAGE='1/16W',
 TOLERANCE='5%',
 SEC_TYPE='0402',
 MATERIAL='CHIP',
 BOM_COST='NT_GBE_BASE',
 PHYS_PAGE='139',
 XY='(-6800,1575)',
 ROT='0',
 VER='1',
 VALUE='0.0',
 PACK_TYPE='0402',
 PART_NUMBER='G21497-005',
 LOCATION='R9E18',
 ROOM='NIC_SPRV',
 GROUP='NI_I210&RJ45',
 SEC='1',
 CDS_LIB='mstr_discrete',
 CDS_PART_NAME='RES_0402-0.0,5%,1/16W,CHIP,G21A',
 PRIM_FILE='./archive_libs/mstr_discrete/res/chips/chips.prt';

PART_NAME
 R9E19 'RES_0402-22.1,1.0%,1/16W,CHIP,A':
 GROUP='NI_I210&RJ45',
 ROOM='BMC';

SECTION_NUMBER 1
 '@BASEBOARD_FAB2_LIB.BASEBOARD_FAB2(SCH_1):PAGE139_I228@MSTR_DISCRETE.RES(CHIPS)':
 C_PATH='@baseboard_fab2_lib.baseboard_fab2(sch_1):page139_i228@mstr_discrete.re~
s(chips)',
 P_PATH='@baseboard_fab2_lib.baseboard_fab2(sch_1):page139_i228@mstr_discrete.re~
s(chips)',
 PATH='I228',
 DRAWING='@BASEBOARD_FAB2_LIB.BASEBOARD_FAB2(SCH_1):PAGE139',
 WATTAGE='1/16W',
 TOLERANCE='1.0%',
 SEC_TYPE='0402',
 MATERIAL='CHIP',
 BOM_COST='SM_CONTROLLER',
 PHYS_PAGE='139',
 XY='(-2275,2525)',
 ROT='0',
 VER='1',
 VALUE='22.1',
 PACK_TYPE='0402',
 PART_NUMBER='G21796-250',
 LOCATION='R9E19',
 ROOM='BMC',
 GROUP='NI_I210&RJ45',
 SEC='1',
 CDS_LIB='mstr_discrete',
 CDS_PART_NAME='RES_0402-22.1,1.0%,1/16W,CHIP,A',
 PRIM_FILE='./archive_libs/mstr_discrete/res/chips/chips.prt';

PART_NAME
 R9E20 'RES_0402-0.0,5%,1/16W,CHIP,G21A':
 GROUP='NI_I210&RJ45',
 ROOM='NIC_SPRV';

SECTION_NUMBER 1
 '@BASEBOARD_FAB2_LIB.BASEBOARD_FAB2(SCH_1):PAGE139_I110@MSTR_DISCRETE.RES(CHIPS)':
 C_PATH='@baseboard_fab2_lib.baseboard_fab2(sch_1):page139_i110@mstr_discrete.re~
s(chips)',
 P_PATH='@baseboard_fab2_lib.baseboard_fab2(sch_1):page139_i110@mstr_discrete.re~
s(chips)',
 PATH='I110',
 DRAWING='@BASEBOARD_FAB2_LIB.BASEBOARD_FAB2(SCH_1):PAGE139',
 WATTAGE='1/16W',
 TOLERANCE='5%',
 SEC_TYPE='0402',
 MATERIAL='CHIP',
 BOM_COST='NT_GBE_BASE',
 PHYS_PAGE='139',
 XY='(-6800,1675)',
 ROT='0',
 VER='1',
 VALUE='0.0',
 PACK_TYPE='0402',
 PART_NUMBER='G21497-005',
 LOCATION='R9E20',
 ROOM='NIC_SPRV',
 GROUP='NI_I210&RJ45',
 SEC='1',
 CDS_LIB='mstr_discrete',
 CDS_PART_NAME='RES_0402-0.0,5%,1/16W,CHIP,G21A',
 PRIM_FILE='./archive_libs/mstr_discrete/res/chips/chips.prt';

PART_NAME
 R9E21 'RES_0402-4.75K,1%,1/16W,CHIP,GA':
 ROOM='BMC';

SECTION_NUMBER 1
 '@BASEBOARD_FAB2_LIB.BASEBOARD_FAB2(SCH_1):PAGE151_I173@MSTR_DISCRETE.RES(CHIPS)':
 C_PATH='@baseboard_fab2_lib.baseboard_fab2(sch_1):page151_i173@mstr_discrete.re~
s(chips)',
 P_PATH='@baseboard_fab2_lib.baseboard_fab2(sch_1):page151_i173@mstr_discrete.re~
s(chips)',
 PATH='I173',
 DRAWING='@BASEBOARD_FAB2_LIB.BASEBOARD_FAB2(SCH_1):PAGE151',
 WATTAGE='1/16W',
 TOLERANCE='1%',
 SEC_TYPE='0402',
 MATERIAL='CHIP',
 BOM_COST='SM_CONTROLLER',
 PHYS_PAGE='151',
 XY='(-1700,-300)',
 ROT='0',
 VER='2',
 VALUE='4.75K',
 PACK_TYPE='0402',
 PART_NUMBER='G21796-072',
 LOCATION='R9E21',
 ROOM='BMC',
 SEC='1',
 CDS_LIB='mstr_discrete',
 CDS_PART_NAME='RES_0402-4.75K,1%,1/16W,CHIP,GA',
 PRIM_FILE='./archive_libs/mstr_discrete/res/chips/chips.prt';

PART_NAME
 R9E22 'RES_0402-10.0K,1%,1/16W,CHIP,GA':
 GROUP='NI_I210&RJ45',
 ROOM='NIC_SPRV';

SECTION_NUMBER 1
 '@BASEBOARD_FAB2_LIB.BASEBOARD_FAB2(SCH_1):PAGE139_I181@MSTR_DISCRETE.RES(CHIPS)':
 C_PATH='@baseboard_fab2_lib.baseboard_fab2(sch_1):page139_i181@mstr_discrete.re~
s(chips)',
 P_PATH='@baseboard_fab2_lib.baseboard_fab2(sch_1):page139_i181@mstr_discrete.re~
s(chips)',
 PATH='I181',
 DRAWING='@BASEBOARD_FAB2_LIB.BASEBOARD_FAB2(SCH_1):PAGE139',
 WATTAGE='1/16W',
 TOLERANCE='1%',
 SEC_TYPE='0402',
 MATERIAL='CHIP',
 BOM_COST='NT_GBE_BASE',
 PHYS_PAGE='139',
 XY='(-1500,2825)',
 ROT='0',
 VER='1',
 VALUE='10.0K',
 PACK_TYPE='0402',
 PART_NUMBER='G21796-016',
 LOCATION='R9E22',
 ROOM='NIC_SPRV',
 GROUP='NI_I210&RJ45',
 SEC='1',
 CDS_LIB='mstr_discrete',
 CDS_PART_NAME='RES_0402-10.0K,1%,1/16W,CHIP,GA',
 PRIM_FILE='./archive_libs/mstr_discrete/res/chips/chips.prt';

PART_NAME
 R9E23 'RES_0402-4.99K,1%,1/16W,CHIP,GA':
 GROUP='NI_I210&RJ45',
 ROOM='NIC_SPRV';

SECTION_NUMBER 1
 '@BASEBOARD_FAB2_LIB.BASEBOARD_FAB2(SCH_1):PAGE139_I174@MSTR_DISCRETE.RES(CHIPS)':
 C_PATH='@baseboard_fab2_lib.baseboard_fab2(sch_1):page139_i174@mstr_discrete.re~
s(chips)',
 P_PATH='@baseboard_fab2_lib.baseboard_fab2(sch_1):page139_i174@mstr_discrete.re~
s(chips)',
 PATH='I174',
 DRAWING='@BASEBOARD_FAB2_LIB.BASEBOARD_FAB2(SCH_1):PAGE139',
 WATTAGE='1/16W',
 TOLERANCE='1%',
 SEC_TYPE='0402',
 MATERIAL='CHIP',
 BOM_COST='NT_GBE_BASE',
 PHYS_PAGE='139',
 XY='(-900,3225)',
 ROT='0',
 VER='2',
 VALUE='4.99K',
 PACK_TYPE='0402',
 PART_NUMBER='G21796-013',
 LOCATION='R9E23',
 ROOM='NIC_SPRV',
 GROUP='NI_I210&RJ45',
 SEC='1',
 CDS_LIB='mstr_discrete',
 CDS_PART_NAME='RES_0402-4.99K,1%,1/16W,CHIP,GA',
 PRIM_FILE='./archive_libs/mstr_discrete/res/chips/chips.prt';

PART_NAME
 R9E24 'RES_0402-221,1.0%,1/16W,CHIP,GA':
 ROOM='BMC';

SECTION_NUMBER 1
 '@BASEBOARD_FAB2_LIB.BASEBOARD_FAB2(SCH_1):PAGE151_I138@MSTR_DISCRETE.RES(CHIPS)':
 C_PATH='@baseboard_fab2_lib.baseboard_fab2(sch_1):page151_i138@mstr_discrete.re~
s(chips)',
 P_PATH='@baseboard_fab2_lib.baseboard_fab2(sch_1):page151_i138@mstr_discrete.re~
s(chips)',
 PATH='I138',
 DRAWING='@BASEBOARD_FAB2_LIB.BASEBOARD_FAB2(SCH_1):PAGE151',
 WATTAGE='1/16W',
 TOLERANCE='1.0%',
 SEC_TYPE='0402',
 MATERIAL='CHIP',
 BOM_COST='SM_CONTROLLER',
 PHYS_PAGE='151',
 XY='(-300,0)',
 ROT='0',
 VER='1',
 VALUE='221',
 PACK_TYPE='0402',
 PART_NUMBER='G21796-271',
 LOCATION='R9E24',
 ROOM='BMC',
 SEC='1',
 CDS_LIB='mstr_discrete',
 CDS_PART_NAME='RES_0402-221,1.0%,1/16W,CHIP,GA',
 PRIM_FILE='./archive_libs/mstr_discrete/res/chips/chips.prt';

PART_NAME
 R9F1 'RES_0402-22.1,1.0%,1/16W,CHIP,A':
 GROUP='NI_I210&RJ45';

SECTION_NUMBER 1
 '@BASEBOARD_FAB2_LIB.BASEBOARD_FAB2(SCH_1):PAGE139_I225@MSTR_DISCRETE.RES(CHIPS)':
 C_PATH='@baseboard_fab2_lib.baseboard_fab2(sch_1):page139_i225@mstr_discrete.re~
s(chips)',
 P_PATH='@baseboard_fab2_lib.baseboard_fab2(sch_1):page139_i225@mstr_discrete.re~
s(chips)',
 PATH='I225',
 DRAWING='@BASEBOARD_FAB2_LIB.BASEBOARD_FAB2(SCH_1):PAGE139',
 WATTAGE='1/16W',
 TOLERANCE='1.0%',
 MATERIAL='CHIP',
 PHYS_PAGE='139',
 XY='(-2400,2675)',
 ROT='0',
 VER='1',
 VALUE='22.1',
 PACK_TYPE='0402',
 PART_NUMBER='G21796-250',
 LOCATION='R9F1',
 GROUP='NI_I210&RJ45',
 CDS_LIB='mstr_discrete',
 CDS_PART_NAME='RES_0402-22.1,1.0%,1/16W,CHIP,A',
 PRIM_FILE='./archive_libs/mstr_discrete/res/chips/chips.prt';

PART_NAME
 R9F3 'RES_0402-4.75K,1%,1/16W,CHIP,GA':
 ROOM='PROC_SIDEBAND';

SECTION_NUMBER 1
 '@BASEBOARD_FAB2_LIB.BASEBOARD_FAB2(SCH_1):PAGE170_I65@MSTR_DISCRETE.RES(CHIPS)':
 C_PATH='@baseboard_fab2_lib.baseboard_fab2(sch_1):page170_i65@mstr_discrete.res~
(chips)',
 P_PATH='@baseboard_fab2_lib.baseboard_fab2(sch_1):page170_i65@mstr_discrete.res~
(chips)',
 PATH='I65',
 DRAWING='@BASEBOARD_FAB2_LIB.BASEBOARD_FAB2(SCH_1):PAGE170',
 WATTAGE='1/16W',
 TOLERANCE='1%',
 SEC_TYPE='0402',
 MATERIAL='CHIP',
 BOM_COST='PROC_SIDEBAND',
 PHYS_PAGE='170',
 XY='(-2950,2775)',
 ROT='0',
 VER='2',
 VALUE='4.75K',
 PACK_TYPE='0402',
 PART_NUMBER='G21796-072',
 LOCATION='R9F3',
 ROOM='PROC_SIDEBAND',
 SEC='1',
 CDS_LIB='mstr_discrete',
 CDS_PART_NAME='RES_0402-4.75K,1%,1/16W,CHIP,GA',
 PRIM_FILE='./archive_libs/mstr_discrete/res/chips/chips.prt';

PART_NAME
 R9F5 'RES_0402-3.32K,1%,1/16W,CHIP,GA':
 GROUP='NI_I210&RJ45',
 ROOM='NIC_SPRV';

SECTION_NUMBER 1
 '@BASEBOARD_FAB2_LIB.BASEBOARD_FAB2(SCH_1):PAGE139_I173@MSTR_DISCRETE.RES(CHIPS)':
 C_PATH='@baseboard_fab2_lib.baseboard_fab2(sch_1):page139_i173@mstr_discrete.re~
s(chips)',
 P_PATH='@baseboard_fab2_lib.baseboard_fab2(sch_1):page139_i173@mstr_discrete.re~
s(chips)',
 PATH='I173',
 DRAWING='@BASEBOARD_FAB2_LIB.BASEBOARD_FAB2(SCH_1):PAGE139',
 WATTAGE='1/16W',
 TOLERANCE='1%',
 MATERIAL='CHIP',
 BOM_COST='NT_GBE_BASE',
 PHYS_PAGE='139',
 XY='(-900,3825)',
 ROT='0',
 VER='2',
 VALUE='3.32K',
 PACK_TYPE='0402',
 PART_NUMBER='G21796-027',
 LOCATION='R9F5',
 ROOM='NIC_SPRV',
 GROUP='NI_I210&RJ45',
 CDS_LIB='mstr_discrete',
 CDS_PART_NAME='RES_0402-3.32K,1%,1/16W,CHIP,GA',
 PRIM_FILE='./archive_libs/mstr_discrete/res/chips/chips.prt';

PART_NAME
 R9F6 '4K42R2F-GP_SMD-RG-4K42R2F-GP,6A':;

SECTION_NUMBER 1
 '@BASEBOARD_FAB2_LIB.BASEBOARD_FAB2(SCH_1):PAGE238_I45@W_HDL.4K42R2F-GP(CHIPS)':
 C_PATH='@baseboard_fab2_lib.baseboard_fab2(sch_1):page238_i45@w_hdl.\4k42r2f-gp~
\(chips)',
 P_PATH='@baseboard_fab2_lib.baseboard_fab2(sch_1):page238_i45@w_hdl.\4k42r2f-gp~
\(chips)',
 PATH='I45',
 DRAWING='@BASEBOARD_FAB2_LIB.BASEBOARD_FAB2(SCH_1):PAGE238',
 PACK_SIZE='0402',
 RATED='1/16W',
 ATTRIBUTE='4.42KOHM',
 TOLERANCE='1%',
 PHYS_PAGE='238',
 XY='(1025,2475)',
 ROT='0',
 VER='1',
 VALUE='4K42R2F-GP',
 PACK_TYPE='SMD-RG',
 PART_NUMBER='64.44215.6DL',
 LOCATION='R9F6',
 CDS_LIB='w_hdl',
 CDS_PART_NAME='4K42R2F-GP_SMD-RG-4K42R2F-GP,6A',
 PRIM_FILE='C:/<user>/w_hdl/4k42r2f#2dgp/chips/chips.prt';

PART_NAME
 R9F8 'RES_0402-10.0K,1%,1/16W,CHIP,GA':
 ROOM='P1V26_BMC_STBY_VR';

SECTION_NUMBER 1
 '@BASEBOARD_FAB2_LIB.BASEBOARD_FAB2(SCH_1):PAGE238_I14@MSTR_DISCRETE.RES(CHIPS)':
 C_PATH='@baseboard_fab2_lib.baseboard_fab2(sch_1):page238_i14@mstr_discrete.res~
(chips)',
 P_PATH='@baseboard_fab2_lib.baseboard_fab2(sch_1):page238_i14@mstr_discrete.res~
(chips)',
 PATH='I14',
 DRAWING='@BASEBOARD_FAB2_LIB.BASEBOARD_FAB2(SCH_1):PAGE238',
 P1V5_STBY_IBMC_VR='',
 P1V5_STBY_IBMC='',
 WATTAGE='1/16W',
 TOLERANCE='1%',
 SEC_TYPE='0402',
 MATERIAL='CHIP',
 BOM_COST='P1V26_BMC_STBY_VR',
 PHYS_PAGE='238',
 XY='(1025,2100)',
 ROT='1',
 VER='1',
 VALUE='10.0K',
 PACK_TYPE='0402',
 PART_NUMBER='G21796-016',
 LOCATION='R9F8',
 ROOM='P1V26_BMC_STBY_VR',
 SEC='1',
 CDS_LIB='mstr_discrete',
 CDS_PART_NAME='RES_0402-10.0K,1%,1/16W,CHIP,GA',
 PRIM_FILE='./archive_libs/mstr_discrete/res/chips/chips.prt';

PART_NAME
 R9F11 'RES_0402-22.1,1.0%,1/16W,CHIP,A':
 ROOM='P1V26_BMC_STBY_VR';

SECTION_NUMBER 1
 '@BASEBOARD_FAB2_LIB.BASEBOARD_FAB2(SCH_1):PAGE238_I41@MSTR_DISCRETE.RES(CHIPS)':
 C_PATH='@baseboard_fab2_lib.baseboard_fab2(sch_1):page238_i41@mstr_discrete.res~
(chips)',
 P_PATH='@baseboard_fab2_lib.baseboard_fab2(sch_1):page238_i41@mstr_discrete.res~
(chips)',
 PATH='I41',
 DRAWING='@BASEBOARD_FAB2_LIB.BASEBOARD_FAB2(SCH_1):PAGE238',
 WATTAGE='1/16W',
 TOLERANCE='1.0%',
 SEC_TYPE='0402',
 MATERIAL='CHIP',
 PHYS_PAGE='238',
 XY='(1850,3200)',
 ROT='0',
 VER='1',
 VALUE='22.1',
 PACK_TYPE='0402',
 PART_NUMBER='G21796-250',
 LOCATION='R9F11',
 ROOM='P1V26_BMC_STBY_VR',
 SEC='1',
 CDS_LIB='mstr_discrete',
 CDS_PART_NAME='RES_0402-22.1,1.0%,1/16W,CHIP,A',
 PRIM_FILE='./archive_libs/mstr_discrete/res/chips/chips.prt';

PART_NAME
 R9F12 'RES_0402-10.0K,1%,1/16W,CHIP,GA':
 ROOM='P1V538_BMC_STBY_VR';

SECTION_NUMBER 1
 '@BASEBOARD_FAB2_LIB.BASEBOARD_FAB2(SCH_1):PAGE239_I6@MSTR_DISCRETE.RES(CHIPS)':
 C_PATH='@baseboard_fab2_lib.baseboard_fab2(sch_1):page239_i6@mstr_discrete.res(~
chips)',
 P_PATH='@baseboard_fab2_lib.baseboard_fab2(sch_1):page239_i6@mstr_discrete.res(~
chips)',
 PATH='I6',
 DRAWING='@BASEBOARD_FAB2_LIB.BASEBOARD_FAB2(SCH_1):PAGE239',
 P1V5_STBY_IBMC_VR='',
 P1V5_STBY_IBMC='',
 WATTAGE='1/16W',
 TOLERANCE='1%',
 SEC_TYPE='0402',
 MATERIAL='CHIP',
 BOM_COST='P1V538_BMC_STBY_VR',
 PHYS_PAGE='239',
 XY='(9625,4525)',
 ROT='0',
 VER='2',
 VALUE='10.0K',
 PACK_TYPE='0402',
 PART_NUMBER='G21796-016',
 LOCATION='R9F12',
 ROOM='P1V538_BMC_STBY_VR',
 SEC='1',
 CDS_LIB='mstr_discrete',
 CDS_PART_NAME='RES_0402-10.0K,1%,1/16W,CHIP,GA',
 PRIM_FILE='./archive_libs/mstr_discrete/res/chips/chips.prt';

PART_NAME
 R9F13 'RES_0402-10.0K,1%,1/16W,CHIP,GA':
 ROOM='P1V26_BMC_STBY_VR';

SECTION_NUMBER 1
 '@BASEBOARD_FAB2_LIB.BASEBOARD_FAB2(SCH_1):PAGE238_I21@MSTR_DISCRETE.RES(CHIPS)':
 C_PATH='@baseboard_fab2_lib.baseboard_fab2(sch_1):page238_i21@mstr_discrete.res~
(chips)',
 P_PATH='@baseboard_fab2_lib.baseboard_fab2(sch_1):page238_i21@mstr_discrete.res~
(chips)',
 PATH='I21',
 DRAWING='@BASEBOARD_FAB2_LIB.BASEBOARD_FAB2(SCH_1):PAGE238',
 P1V5_STBY_IBMC_VR='',
 P1V5_STBY_IBMC='',
 WATTAGE='1/16W',
 TOLERANCE='1%',
 SEC_TYPE='0402',
 MATERIAL='CHIP',
 BOM_COST='P1V26_BMC_STBY_VR',
 PHYS_PAGE='238',
 XY='(900,3500)',
 ROT='0',
 VER='2',
 VALUE='10.0K',
 PACK_TYPE='0402',
 PART_NUMBER='G21796-016',
 LOCATION='R9F13',
 ROOM='P1V26_BMC_STBY_VR',
 SEC='1',
 CDS_LIB='mstr_discrete',
 CDS_PART_NAME='RES_0402-10.0K,1%,1/16W,CHIP,GA',
 PRIM_FILE='./archive_libs/mstr_discrete/res/chips/chips.prt';

PART_NAME
 R9F20 'RES_0402-348,1%,1/16W,EMPTY,G2A':
 ROOM='BMC';

SECTION_NUMBER 1
 '@BASEBOARD_FAB2_LIB.BASEBOARD_FAB2(SCH_1):PAGE145_I22@MSTR_DISCRETE.RES(CHIPS)':
 C_PATH='@baseboard_fab2_lib.baseboard_fab2(sch_1):page145_i22@mstr_discrete.res~
(chips)',
 P_PATH='@baseboard_fab2_lib.baseboard_fab2(sch_1):page145_i22@mstr_discrete.res~
(chips)',
 PATH='I22',
 DRAWING='@BASEBOARD_FAB2_LIB.BASEBOARD_FAB2(SCH_1):PAGE145',
 WATTAGE='1/16W',
 TOLERANCE='1%',
 SEC_TYPE='0402',
 MATERIAL='EMPTY',
 BOM_COST='SM_CONTROLLER',
 PHYS_PAGE='145',
 XY='(-7650,-3425)',
 ROT='0',
 VER='2',
 VALUE='348',
 PACK_TYPE='0402',
 PART_NUMBER='G21796-340',
 LOCATION='R9F20',
 ROOM='BMC',
 SEC='1',
 CDS_LIB='mstr_discrete',
 CDS_PART_NAME='RES_0402-348,1%,1/16W,EMPTY,G2A',
 PRIM_FILE='./archive_libs/mstr_discrete/res/chips/chips.prt';

PART_NAME
 R9F22 'RES_0402-20.0,1%,1/16W,CHIP,G2A':
 ROOM='SMBUS';

SECTION_NUMBER 1
 '@BASEBOARD_FAB2_LIB.BASEBOARD_FAB2(SCH_1):PAGE160_I52@MSTR_DISCRETE.RES(CHIPS)':
 C_PATH='@baseboard_fab2_lib.baseboard_fab2(sch_1):page160_i52@mstr_discrete.res~
(chips)',
 P_PATH='@baseboard_fab2_lib.baseboard_fab2(sch_1):page160_i52@mstr_discrete.res~
(chips)',
 PATH='I52',
 DRAWING='@BASEBOARD_FAB2_LIB.BASEBOARD_FAB2(SCH_1):PAGE160',
 WATTAGE='1/16W',
 TOLERANCE='1%',
 MATERIAL='CHIP',
 BOM_COST='SM_CONTROLLER',
 PHYS_PAGE='160',
 XY='(-3350,3525)',
 ROT='0',
 VER='1',
 VALUE='20.0',
 PACK_TYPE='0402',
 PART_NUMBER='G21796-173',
 LOCATION='R9F22',
 ROOM='SMBUS',
 CDS_LIB='mstr_discrete',
 CDS_PART_NAME='RES_0402-20.0,1%,1/16W,CHIP,G2A',
 PRIM_FILE='./archive_libs/mstr_discrete/res/chips/chips.prt';

PART_NAME
 R9F23 'RES_0402-20.0,1%,1/16W,CHIP,G2A':
 ROOM='SMBUS';

SECTION_NUMBER 1
 '@BASEBOARD_FAB2_LIB.BASEBOARD_FAB2(SCH_1):PAGE160_I51@MSTR_DISCRETE.RES(CHIPS)':
 C_PATH='@baseboard_fab2_lib.baseboard_fab2(sch_1):page160_i51@mstr_discrete.res~
(chips)',
 P_PATH='@baseboard_fab2_lib.baseboard_fab2(sch_1):page160_i51@mstr_discrete.res~
(chips)',
 PATH='I51',
 DRAWING='@BASEBOARD_FAB2_LIB.BASEBOARD_FAB2(SCH_1):PAGE160',
 WATTAGE='1/16W',
 TOLERANCE='1%',
 MATERIAL='CHIP',
 BOM_COST='SM_CONTROLLER',
 PHYS_PAGE='160',
 XY='(-3350,3700)',
 ROT='0',
 VER='1',
 VALUE='20.0',
 PACK_TYPE='0402',
 PART_NUMBER='G21796-173',
 LOCATION='R9F23',
 ROOM='SMBUS',
 CDS_LIB='mstr_discrete',
 CDS_PART_NAME='RES_0402-20.0,1%,1/16W,CHIP,G2A',
 PRIM_FILE='./archive_libs/mstr_discrete/res/chips/chips.prt';

PART_NAME
 R9F24 'RES_0402-0.0,5%,1/16W,EMPTY,G2A':
 ROOM='UART_MUX';

SECTION_NUMBER 1
 '@BASEBOARD_FAB2_LIB.BASEBOARD_FAB2(SCH_1):PAGE158_I100@MSTR_DISCRETE.RES(CHIPS)':
 C_PATH='@baseboard_fab2_lib.baseboard_fab2(sch_1):page158_i100@mstr_discrete.re~
s(chips)',
 P_PATH='@baseboard_fab2_lib.baseboard_fab2(sch_1):page158_i100@mstr_discrete.re~
s(chips)',
 PATH='I100',
 DRAWING='@BASEBOARD_FAB2_LIB.BASEBOARD_FAB2(SCH_1):PAGE158',
 WATTAGE='1/16W',
 TOLERANCE='5%',
 SEC_TYPE='0402',
 MATERIAL='EMPTY',
 BOM_COST='DEBUG',
 PHYS_PAGE='158',
 XY='(-2650,1525)',
 ROT='0',
 VER='1',
 VALUE='0.0',
 PACK_TYPE='0402',
 PART_NUMBER='G21497-005',
 LOCATION='R9F24',
 ROOM='UART_MUX',
 SEC='1',
 CDS_LIB='mstr_discrete',
 CDS_PART_NAME='RES_0402-0.0,5%,1/16W,EMPTY,G2A',
 PRIM_FILE='./archive_libs/mstr_discrete/res/chips/chips.prt';

PART_NAME
 R9F25 'RES_0402-100.0,1%,1/16W,CHIP,GA':
 ROOM='UART_MUX';

SECTION_NUMBER 1
 '@BASEBOARD_FAB2_LIB.BASEBOARD_FAB2(SCH_1):PAGE158_I86@MSTR_DISCRETE.RES(CHIPS)':
 C_PATH='@baseboard_fab2_lib.baseboard_fab2(sch_1):page158_i86@mstr_discrete.res~
(chips)',
 P_PATH='@baseboard_fab2_lib.baseboard_fab2(sch_1):page158_i86@mstr_discrete.res~
(chips)',
 PATH='I86',
 DRAWING='@BASEBOARD_FAB2_LIB.BASEBOARD_FAB2(SCH_1):PAGE158',
 WATTAGE='1/16W',
 TOLERANCE='1%',
 SEC_TYPE='0402',
 MATERIAL='CHIP',
 BOM_COST='DEBUG',
 PHYS_PAGE='158',
 XY='(-3625,900)',
 ROT='0',
 VER='1',
 VALUE='100.0',
 PACK_TYPE='0402',
 PART_NUMBER='G21796-017',
 LOCATION='R9F25',
 ROOM='UART_MUX',
 SEC='1',
 CDS_LIB='mstr_discrete',
 CDS_PART_NAME='RES_0402-100.0,1%,1/16W,CHIP,GA',
 PRIM_FILE='./archive_libs/mstr_discrete/res/chips/chips.prt';

PART_NAME
 R9F26 'RES_0402-0.0,5%,1/16W,EMPTY,G2A':
 ROOM='UART_MUX';

SECTION_NUMBER 1
 '@BASEBOARD_FAB2_LIB.BASEBOARD_FAB2(SCH_1):PAGE158_I99@MSTR_DISCRETE.RES(CHIPS)':
 C_PATH='@baseboard_fab2_lib.baseboard_fab2(sch_1):page158_i99@mstr_discrete.res~
(chips)',
 P_PATH='@baseboard_fab2_lib.baseboard_fab2(sch_1):page158_i99@mstr_discrete.res~
(chips)',
 PATH='I99',
 DRAWING='@BASEBOARD_FAB2_LIB.BASEBOARD_FAB2(SCH_1):PAGE158',
 WATTAGE='1/16W',
 TOLERANCE='5%',
 SEC_TYPE='0402',
 MATERIAL='EMPTY',
 BOM_COST='DEBUG',
 PHYS_PAGE='158',
 XY='(-1900,3450)',
 ROT='0',
 VER='1',
 VALUE='0.0',
 PACK_TYPE='0402',
 PART_NUMBER='G21497-005',
 LOCATION='R9F26',
 ROOM='UART_MUX',
 SEC='1',
 CDS_LIB='mstr_discrete',
 CDS_PART_NAME='RES_0402-0.0,5%,1/16W,EMPTY,G2A',
 PRIM_FILE='./archive_libs/mstr_discrete/res/chips/chips.prt';

PART_NAME
 R9F27 'RES_0402-0.0,5%,1/16W,CHIP,G21A':
 ROOM='UART_MUX';

SECTION_NUMBER 1
 '@BASEBOARD_FAB2_LIB.BASEBOARD_FAB2(SCH_1):PAGE158_I91@MSTR_DISCRETE.RES(CHIPS)':
 C_PATH='@baseboard_fab2_lib.baseboard_fab2(sch_1):page158_i91@mstr_discrete.res~
(chips)',
 P_PATH='@baseboard_fab2_lib.baseboard_fab2(sch_1):page158_i91@mstr_discrete.res~
(chips)',
 PATH='I91',
 DRAWING='@BASEBOARD_FAB2_LIB.BASEBOARD_FAB2(SCH_1):PAGE158',
 WATTAGE='1/16W',
 TOLERANCE='5%',
 SEC_TYPE='0402',
 MATERIAL='CHIP',
 BOM_COST='DEBUG',
 PHYS_PAGE='158',
 XY='(-1325,2625)',
 ROT='0',
 VER='1',
 VALUE='0.0',
 PACK_TYPE='0402',
 PART_NUMBER='G21497-005',
 LOCATION='R9F27',
 ROOM='UART_MUX',
 SEC='1',
 CDS_LIB='mstr_discrete',
 CDS_PART_NAME='RES_0402-0.0,5%,1/16W,CHIP,G21A',
 PRIM_FILE='./archive_libs/mstr_discrete/res/chips/chips.prt';

PART_NAME
 R9F28 'RES_0402-221,1.0%,1/16W,CHIP,GA':
 ROOM='BMC';

SECTION_NUMBER 1
 '@BASEBOARD_FAB2_LIB.BASEBOARD_FAB2(SCH_1):PAGE177_I72@MSTR_DISCRETE.RES(CHIPS)':
 C_PATH='@baseboard_fab2_lib.baseboard_fab2(sch_1):page177_i72@mstr_discrete.res~
(chips)',
 P_PATH='@baseboard_fab2_lib.baseboard_fab2(sch_1):page177_i72@mstr_discrete.res~
(chips)',
 PATH='I72',
 DRAWING='@BASEBOARD_FAB2_LIB.BASEBOARD_FAB2(SCH_1):PAGE177',
 WATTAGE='1/16W',
 TOLERANCE='1.0%',
 SEC_TYPE='0402',
 MATERIAL='CHIP',
 BOM_COST='SM_CONTROLLER',
 PHYS_PAGE='177',
 XY='(-7200,8825)',
 ROT='0',
 VER='2',
 VALUE='221',
 PACK_TYPE='0402',
 PART_NUMBER='G21796-271',
 LOCATION='R9F28',
 ROOM='BMC',
 SEC='1',
 CDS_LIB='mstr_discrete',
 CDS_PART_NAME='RES_0402-221,1.0%,1/16W,CHIP,GA',
 PRIM_FILE='./archive_libs/mstr_discrete/res/chips/chips.prt';

PART_NAME
 R9F29 'RES_0402-4.75K,1%,1/16W,CHIP,GA':
 ROOM='BMC_MEMORY';

SECTION_NUMBER 1
 '@BASEBOARD_FAB2_LIB.BASEBOARD_FAB2(SCH_1):PAGE151_I55@MSTR_DISCRETE.RES(CHIPS)':
 C_PATH='@baseboard_fab2_lib.baseboard_fab2(sch_1):page151_i55@mstr_discrete.res~
(chips)',
 P_PATH='@baseboard_fab2_lib.baseboard_fab2(sch_1):page151_i55@mstr_discrete.res~
(chips)',
 PATH='I55',
 DRAWING='@BASEBOARD_FAB2_LIB.BASEBOARD_FAB2(SCH_1):PAGE151',
 POP='NOPOP',
 WATTAGE='1/16W',
 TOLERANCE='1%',
 SEC_TYPE='0402',
 MATERIAL='CHIP',
 BOM_COST='SM_MEM',
 PHYS_PAGE='151',
 XY='(2775,2150)',
 ROT='0',
 VER='2',
 VALUE='4.75K',
 PACK_TYPE='0402',
 PART_NUMBER='G21796-072',
 LOCATION='R9F29',
 ROOM='BMC_MEMORY',
 SEC='1',
 CDS_LIB='mstr_discrete',
 CDS_PART_NAME='RES_0402-4.75K,1%,1/16W,CHIP,GA',
 PRIM_FILE='./archive_libs/mstr_discrete/res/chips/chips.prt';

PART_NAME
 R9F30 'RES_0402-4.75K,1%,1/16W,CHIP,GA':
 ROOM='BMC';

SECTION_NUMBER 1
 '@BASEBOARD_FAB2_LIB.BASEBOARD_FAB2(SCH_1):PAGE177_I76@MSTR_DISCRETE.RES(CHIPS)':
 C_PATH='@baseboard_fab2_lib.baseboard_fab2(sch_1):page177_i76@mstr_discrete.res~
(chips)',
 P_PATH='@baseboard_fab2_lib.baseboard_fab2(sch_1):page177_i76@mstr_discrete.res~
(chips)',
 PATH='I76',
 DRAWING='@BASEBOARD_FAB2_LIB.BASEBOARD_FAB2(SCH_1):PAGE177',
 WATTAGE='1/16W',
 TOLERANCE='1%',
 SEC_TYPE='0402',
 MATERIAL='CHIP',
 BOM_COST='SM_CONTROLLER',
 PHYS_PAGE='177',
 XY='(-8800,7850)',
 ROT='0',
 VER='2',
 VALUE='4.75K',
 PACK_TYPE='0402',
 PART_NUMBER='G21796-072',
 LOCATION='R9F30',
 ROOM='BMC',
 SEC='1',
 CDS_LIB='mstr_discrete',
 CDS_PART_NAME='RES_0402-4.75K,1%,1/16W,CHIP,GA',
 PRIM_FILE='./archive_libs/mstr_discrete/res/chips/chips.prt';

PART_NAME
 R9F31 '5K1R2F-2-GP_SMD-RG-5K1R2F-2-GPA':;

SECTION_NUMBER 1
 '@BASEBOARD_FAB2_LIB.BASEBOARD_FAB2(SCH_1):PAGE239_I98@W_HDL.5K1R2F-2-GP(CHIPS)':
 C_PATH='@baseboard_fab2_lib.baseboard_fab2(sch_1):page239_i98@w_hdl.\5k1r2f-2-g~
p\(chips)',
 P_PATH='@baseboard_fab2_lib.baseboard_fab2(sch_1):page239_i98@w_hdl.\5k1r2f-2-g~
p\(chips)',
 PATH='I98',
 DRAWING='@BASEBOARD_FAB2_LIB.BASEBOARD_FAB2(SCH_1):PAGE239',
 PACK_SIZE='0402',
 RATED='1/16W',
 ATTRIBUTE='5.1KOHM',
 TOLERANCE='1%',
 PHYS_PAGE='239',
 XY='(10350,3525)',
 ROT='0',
 VER='1',
 VALUE='5K1R2F-2-GP',
 PACK_TYPE='SMD-RG',
 PART_NUMBER='64.51015.6DL',
 LOCATION='R9F31',
 CDS_LIB='w_hdl',
 CDS_PART_NAME='5K1R2F-2-GP_SMD-RG-5K1R2F-2-GPA',
 PRIM_FILE='C:/<user>/w_hdl/5k1r2f#2d2#2dgp/chips/chips.prt';

PART_NAME
 R9F32 'RES_0402-10.0K,1%,1/16W,CHIP,GA':
 ROOM='CPU0';

SECTION_NUMBER 1
 '@BASEBOARD_FAB2_LIB.BASEBOARD_FAB2(SCH_1):PAGE239_I100@MSTR_DISCRETE.RES(CHIPS)':
 C_PATH='@baseboard_fab2_lib.baseboard_fab2(sch_1):page239_i100@mstr_discrete.re~
s(chips)',
 P_PATH='@baseboard_fab2_lib.baseboard_fab2(sch_1):page239_i100@mstr_discrete.re~
s(chips)',
 PATH='I100',
 DRAWING='@BASEBOARD_FAB2_LIB.BASEBOARD_FAB2(SCH_1):PAGE239',
 WATTAGE='1/16W',
 TOLERANCE='1%',
 SEC_TYPE='0402',
 MATERIAL='CHIP',
 BOM_COST='PROC_SIDEBAND',
 PHYS_PAGE='239',
 XY='(10350,3075)',
 ROT='0',
 VER='2',
 VALUE='10.0K',
 PACK_TYPE='0402',
 PART_NUMBER='G21796-016',
 LOCATION='R9F32',
 ROOM='CPU0',
 SEC='1',
 CDS_LIB='mstr_discrete',
 CDS_PART_NAME='RES_0402-10.0K,1%,1/16W,CHIP,GA',
 PRIM_FILE='./archive_libs/mstr_discrete/res/chips/chips.prt';

PART_NAME
 R9F33 'RES_0402-0.0,5%,1/16W,CHIP,G21A':
 ROOM='BMC';

SECTION_NUMBER 1
 '@BASEBOARD_FAB2_LIB.BASEBOARD_FAB2(SCH_1):PAGE145_I20@MSTR_DISCRETE.RES(CHIPS)':
 C_PATH='@baseboard_fab2_lib.baseboard_fab2(sch_1):page145_i20@mstr_discrete.res~
(chips)',
 P_PATH='@baseboard_fab2_lib.baseboard_fab2(sch_1):page145_i20@mstr_discrete.res~
(chips)',
 PATH='I20',
 DRAWING='@BASEBOARD_FAB2_LIB.BASEBOARD_FAB2(SCH_1):PAGE145',
 WATTAGE='1/16W',
 TOLERANCE='5%',
 SEC_TYPE='0402',
 MATERIAL='CHIP',
 BOM_COST='SM_CONTROLLER',
 PHYS_PAGE='145',
 XY='(-6450,-3250)',
 ROT='0',
 VER='1',
 VALUE='0.0',
 PACK_TYPE='0402',
 PART_NUMBER='G21497-005',
 LOCATION='R9F33',
 ROOM='BMC',
 SEC='1',
 CDS_LIB='mstr_discrete',
 CDS_PART_NAME='RES_0402-0.0,5%,1/16W,CHIP,G21A',
 PRIM_FILE='./archive_libs/mstr_discrete/res/chips/chips.prt';

PART_NAME
 R9F34 'RES_0402-33.2,1%,1/16W,EMPTY,GA':
 ROOM='DEBUG';

SECTION_NUMBER 1
 '@BASEBOARD_FAB2_LIB.BASEBOARD_FAB2(SCH_1):PAGE151_I209@MSTR_DISCRETE.RES(CHIPS)':
 C_PATH='@baseboard_fab2_lib.baseboard_fab2(sch_1):page151_i209@mstr_discrete.re~
s(chips)',
 P_PATH='@baseboard_fab2_lib.baseboard_fab2(sch_1):page151_i209@mstr_discrete.re~
s(chips)',
 PATH='I209',
 DRAWING='@BASEBOARD_FAB2_LIB.BASEBOARD_FAB2(SCH_1):PAGE151',
 WATTAGE='1/16W',
 TOLERANCE='1%',
 SEC_TYPE='0402',
 MATERIAL='EMPTY',
 PHYS_PAGE='151',
 XY='(3125,1975)',
 ROT='1',
 VER='2',
 VALUE='33.2',
 PACK_TYPE='0402',
 PART_NUMBER='G21796-074',
 LOCATION='R9F34',
 ROOM='DEBUG',
 SEC='1',
 CDS_LIB='mstr_discrete',
 CDS_PART_NAME='RES_0402-33.2,1%,1/16W,EMPTY,GA',
 PRIM_FILE='./archive_libs/mstr_discrete/res/chips/chips.prt';

PART_NAME
 R9F52 'RES_0402-4.75K,1%,1/16W,CHIP,GA':
 ROOM='BMC';

SECTION_NUMBER 1
 '@BASEBOARD_FAB2_LIB.BASEBOARD_FAB2(SCH_1):PAGE177_I82@MSTR_DISCRETE.RES(CHIPS)':
 C_PATH='@baseboard_fab2_lib.baseboard_fab2(sch_1):page177_i82@mstr_discrete.res~
(chips)',
 P_PATH='@baseboard_fab2_lib.baseboard_fab2(sch_1):page177_i82@mstr_discrete.res~
(chips)',
 PATH='I82',
 DRAWING='@BASEBOARD_FAB2_LIB.BASEBOARD_FAB2(SCH_1):PAGE177',
 WATTAGE='1/16W',
 TOLERANCE='1%',
 SEC_TYPE='0402',
 MATERIAL='CHIP',
 BOM_COST='SM_CONTROLLER',
 PHYS_PAGE='177',
 XY='(-8125,8225)',
 ROT='0',
 VER='2',
 VALUE='4.75K',
 PACK_TYPE='0402',
 PART_NUMBER='G21796-072',
 LOCATION='R9F52',
 ROOM='BMC',
 SEC='1',
 CDS_LIB='mstr_discrete',
 CDS_PART_NAME='RES_0402-4.75K,1%,1/16W,CHIP,GA',
 PRIM_FILE='./archive_libs/mstr_discrete/res/chips/chips.prt';

PART_NAME
 R9F55 'RES_0402-4.75K,1%,1/16W,CHIP,GA':
 ROOM='LBG';

SECTION_NUMBER 1
 '@BASEBOARD_FAB2_LIB.BASEBOARD_FAB2(SCH_1):PAGE183_I3@MSTR_DISCRETE.RES(CHIPS)':
 C_PATH='@baseboard_fab2_lib.baseboard_fab2(sch_1):page183_i3@mstr_discrete.res(~
chips)',
 P_PATH='@baseboard_fab2_lib.baseboard_fab2(sch_1):page183_i3@mstr_discrete.res(~
chips)',
 PATH='I3',
 DRAWING='@BASEBOARD_FAB2_LIB.BASEBOARD_FAB2(SCH_1):PAGE183',
 WATTAGE='1/16W',
 TOLERANCE='1%',
 SEC_TYPE='0402',
 MATERIAL='CHIP',
 BOM_COST='LBG_UART',
 PHYS_PAGE='183',
 XY='(3150,-400)',
 ROT='0',
 VER='2',
 VALUE='4.75K',
 PACK_TYPE='0402',
 PART_NUMBER='G21796-072',
 LOCATION='R9F55',
 ROOM='LBG',
 SEC='1',
 CDS_LIB='mstr_discrete',
 CDS_PART_NAME='RES_0402-4.75K,1%,1/16W,CHIP,GA',
 PRIM_FILE='./archive_libs/mstr_discrete/res/chips/chips.prt';

PART_NAME
 R9F60 'RES_0402-0.0,5%,1/16W,EMPTY,G2A':
 ROOM='BMC';

SECTION_NUMBER 1
 '@BASEBOARD_FAB2_LIB.BASEBOARD_FAB2(SCH_1):PAGE145_I10@MSTR_DISCRETE.RES(CHIPS)':
 C_PATH='@baseboard_fab2_lib.baseboard_fab2(sch_1):page145_i10@mstr_discrete.res~
(chips)',
 P_PATH='@baseboard_fab2_lib.baseboard_fab2(sch_1):page145_i10@mstr_discrete.res~
(chips)',
 PATH='I10',
 DRAWING='@BASEBOARD_FAB2_LIB.BASEBOARD_FAB2(SCH_1):PAGE145',
 WATTAGE='1/16W',
 TOLERANCE='5%',
 SEC_TYPE='0402',
 MATERIAL='EMPTY',
 BOM_COST='SM_CONTROLLER',
 PHYS_PAGE='145',
 XY='(-4450,-250)',
 ROT='0',
 VER='1',
 VALUE='0.0',
 PACK_TYPE='0402',
 PART_NUMBER='G21497-005',
 LOCATION='R9F60',
 ROOM='BMC',
 SEC='1',
 CDS_LIB='mstr_discrete',
 CDS_PART_NAME='RES_0402-0.0,5%,1/16W,EMPTY,G2A',
 PRIM_FILE='./archive_libs/mstr_discrete/res/chips/chips.prt';

PART_NAME
 R9F61 'RES_0402-10.0K,1%,1/16W,CHIP,GA':
 ROOM='BMC';

SECTION_NUMBER 1
 '@BASEBOARD_FAB2_LIB.BASEBOARD_FAB2(SCH_1):PAGE145_I14@MSTR_DISCRETE.RES(CHIPS)':
 C_PATH='@baseboard_fab2_lib.baseboard_fab2(sch_1):page145_i14@mstr_discrete.res~
(chips)',
 P_PATH='@baseboard_fab2_lib.baseboard_fab2(sch_1):page145_i14@mstr_discrete.res~
(chips)',
 PATH='I14',
 DRAWING='@BASEBOARD_FAB2_LIB.BASEBOARD_FAB2(SCH_1):PAGE145',
 WATTAGE='1/16W',
 TOLERANCE='1%',
 SEC_TYPE='0402',
 MATERIAL='CHIP',
 BOM_COST='SM_CONTROLLER',
 PHYS_PAGE='145',
 XY='(-7000,-475)',
 ROT='0',
 VER='2',
 VALUE='10.0K',
 PACK_TYPE='0402',
 PART_NUMBER='G21796-016',
 LOCATION='R9F61',
 ROOM='BMC',
 SEC='1',
 CDS_LIB='mstr_discrete',
 CDS_PART_NAME='RES_0402-10.0K,1%,1/16W,CHIP,GA',
 PRIM_FILE='./archive_libs/mstr_discrete/res/chips/chips.prt';

PART_NAME
 R9F62 'RES_0402-0.0,5%,1/16W,CHIP,G21A':
 ROOM='BMC';

SECTION_NUMBER 1
 '@BASEBOARD_FAB2_LIB.BASEBOARD_FAB2(SCH_1):PAGE145_I11@MSTR_DISCRETE.RES(CHIPS)':
 C_PATH='@baseboard_fab2_lib.baseboard_fab2(sch_1):page145_i11@mstr_discrete.res~
(chips)',
 P_PATH='@baseboard_fab2_lib.baseboard_fab2(sch_1):page145_i11@mstr_discrete.res~
(chips)',
 PATH='I11',
 DRAWING='@BASEBOARD_FAB2_LIB.BASEBOARD_FAB2(SCH_1):PAGE145',
 WATTAGE='1/16W',
 TOLERANCE='5%',
 SEC_TYPE='0402',
 MATERIAL='CHIP',
 BOM_COST='SM_CONTROLLER',
 PHYS_PAGE='145',
 XY='(-4450,-550)',
 ROT='0',
 VER='1',
 VALUE='0.0',
 PACK_TYPE='0402',
 PART_NUMBER='G21497-005',
 LOCATION='R9F62',
 ROOM='BMC',
 SEC='1',
 CDS_LIB='mstr_discrete',
 CDS_PART_NAME='RES_0402-0.0,5%,1/16W,CHIP,G21A',
 PRIM_FILE='./archive_libs/mstr_discrete/res/chips/chips.prt';

PART_NAME
 R9F63 'RES_0402-0.0,5%,1/16W,EMPTY,G2A':
 ROOM='UART_MUX';

SECTION_NUMBER 1
 '@BASEBOARD_FAB2_LIB.BASEBOARD_FAB2(SCH_1):PAGE181_I28@MSTR_DISCRETE.RES(CHIPS)':
 C_PATH='@baseboard_fab2_lib.baseboard_fab2(sch_1):page181_i28@mstr_discrete.res~
(chips)',
 P_PATH='@baseboard_fab2_lib.baseboard_fab2(sch_1):page181_i28@mstr_discrete.res~
(chips)',
 PATH='I28',
 DRAWING='@BASEBOARD_FAB2_LIB.BASEBOARD_FAB2(SCH_1):PAGE181',
 WATTAGE='1/16W',
 TOLERANCE='5%',
 SEC_TYPE='0402',
 MATERIAL='EMPTY',
 PHYS_PAGE='181',
 XY='(-2125,3100)',
 ROT='0',
 VER='1',
 VALUE='0.0',
 PACK_TYPE='0402',
 PART_NUMBER='G21497-005',
 LOCATION='R9F63',
 ROOM='UART_MUX',
 SEC='1',
 CDS_LIB='mstr_discrete',
 CDS_PART_NAME='RES_0402-0.0,5%,1/16W,EMPTY,G2A',
 PRIM_FILE='./archive_libs/mstr_discrete/res/chips/chips.prt';

PART_NAME
 R9F64 'RES_0402-0.0,5%,1/16W,CHIP,G21A':
 ROOM='UART_MUX';

SECTION_NUMBER 1
 '@BASEBOARD_FAB2_LIB.BASEBOARD_FAB2(SCH_1):PAGE181_I29@MSTR_DISCRETE.RES(CHIPS)':
 C_PATH='@baseboard_fab2_lib.baseboard_fab2(sch_1):page181_i29@mstr_discrete.res~
(chips)',
 P_PATH='@baseboard_fab2_lib.baseboard_fab2(sch_1):page181_i29@mstr_discrete.res~
(chips)',
 PATH='I29',
 DRAWING='@BASEBOARD_FAB2_LIB.BASEBOARD_FAB2(SCH_1):PAGE181',
 WATTAGE='1/16W',
 TOLERANCE='5%',
 SEC_TYPE='0402',
 MATERIAL='CHIP',
 PHYS_PAGE='181',
 XY='(-2175,3550)',
 ROT='0',
 VER='1',
 VALUE='0.0',
 PACK_TYPE='0402',
 PART_NUMBER='G21497-005',
 LOCATION='R9F64',
 ROOM='UART_MUX',
 SEC='1',
 CDS_LIB='mstr_discrete',
 CDS_PART_NAME='RES_0402-0.0,5%,1/16W,CHIP,G21A',
 PRIM_FILE='./archive_libs/mstr_discrete/res/chips/chips.prt';

PART_NAME
 R9F65 'RES_0402-0.0,5%,1/16W,CHIP,G21A':
 ROOM='UART_MUX';

SECTION_NUMBER 1
 '@BASEBOARD_FAB2_LIB.BASEBOARD_FAB2(SCH_1):PAGE158_I148@MSTR_DISCRETE.RES(CHIPS)':
 C_PATH='@baseboard_fab2_lib.baseboard_fab2(sch_1):page158_i148@mstr_discrete.re~
s(chips)',
 P_PATH='@baseboard_fab2_lib.baseboard_fab2(sch_1):page158_i148@mstr_discrete.re~
s(chips)',
 PATH='I148',
 DRAWING='@BASEBOARD_FAB2_LIB.BASEBOARD_FAB2(SCH_1):PAGE158',
 WATTAGE='1/16W',
 TOLERANCE='5%',
 SEC_TYPE='0402',
 MATERIAL='CHIP',
 BOM_COST='DEBUG',
 PHYS_PAGE='158',
 XY='(-3125,3750)',
 ROT='0',
 VER='1',
 VALUE='0.0',
 PACK_TYPE='0402',
 PART_NUMBER='G21497-005',
 LOCATION='R9F65',
 ROOM='UART_MUX',
 SEC='1',
 CDS_LIB='mstr_discrete',
 CDS_PART_NAME='RES_0402-0.0,5%,1/16W,CHIP,G21A',
 PRIM_FILE='./archive_libs/mstr_discrete/res/chips/chips.prt';

PART_NAME
 R9F66 'RES_0402-0.0,5%,1/16W,EMPTY,G2A':
 ROOM='UART_MUX';

SECTION_NUMBER 1
 '@BASEBOARD_FAB2_LIB.BASEBOARD_FAB2(SCH_1):PAGE158_I152@MSTR_DISCRETE.RES(CHIPS)':
 C_PATH='@baseboard_fab2_lib.baseboard_fab2(sch_1):page158_i152@mstr_discrete.re~
s(chips)',
 P_PATH='@baseboard_fab2_lib.baseboard_fab2(sch_1):page158_i152@mstr_discrete.re~
s(chips)',
 PATH='I152',
 DRAWING='@BASEBOARD_FAB2_LIB.BASEBOARD_FAB2(SCH_1):PAGE158',
 WATTAGE='1/16W',
 TOLERANCE='5%',
 MATERIAL='EMPTY',
 BOM_COST='DEBUG',
 PHYS_PAGE='158',
 XY='(-3150,2575)',
 ROT='0',
 VER='1',
 VALUE='0.0',
 PACK_TYPE='0402',
 PART_NUMBER='G21497-005',
 LOCATION='R9F66',
 ROOM='UART_MUX',
 CDS_LIB='mstr_discrete',
 CDS_PART_NAME='RES_0402-0.0,5%,1/16W,EMPTY,G2A',
 PRIM_FILE='./archive_libs/mstr_discrete/res/chips/chips.prt';

PART_NAME
 R9F67 'RES_0402-0.0,5%,1/16W,CHIP,G21A':
 ROOM='UART_MUX';

SECTION_NUMBER 1
 '@BASEBOARD_FAB2_LIB.BASEBOARD_FAB2(SCH_1):PAGE181_I33@MSTR_DISCRETE.RES(CHIPS)':
 C_PATH='@baseboard_fab2_lib.baseboard_fab2(sch_1):page181_i33@mstr_discrete.res~
(chips)',
 P_PATH='@baseboard_fab2_lib.baseboard_fab2(sch_1):page181_i33@mstr_discrete.res~
(chips)',
 PATH='I33',
 DRAWING='@BASEBOARD_FAB2_LIB.BASEBOARD_FAB2(SCH_1):PAGE181',
 WATTAGE='1/16W',
 TOLERANCE='5%',
 MATERIAL='CHIP',
 PHYS_PAGE='181',
 XY='(-1775,3600)',
 ROT='0',
 VER='1',
 VALUE='0.0',
 PACK_TYPE='0402',
 PART_NUMBER='G21497-005',
 LOCATION='R9F67',
 ROOM='UART_MUX',
 CDS_LIB='mstr_discrete',
 CDS_PART_NAME='RES_0402-0.0,5%,1/16W,CHIP,G21A',
 PRIM_FILE='./archive_libs/mstr_discrete/res/chips/chips.prt';

PART_NAME
 R9F68 'RES_0402-0.0,5%,1/16W,EMPTY,G2A':
 ROOM='UART_MUX';

SECTION_NUMBER 1
 '@BASEBOARD_FAB2_LIB.BASEBOARD_FAB2(SCH_1):PAGE158_I149@MSTR_DISCRETE.RES(CHIPS)':
 C_PATH='@baseboard_fab2_lib.baseboard_fab2(sch_1):page158_i149@mstr_discrete.re~
s(chips)',
 P_PATH='@baseboard_fab2_lib.baseboard_fab2(sch_1):page158_i149@mstr_discrete.re~
s(chips)',
 PATH='I149',
 DRAWING='@BASEBOARD_FAB2_LIB.BASEBOARD_FAB2(SCH_1):PAGE158',
 WATTAGE='1/16W',
 TOLERANCE='5%',
 SEC_TYPE='0402',
 MATERIAL='EMPTY',
 BOM_COST='DEBUG',
 PHYS_PAGE='158',
 XY='(-1250,850)',
 ROT='0',
 VER='1',
 VALUE='0.0',
 PACK_TYPE='0402',
 PART_NUMBER='G21497-005',
 LOCATION='R9F68',
 ROOM='UART_MUX',
 SEC='1',
 CDS_LIB='mstr_discrete',
 CDS_PART_NAME='RES_0402-0.0,5%,1/16W,EMPTY,G2A',
 PRIM_FILE='./archive_libs/mstr_discrete/res/chips/chips.prt';

PART_NAME
 R9F69 'RES_0402-0.0,5%,1/16W,CHIP,G21A':
 ROOM='UART_MUX';

SECTION_NUMBER 1
 '@BASEBOARD_FAB2_LIB.BASEBOARD_FAB2(SCH_1):PAGE158_I150@MSTR_DISCRETE.RES(CHIPS)':
 C_PATH='@baseboard_fab2_lib.baseboard_fab2(sch_1):page158_i150@mstr_discrete.re~
s(chips)',
 P_PATH='@baseboard_fab2_lib.baseboard_fab2(sch_1):page158_i150@mstr_discrete.re~
s(chips)',
 PATH='I150',
 DRAWING='@BASEBOARD_FAB2_LIB.BASEBOARD_FAB2(SCH_1):PAGE158',
 WATTAGE='1/16W',
 TOLERANCE='5%',
 SEC_TYPE='0402',
 MATERIAL='CHIP',
 BOM_COST='DEBUG',
 PHYS_PAGE='158',
 XY='(-1100,1775)',
 ROT='0',
 VER='1',
 VALUE='0.0',
 PACK_TYPE='0402',
 PART_NUMBER='G21497-005',
 LOCATION='R9F69',
 ROOM='UART_MUX',
 SEC='1',
 CDS_LIB='mstr_discrete',
 CDS_PART_NAME='RES_0402-0.0,5%,1/16W,CHIP,G21A',
 PRIM_FILE='./archive_libs/mstr_discrete/res/chips/chips.prt';

PART_NAME
 R9F70 'RES_0402-0.0,5%,1/16W,EMPTY,G2A':
 ROOM='UART_MUX';

SECTION_NUMBER 1
 '@BASEBOARD_FAB2_LIB.BASEBOARD_FAB2(SCH_1):PAGE181_I30@MSTR_DISCRETE.RES(CHIPS)':
 C_PATH='@baseboard_fab2_lib.baseboard_fab2(sch_1):page181_i30@mstr_discrete.res~
(chips)',
 P_PATH='@baseboard_fab2_lib.baseboard_fab2(sch_1):page181_i30@mstr_discrete.res~
(chips)',
 PATH='I30',
 DRAWING='@BASEBOARD_FAB2_LIB.BASEBOARD_FAB2(SCH_1):PAGE181',
 WATTAGE='1/16W',
 TOLERANCE='5%',
 SEC_TYPE='0402',
 MATERIAL='EMPTY',
 PHYS_PAGE='181',
 XY='(-1750,3150)',
 ROT='0',
 VER='1',
 VALUE='0.0',
 PACK_TYPE='0402',
 PART_NUMBER='G21497-005',
 LOCATION='R9F70',
 ROOM='UART_MUX',
 SEC='1',
 CDS_LIB='mstr_discrete',
 CDS_PART_NAME='RES_0402-0.0,5%,1/16W,EMPTY,G2A',
 PRIM_FILE='./archive_libs/mstr_discrete/res/chips/chips.prt';

PART_NAME
 R9G1 'RES_0402-150.0,1%,1/16W,CHIP,GA':
 GROUP='NI_I210&RJ45',
 ROOM='NIC_SPRV';

SECTION_NUMBER 1
 '@BASEBOARD_FAB2_LIB.BASEBOARD_FAB2(SCH_1):PAGE141_I157@MSTR_DISCRETE.RES(CHIPS)':
 C_PATH='@baseboard_fab2_lib.baseboard_fab2(sch_1):page141_i157@mstr_discrete.re~
s(chips)',
 P_PATH='@baseboard_fab2_lib.baseboard_fab2(sch_1):page141_i157@mstr_discrete.re~
s(chips)',
 PATH='I157',
 DRAWING='@BASEBOARD_FAB2_LIB.BASEBOARD_FAB2(SCH_1):PAGE141',
 WATTAGE='1/16W',
 TOLERANCE='1%',
 SEC_TYPE='0402',
 MATERIAL='CHIP',
 BOM_COST='NT_GBE_BASE',
 PHYS_PAGE='141',
 XY='(-2800,1450)',
 ROT='0',
 VER='1',
 VALUE='150.0',
 PACK_TYPE='0402',
 PART_NUMBER='G21796-009',
 LOCATION='R9G1',
 ROOM='NIC_SPRV',
 GROUP='NI_I210&RJ45',
 SEC='1',
 CDS_LIB='mstr_discrete',
 CDS_PART_NAME='RES_0402-150.0,1%,1/16W,CHIP,GA',
 PRIM_FILE='./archive_libs/mstr_discrete/res/chips/chips.prt';

PART_NAME
 R9G2 'RES_0402-75,1.0%,1/16W,CHIP,G2A':
 GROUP='NI_I210&RJ45',
 ROOM='PROC_SIDEBAND';

SECTION_NUMBER 1
 '@BASEBOARD_FAB2_LIB.BASEBOARD_FAB2(SCH_1):PAGE141_I134@MSTR_DISCRETE.RES(CHIPS)':
 C_PATH='@baseboard_fab2_lib.baseboard_fab2(sch_1):page141_i134@mstr_discrete.re~
s(chips)',
 P_PATH='@baseboard_fab2_lib.baseboard_fab2(sch_1):page141_i134@mstr_discrete.re~
s(chips)',
 PATH='I134',
 DRAWING='@BASEBOARD_FAB2_LIB.BASEBOARD_FAB2(SCH_1):PAGE141',
 WATTAGE='1/16W',
 TOLERANCE='1.0%',
 MATERIAL='CHIP',
 BOM_COST='PROC',
 PHYS_PAGE='141',
 XY='(-2800,2725)',
 ROT='4',
 VER='1',
 VALUE='75',
 PACK_TYPE='0402',
 PART_NUMBER='G21796-267',
 LOCATION='R9G2',
 ROOM='PROC_SIDEBAND',
 GROUP='NI_I210&RJ45',
 CDS_LIB='mstr_discrete',
 CDS_PART_NAME='RES_0402-75,1.0%,1/16W,CHIP,G2A',
 PRIM_FILE='./archive_libs/mstr_discrete/res/chips/chips.prt';

PART_NAME
 R9G3 'RES_0402-75,1.0%,1/16W,CHIP,G2A':
 GROUP='NI_I210&RJ45',
 ROOM='PROC_SIDEBAND';

SECTION_NUMBER 1
 '@BASEBOARD_FAB2_LIB.BASEBOARD_FAB2(SCH_1):PAGE141_I135@MSTR_DISCRETE.RES(CHIPS)':
 C_PATH='@baseboard_fab2_lib.baseboard_fab2(sch_1):page141_i135@mstr_discrete.re~
s(chips)',
 P_PATH='@baseboard_fab2_lib.baseboard_fab2(sch_1):page141_i135@mstr_discrete.re~
s(chips)',
 PATH='I135',
 DRAWING='@BASEBOARD_FAB2_LIB.BASEBOARD_FAB2(SCH_1):PAGE141',
 WATTAGE='1/16W',
 TOLERANCE='1.0%',
 MATERIAL='CHIP',
 BOM_COST='PROC',
 PHYS_PAGE='141',
 XY='(-2800,2525)',
 ROT='4',
 VER='1',
 VALUE='75',
 PACK_TYPE='0402',
 PART_NUMBER='G21796-267',
 LOCATION='R9G3',
 ROOM='PROC_SIDEBAND',
 GROUP='NI_I210&RJ45',
 CDS_LIB='mstr_discrete',
 CDS_PART_NAME='RES_0402-75,1.0%,1/16W,CHIP,G2A',
 PRIM_FILE='./archive_libs/mstr_discrete/res/chips/chips.prt';

PART_NAME
 R9G4 'RES_0402-0.0,5%,1/16W,CHIP,G21A':
 GROUP='NI_I210&RJ45',
 ROOM='NIC_SPRV';

SECTION_NUMBER 1
 '@BASEBOARD_FAB2_LIB.BASEBOARD_FAB2(SCH_1):PAGE141_I156@MSTR_DISCRETE.RES(CHIPS)':
 C_PATH='@baseboard_fab2_lib.baseboard_fab2(sch_1):page141_i156@mstr_discrete.re~
s(chips)',
 P_PATH='@baseboard_fab2_lib.baseboard_fab2(sch_1):page141_i156@mstr_discrete.re~
s(chips)',
 PATH='I156',
 DRAWING='@BASEBOARD_FAB2_LIB.BASEBOARD_FAB2(SCH_1):PAGE141',
 WATTAGE='1/16W',
 TOLERANCE='5%',
 SEC_TYPE='0402',
 MATERIAL='CHIP',
 BOM_COST='NT_GBE_BASE',
 PHYS_PAGE='141',
 XY='(-2875,1200)',
 ROT='4',
 VER='1',
 VALUE='0.0',
 PACK_TYPE='0402',
 PART_NUMBER='G21497-005',
 LOCATION='R9G4',
 ROOM='NIC_SPRV',
 GROUP='NI_I210&RJ45',
 SEC='1',
 CDS_LIB='mstr_discrete',
 CDS_PART_NAME='RES_0402-0.0,5%,1/16W,CHIP,G21A',
 PRIM_FILE='./archive_libs/mstr_discrete/res/chips/chips.prt';

PART_NAME
 R9G9 'RES_0402-0.0,5%,1/16W,CHIP,G21A':
 GROUP='NI_I210&RJ45',
 ROOM='NIC_SPRV';

SECTION_NUMBER 1
 '@BASEBOARD_FAB2_LIB.BASEBOARD_FAB2(SCH_1):PAGE141_I75@MSTR_DISCRETE.RES(CHIPS)':
 C_PATH='@baseboard_fab2_lib.baseboard_fab2(sch_1):page141_i75@mstr_discrete.res~
(chips)',
 P_PATH='@baseboard_fab2_lib.baseboard_fab2(sch_1):page141_i75@mstr_discrete.res~
(chips)',
 PATH='I75',
 DRAWING='@BASEBOARD_FAB2_LIB.BASEBOARD_FAB2(SCH_1):PAGE141',
 WATTAGE='1/16W',
 TOLERANCE='5%',
 SEC_TYPE='0402',
 MATERIAL='CHIP',
 BOM_COST='NT_GBE_BASE',
 PHYS_PAGE='141',
 XY='(-3275,3775)',
 ROT='0',
 VER='1',
 VALUE='0.0',
 PACK_TYPE='0402',
 PART_NUMBER='G21497-005',
 LOCATION='R9G9',
 ROOM='NIC_SPRV',
 GROUP='NI_I210&RJ45',
 SEC='1',
 CDS_LIB='mstr_discrete',
 CDS_PART_NAME='RES_0402-0.0,5%,1/16W,CHIP,G21A',
 PRIM_FILE='./archive_libs/mstr_discrete/res/chips/chips.prt';

PART_NAME
 R9G11 'RES_0402-0.0,5%,1/16W,CHIP,G21A':
 GROUP='NI_I210&RJ45',
 ROOM='NIC_SPRV';

SECTION_NUMBER 1
 '@BASEBOARD_FAB2_LIB.BASEBOARD_FAB2(SCH_1):PAGE141_I76@MSTR_DISCRETE.RES(CHIPS)':
 C_PATH='@baseboard_fab2_lib.baseboard_fab2(sch_1):page141_i76@mstr_discrete.res~
(chips)',
 P_PATH='@baseboard_fab2_lib.baseboard_fab2(sch_1):page141_i76@mstr_discrete.res~
(chips)',
 PATH='I76',
 DRAWING='@BASEBOARD_FAB2_LIB.BASEBOARD_FAB2(SCH_1):PAGE141',
 WATTAGE='1/16W',
 TOLERANCE='5%',
 SEC_TYPE='0402',
 MATERIAL='CHIP',
 BOM_COST='NT_GBE_BASE',
 PHYS_PAGE='141',
 XY='(-3275,3725)',
 ROT='0',
 VER='1',
 VALUE='0.0',
 PACK_TYPE='0402',
 PART_NUMBER='G21497-005',
 LOCATION='R9G11',
 ROOM='NIC_SPRV',
 GROUP='NI_I210&RJ45',
 SEC='1',
 CDS_LIB='mstr_discrete',
 CDS_PART_NAME='RES_0402-0.0,5%,1/16W,CHIP,G21A',
 PRIM_FILE='./archive_libs/mstr_discrete/res/chips/chips.prt';

PART_NAME
 R9G12 'RES_0402-20.0,1%,1/16W,CHIP,G2A':
 ROOM='SMBUS';

SECTION_NUMBER 1
 '@BASEBOARD_FAB2_LIB.BASEBOARD_FAB2(SCH_1):PAGE159_I224@MSTR_DISCRETE.RES(CHIPS)':
 C_PATH='@baseboard_fab2_lib.baseboard_fab2(sch_1):page159_i224@mstr_discrete.re~
s(chips)',
 P_PATH='@baseboard_fab2_lib.baseboard_fab2(sch_1):page159_i224@mstr_discrete.re~
s(chips)',
 PATH='I224',
 DRAWING='@BASEBOARD_FAB2_LIB.BASEBOARD_FAB2(SCH_1):PAGE159',
 WATTAGE='1/16W',
 TOLERANCE='1%',
 MATERIAL='CHIP',
 BOM_COST='SM_CONTROLLER',
 PHYS_PAGE='159',
 XY='(-3625,1575)',
 ROT='0',
 VER='1',
 VALUE='20.0',
 PACK_TYPE='0402',
 PART_NUMBER='G21796-173',
 LOCATION='R9G12',
 ROOM='SMBUS',
 CDS_LIB='mstr_discrete',
 CDS_PART_NAME='RES_0402-20.0,1%,1/16W,CHIP,G2A',
 PRIM_FILE='./archive_libs/mstr_discrete/res/chips/chips.prt';

PART_NAME
 R9G13 'RES_0402-20.0,1%,1/16W,CHIP,G2A':
 ROOM='SMBUS';

SECTION_NUMBER 1
 '@BASEBOARD_FAB2_LIB.BASEBOARD_FAB2(SCH_1):PAGE159_I227@MSTR_DISCRETE.RES(CHIPS)':
 C_PATH='@baseboard_fab2_lib.baseboard_fab2(sch_1):page159_i227@mstr_discrete.re~
s(chips)',
 P_PATH='@baseboard_fab2_lib.baseboard_fab2(sch_1):page159_i227@mstr_discrete.re~
s(chips)',
 PATH='I227',
 DRAWING='@BASEBOARD_FAB2_LIB.BASEBOARD_FAB2(SCH_1):PAGE159',
 WATTAGE='1/16W',
 TOLERANCE='1%',
 MATERIAL='CHIP',
 BOM_COST='SM_CONTROLLER',
 PHYS_PAGE='159',
 XY='(-3625,1200)',
 ROT='0',
 VER='1',
 VALUE='20.0',
 PACK_TYPE='0402',
 PART_NUMBER='G21796-173',
 LOCATION='R9G13',
 ROOM='SMBUS',
 CDS_LIB='mstr_discrete',
 CDS_PART_NAME='RES_0402-20.0,1%,1/16W,CHIP,G2A',
 PRIM_FILE='./archive_libs/mstr_discrete/res/chips/chips.prt';

PART_NAME
 R9G14 'RES_0402-20.0,1%,1/16W,CHIP,G2A':
 ROOM='SMBUS';

SECTION_NUMBER 1
 '@BASEBOARD_FAB2_LIB.BASEBOARD_FAB2(SCH_1):PAGE167_I77@MSTR_DISCRETE.RES(CHIPS)':
 C_PATH='@baseboard_fab2_lib.baseboard_fab2(sch_1):page167_i77@mstr_discrete.res~
(chips)',
 P_PATH='@baseboard_fab2_lib.baseboard_fab2(sch_1):page167_i77@mstr_discrete.res~
(chips)',
 PATH='I77',
 DRAWING='@BASEBOARD_FAB2_LIB.BASEBOARD_FAB2(SCH_1):PAGE167',
 SKU='B',
 WATTAGE='1/16W',
 TOLERANCE='1%',
 MATERIAL='CHIP',
 BOM_COST='SM_CONTROLLER',
 PHYS_PAGE='167',
 XY='(-6725,1325)',
 ROT='0',
 VER='1',
 VALUE='20.0',
 PACK_TYPE='0402',
 PART_NUMBER='G21796-173',
 LOCATION='R9G14',
 ROOM='SMBUS',
 CDS_LIB='mstr_discrete',
 CDS_PART_NAME='RES_0402-20.0,1%,1/16W,CHIP,G2A',
 PRIM_FILE='./archive_libs/mstr_discrete/res/chips/chips.prt';

PART_NAME
 R9G15 'RES_0402-20.0,1%,1/16W,CHIP,G2A':
 ROOM='SMBUS';

SECTION_NUMBER 1
 '@BASEBOARD_FAB2_LIB.BASEBOARD_FAB2(SCH_1):PAGE167_I58@MSTR_DISCRETE.RES(CHIPS)':
 C_PATH='@baseboard_fab2_lib.baseboard_fab2(sch_1):page167_i58@mstr_discrete.res~
(chips)',
 P_PATH='@baseboard_fab2_lib.baseboard_fab2(sch_1):page167_i58@mstr_discrete.res~
(chips)',
 PATH='I58',
 DRAWING='@BASEBOARD_FAB2_LIB.BASEBOARD_FAB2(SCH_1):PAGE167',
 SKU='B',
 WATTAGE='1/16W',
 TOLERANCE='1%',
 MATERIAL='CHIP',
 BOM_COST='SM_CONTROLLER',
 PHYS_PAGE='167',
 XY='(-6725,1450)',
 ROT='0',
 VER='1',
 VALUE='20.0',
 PACK_TYPE='0402',
 PART_NUMBER='G21796-173',
 LOCATION='R9G15',
 ROOM='SMBUS',
 CDS_LIB='mstr_discrete',
 CDS_PART_NAME='RES_0402-20.0,1%,1/16W,CHIP,G2A',
 PRIM_FILE='./archive_libs/mstr_discrete/res/chips/chips.prt';

PART_NAME
 R9G17 'RES_0402-0.0,5%,1/16W,CHIP,G21A':
 GROUP='NI_I210&RJ45',
 ROOM='NIC_SPRV';

SECTION_NUMBER 1
 '@BASEBOARD_FAB2_LIB.BASEBOARD_FAB2(SCH_1):PAGE141_I78@MSTR_DISCRETE.RES(CHIPS)':
 C_PATH='@baseboard_fab2_lib.baseboard_fab2(sch_1):page141_i78@mstr_discrete.res~
(chips)',
 P_PATH='@baseboard_fab2_lib.baseboard_fab2(sch_1):page141_i78@mstr_discrete.res~
(chips)',
 PATH='I78',
 DRAWING='@BASEBOARD_FAB2_LIB.BASEBOARD_FAB2(SCH_1):PAGE141',
 WATTAGE='1/16W',
 TOLERANCE='5%',
 SEC_TYPE='0402',
 MATERIAL='CHIP',
 BOM_COST='NT_GBE_BASE',
 PHYS_PAGE='141',
 XY='(-3275,3625)',
 ROT='0',
 VER='1',
 VALUE='0.0',
 PACK_TYPE='0402',
 PART_NUMBER='G21497-005',
 LOCATION='R9G17',
 ROOM='NIC_SPRV',
 GROUP='NI_I210&RJ45',
 SEC='1',
 CDS_LIB='mstr_discrete',
 CDS_PART_NAME='RES_0402-0.0,5%,1/16W,CHIP,G21A',
 PRIM_FILE='./archive_libs/mstr_discrete/res/chips/chips.prt';

PART_NAME
 R9G18 'RES_0402-0.0,5%,1/16W,CHIP,G21A':
 GROUP='NI_I210&RJ45',
 ROOM='NIC_SPRV';

SECTION_NUMBER 1
 '@BASEBOARD_FAB2_LIB.BASEBOARD_FAB2(SCH_1):PAGE141_I77@MSTR_DISCRETE.RES(CHIPS)':
 C_PATH='@baseboard_fab2_lib.baseboard_fab2(sch_1):page141_i77@mstr_discrete.res~
(chips)',
 P_PATH='@baseboard_fab2_lib.baseboard_fab2(sch_1):page141_i77@mstr_discrete.res~
(chips)',
 PATH='I77',
 DRAWING='@BASEBOARD_FAB2_LIB.BASEBOARD_FAB2(SCH_1):PAGE141',
 WATTAGE='1/16W',
 TOLERANCE='5%',
 SEC_TYPE='0402',
 MATERIAL='CHIP',
 BOM_COST='NT_GBE_BASE',
 PHYS_PAGE='141',
 XY='(-3275,3675)',
 ROT='0',
 VER='1',
 VALUE='0.0',
 PACK_TYPE='0402',
 PART_NUMBER='G21497-005',
 LOCATION='R9G18',
 ROOM='NIC_SPRV',
 GROUP='NI_I210&RJ45',
 SEC='1',
 CDS_LIB='mstr_discrete',
 CDS_PART_NAME='RES_0402-0.0,5%,1/16W,CHIP,G21A',
 PRIM_FILE='./archive_libs/mstr_discrete/res/chips/chips.prt';

PART_NAME
 R9G19 'RES_0402-0.0,5%,1/16W,CHIP,G21A':
 GROUP='NI_I210&RJ45',
 ROOM='NIC_SPRV';

SECTION_NUMBER 1
 '@BASEBOARD_FAB2_LIB.BASEBOARD_FAB2(SCH_1):PAGE141_I79@MSTR_DISCRETE.RES(CHIPS)':
 C_PATH='@baseboard_fab2_lib.baseboard_fab2(sch_1):page141_i79@mstr_discrete.res~
(chips)',
 P_PATH='@baseboard_fab2_lib.baseboard_fab2(sch_1):page141_i79@mstr_discrete.res~
(chips)',
 PATH='I79',
 DRAWING='@BASEBOARD_FAB2_LIB.BASEBOARD_FAB2(SCH_1):PAGE141',
 WATTAGE='1/16W',
 TOLERANCE='5%',
 SEC_TYPE='0402',
 MATERIAL='CHIP',
 BOM_COST='NT_GBE_BASE',
 PHYS_PAGE='141',
 XY='(-3275,3575)',
 ROT='0',
 VER='1',
 VALUE='0.0',
 PACK_TYPE='0402',
 PART_NUMBER='G21497-005',
 LOCATION='R9G19',
 ROOM='NIC_SPRV',
 GROUP='NI_I210&RJ45',
 SEC='1',
 CDS_LIB='mstr_discrete',
 CDS_PART_NAME='RES_0402-0.0,5%,1/16W,CHIP,G21A',
 PRIM_FILE='./archive_libs/mstr_discrete/res/chips/chips.prt';

PART_NAME
 R9G20 'RES_0402-0.0,5%,1/16W,CHIP,G21A':
 GROUP='NI_I210&RJ45',
 ROOM='NIC_SPRV';

SECTION_NUMBER 1
 '@BASEBOARD_FAB2_LIB.BASEBOARD_FAB2(SCH_1):PAGE141_I80@MSTR_DISCRETE.RES(CHIPS)':
 C_PATH='@baseboard_fab2_lib.baseboard_fab2(sch_1):page141_i80@mstr_discrete.res~
(chips)',
 P_PATH='@baseboard_fab2_lib.baseboard_fab2(sch_1):page141_i80@mstr_discrete.res~
(chips)',
 PATH='I80',
 DRAWING='@BASEBOARD_FAB2_LIB.BASEBOARD_FAB2(SCH_1):PAGE141',
 WATTAGE='1/16W',
 TOLERANCE='5%',
 SEC_TYPE='0402',
 MATERIAL='CHIP',
 BOM_COST='NT_GBE_BASE',
 PHYS_PAGE='141',
 XY='(-3275,3525)',
 ROT='0',
 VER='1',
 VALUE='0.0',
 PACK_TYPE='0402',
 PART_NUMBER='G21497-005',
 LOCATION='R9G20',
 ROOM='NIC_SPRV',
 GROUP='NI_I210&RJ45',
 SEC='1',
 CDS_LIB='mstr_discrete',
 CDS_PART_NAME='RES_0402-0.0,5%,1/16W,CHIP,G21A',
 PRIM_FILE='./archive_libs/mstr_discrete/res/chips/chips.prt';

PART_NAME
 R9G22 'RES_0402-0.0,5%,1/16W,CHIP,G21A':
 GROUP='NI_I210&RJ45',
 ROOM='NIC_SPRV';

SECTION_NUMBER 1
 '@BASEBOARD_FAB2_LIB.BASEBOARD_FAB2(SCH_1):PAGE141_I82@MSTR_DISCRETE.RES(CHIPS)':
 C_PATH='@baseboard_fab2_lib.baseboard_fab2(sch_1):page141_i82@mstr_discrete.res~
(chips)',
 P_PATH='@baseboard_fab2_lib.baseboard_fab2(sch_1):page141_i82@mstr_discrete.res~
(chips)',
 PATH='I82',
 DRAWING='@BASEBOARD_FAB2_LIB.BASEBOARD_FAB2(SCH_1):PAGE141',
 WATTAGE='1/16W',
 TOLERANCE='5%',
 SEC_TYPE='0402',
 MATERIAL='CHIP',
 BOM_COST='NT_GBE_BASE',
 PHYS_PAGE='141',
 XY='(-3275,3425)',
 ROT='0',
 VER='1',
 VALUE='0.0',
 PACK_TYPE='0402',
 PART_NUMBER='G21497-005',
 LOCATION='R9G22',
 ROOM='NIC_SPRV',
 GROUP='NI_I210&RJ45',
 SEC='1',
 CDS_LIB='mstr_discrete',
 CDS_PART_NAME='RES_0402-0.0,5%,1/16W,CHIP,G21A',
 PRIM_FILE='./archive_libs/mstr_discrete/res/chips/chips.prt';

PART_NAME
 R9G24 'RES_0402-0.0,5%,1/16W,CHIP,G21A':
 GROUP='NI_I210&RJ45',
 ROOM='NIC_SPRV';

SECTION_NUMBER 1
 '@BASEBOARD_FAB2_LIB.BASEBOARD_FAB2(SCH_1):PAGE141_I81@MSTR_DISCRETE.RES(CHIPS)':
 C_PATH='@baseboard_fab2_lib.baseboard_fab2(sch_1):page141_i81@mstr_discrete.res~
(chips)',
 P_PATH='@baseboard_fab2_lib.baseboard_fab2(sch_1):page141_i81@mstr_discrete.res~
(chips)',
 PATH='I81',
 DRAWING='@BASEBOARD_FAB2_LIB.BASEBOARD_FAB2(SCH_1):PAGE141',
 WATTAGE='1/16W',
 TOLERANCE='5%',
 SEC_TYPE='0402',
 MATERIAL='CHIP',
 BOM_COST='NT_GBE_BASE',
 PHYS_PAGE='141',
 XY='(-3275,3475)',
 ROT='0',
 VER='1',
 VALUE='0.0',
 PACK_TYPE='0402',
 PART_NUMBER='G21497-005',
 LOCATION='R9G24',
 ROOM='NIC_SPRV',
 GROUP='NI_I210&RJ45',
 SEC='1',
 CDS_LIB='mstr_discrete',
 CDS_PART_NAME='RES_0402-0.0,5%,1/16W,CHIP,G21A',
 PRIM_FILE='./archive_libs/mstr_discrete/res/chips/chips.prt';

PART_NAME
 R9G26 'RES_0402-100.0K,1%,1/16W,CHIP,A':
 ROOM='BMC_VOLT_MONITOR';

SECTION_NUMBER 1
 '@BASEBOARD_FAB2_LIB.BASEBOARD_FAB2(SCH_1):PAGE169_I106@MSTR_DISCRETE.RES(CHIPS)':
 C_PATH='@baseboard_fab2_lib.baseboard_fab2(sch_1):page169_i106@mstr_discrete.re~
s(chips)',
 P_PATH='@baseboard_fab2_lib.baseboard_fab2(sch_1):page169_i106@mstr_discrete.re~
s(chips)',
 PATH='I106',
 DRAWING='@BASEBOARD_FAB2_LIB.BASEBOARD_FAB2(SCH_1):PAGE169',
 WATTAGE='1/16W',
 TOLERANCE='1%',
 SEC_TYPE='0402',
 MATERIAL='CHIP',
 BOM_COST='SM_HM',
 PHYS_PAGE='169',
 XY='(400,2725)',
 ROT='0',
 VER='2',
 VALUE='100.0K',
 PACK_TYPE='0402',
 PART_NUMBER='G21796-010',
 LOCATION='R9G26',
 ROOM='BMC_VOLT_MONITOR',
 SEC='1',
 CDS_LIB='mstr_discrete',
 CDS_PART_NAME='RES_0402-100.0K,1%,1/16W,CHIP,A',
 PRIM_FILE='./archive_libs/mstr_discrete/res/chips/chips.prt';

PART_NAME
 R9G27 'RES_0402-0.0,5%,1/16W,EMPTY,G2A':;

SECTION_NUMBER 1
 '@BASEBOARD_FAB2_LIB.BASEBOARD_FAB2(SCH_1):PAGE152_I47@MSTR_DISCRETE.RES(CHIPS)':
 C_PATH='@baseboard_fab2_lib.baseboard_fab2(sch_1):page152_i47@mstr_discrete.res~
(chips)',
 P_PATH='@baseboard_fab2_lib.baseboard_fab2(sch_1):page152_i47@mstr_discrete.res~
(chips)',
 PATH='I47',
 DRAWING='@BASEBOARD_FAB2_LIB.BASEBOARD_FAB2(SCH_1):PAGE152',
 WATTAGE='1/16W',
 TOLERANCE='5%',
 SEC_TYPE='0402',
 MATERIAL='EMPTY',
 PHYS_PAGE='152',
 XY='(-3150,4600)',
 ROT='0',
 VER='2',
 VALUE='0.0',
 PACK_TYPE='0402',
 PART_NUMBER='G21497-005',
 LOCATION='R9G27',
 SEC='1',
 CDS_LIB='mstr_discrete',
 CDS_PART_NAME='RES_0402-0.0,5%,1/16W,EMPTY,G2A',
 PRIM_FILE='./archive_libs/mstr_discrete/res/chips/chips.prt';

PART_NAME
 R9G28 'RES_0402-0.0,5%,1/16W,CHIP,G21A':;

SECTION_NUMBER 1
 '@BASEBOARD_FAB2_LIB.BASEBOARD_FAB2(SCH_1):PAGE152_I71@MSTR_DISCRETE.RES(CHIPS)':
 C_PATH='@baseboard_fab2_lib.baseboard_fab2(sch_1):page152_i71@mstr_discrete.res~
(chips)',
 P_PATH='@baseboard_fab2_lib.baseboard_fab2(sch_1):page152_i71@mstr_discrete.res~
(chips)',
 PATH='I71',
 DRAWING='@BASEBOARD_FAB2_LIB.BASEBOARD_FAB2(SCH_1):PAGE152',
 WATTAGE='1/16W',
 TOLERANCE='5%',
 SEC_TYPE='0402',
 MATERIAL='CHIP',
 PHYS_PAGE='152',
 XY='(-3375,3725)',
 ROT='0',
 VER='1',
 VALUE='0.0',
 PACK_TYPE='0402',
 PART_NUMBER='G21497-005',
 LOCATION='R9G28',
 SEC='1',
 CDS_LIB='mstr_discrete',
 CDS_PART_NAME='RES_0402-0.0,5%,1/16W,CHIP,G21A',
 PRIM_FILE='./archive_libs/mstr_discrete/res/chips/chips.prt';

PART_NAME
 R9G29 'RES_0402-0.0,5%,1/16W,CHIP,G21A':;

SECTION_NUMBER 1
 '@BASEBOARD_FAB2_LIB.BASEBOARD_FAB2(SCH_1):PAGE152_I92@MSTR_DISCRETE.RES(CHIPS)':
 C_PATH='@baseboard_fab2_lib.baseboard_fab2(sch_1):page152_i92@mstr_discrete.res~
(chips)',
 P_PATH='@baseboard_fab2_lib.baseboard_fab2(sch_1):page152_i92@mstr_discrete.res~
(chips)',
 PATH='I92',
 DRAWING='@BASEBOARD_FAB2_LIB.BASEBOARD_FAB2(SCH_1):PAGE152',
 WATTAGE='1/16W',
 TOLERANCE='5%',
 SEC_TYPE='0402',
 MATERIAL='CHIP',
 PHYS_PAGE='152',
 XY='(-6700,2025)',
 ROT='0',
 VER='1',
 VALUE='0.0',
 PACK_TYPE='0402',
 PART_NUMBER='G21497-005',
 LOCATION='R9G29',
 SEC='1',
 CDS_LIB='mstr_discrete',
 CDS_PART_NAME='RES_0402-0.0,5%,1/16W,CHIP,G21A',
 PRIM_FILE='./archive_libs/mstr_discrete/res/chips/chips.prt';

PART_NAME
 R9G30 'RES_0402-0.0,5%,1/16W,EMPTY,G2A':;

SECTION_NUMBER 1
 '@BASEBOARD_FAB2_LIB.BASEBOARD_FAB2(SCH_1):PAGE152_I98@MSTR_DISCRETE.RES(CHIPS)':
 C_PATH='@baseboard_fab2_lib.baseboard_fab2(sch_1):page152_i98@mstr_discrete.res~
(chips)',
 P_PATH='@baseboard_fab2_lib.baseboard_fab2(sch_1):page152_i98@mstr_discrete.res~
(chips)',
 PATH='I98',
 DRAWING='@BASEBOARD_FAB2_LIB.BASEBOARD_FAB2(SCH_1):PAGE152',
 WATTAGE='1/16W',
 TOLERANCE='5%',
 SEC_TYPE='0402',
 MATERIAL='EMPTY',
 PHYS_PAGE='152',
 XY='(-6700,1825)',
 ROT='0',
 VER='1',
 VALUE='0.0',
 PACK_TYPE='0402',
 PART_NUMBER='G21497-005',
 LOCATION='R9G30',
 SEC='1',
 CDS_LIB='mstr_discrete',
 CDS_PART_NAME='RES_0402-0.0,5%,1/16W,EMPTY,G2A',
 PRIM_FILE='./archive_libs/mstr_discrete/res/chips/chips.prt';

PART_NAME
 R9G31 'RES_0402-33.2,1%,1/16W,CHIP,G2A':
 ROOM='PROC_SIDEBAND';

SECTION_NUMBER 1
 '@BASEBOARD_FAB2_LIB.BASEBOARD_FAB2(SCH_1):PAGE152_I14@MSTR_DISCRETE.RES(CHIPS)':
 C_PATH='@baseboard_fab2_lib.baseboard_fab2(sch_1):page152_i14@mstr_discrete.res~
(chips)',
 P_PATH='@baseboard_fab2_lib.baseboard_fab2(sch_1):page152_i14@mstr_discrete.res~
(chips)',
 PATH='I14',
 DRAWING='@BASEBOARD_FAB2_LIB.BASEBOARD_FAB2(SCH_1):PAGE152',
 WATTAGE='1/16W',
 TOLERANCE='1%',
 SEC_TYPE='0402',
 MATERIAL='CHIP',
 BOM_COST='PROC_SIDEBAND',
 PHYS_PAGE='152',
 XY='(-2400,4075)',
 ROT='0',
 VER='1',
 VALUE='33.2',
 PACK_TYPE='0402',
 PART_NUMBER='G21796-074',
 LOCATION='R9G31',
 ROOM='PROC_SIDEBAND',
 SEC='1',
 CDS_LIB='mstr_discrete',
 CDS_PART_NAME='RES_0402-33.2,1%,1/16W,CHIP,G2A',
 PRIM_FILE='./archive_libs/mstr_discrete/res/chips/chips.prt';

PART_NAME
 R9G32 'RES_0402-0.0,5%,1/16W,CHIP,G21A':;

SECTION_NUMBER 1
 '@BASEBOARD_FAB2_LIB.BASEBOARD_FAB2(SCH_1):PAGE152_I72@MSTR_DISCRETE.RES(CHIPS)':
 C_PATH='@baseboard_fab2_lib.baseboard_fab2(sch_1):page152_i72@mstr_discrete.res~
(chips)',
 P_PATH='@baseboard_fab2_lib.baseboard_fab2(sch_1):page152_i72@mstr_discrete.res~
(chips)',
 PATH='I72',
 DRAWING='@BASEBOARD_FAB2_LIB.BASEBOARD_FAB2(SCH_1):PAGE152',
 WATTAGE='1/16W',
 TOLERANCE='5%',
 SEC_TYPE='0402',
 MATERIAL='CHIP',
 PHYS_PAGE='152',
 XY='(-3375,3900)',
 ROT='0',
 VER='1',
 VALUE='0.0',
 PACK_TYPE='0402',
 PART_NUMBER='G21497-005',
 LOCATION='R9G32',
 SEC='1',
 CDS_LIB='mstr_discrete',
 CDS_PART_NAME='RES_0402-0.0,5%,1/16W,CHIP,G21A',
 PRIM_FILE='./archive_libs/mstr_discrete/res/chips/chips.prt';

PART_NAME
 R9G33 'RES_0402-0.0,5%,1/16W,CHIP,G21A':;

SECTION_NUMBER 1
 '@BASEBOARD_FAB2_LIB.BASEBOARD_FAB2(SCH_1):PAGE152_I73@MSTR_DISCRETE.RES(CHIPS)':
 C_PATH='@baseboard_fab2_lib.baseboard_fab2(sch_1):page152_i73@mstr_discrete.res~
(chips)',
 P_PATH='@baseboard_fab2_lib.baseboard_fab2(sch_1):page152_i73@mstr_discrete.res~
(chips)',
 PATH='I73',
 DRAWING='@BASEBOARD_FAB2_LIB.BASEBOARD_FAB2(SCH_1):PAGE152',
 WATTAGE='1/16W',
 TOLERANCE='5%',
 SEC_TYPE='0402',
 MATERIAL='CHIP',
 PHYS_PAGE='152',
 XY='(-3375,4075)',
 ROT='0',
 VER='1',
 VALUE='0.0',
 PACK_TYPE='0402',
 PART_NUMBER='G21497-005',
 LOCATION='R9G33',
 SEC='1',
 CDS_LIB='mstr_discrete',
 CDS_PART_NAME='RES_0402-0.0,5%,1/16W,CHIP,G21A',
 PRIM_FILE='./archive_libs/mstr_discrete/res/chips/chips.prt';

PART_NAME
 R9G34 'RES_0402-0.0,5%,1/16W,CHIP,G21A':;

SECTION_NUMBER 1
 '@BASEBOARD_FAB2_LIB.BASEBOARD_FAB2(SCH_1):PAGE152_I45@MSTR_DISCRETE.RES(CHIPS)':
 C_PATH='@baseboard_fab2_lib.baseboard_fab2(sch_1):page152_i45@mstr_discrete.res~
(chips)',
 P_PATH='@baseboard_fab2_lib.baseboard_fab2(sch_1):page152_i45@mstr_discrete.res~
(chips)',
 PATH='I45',
 DRAWING='@BASEBOARD_FAB2_LIB.BASEBOARD_FAB2(SCH_1):PAGE152',
 WATTAGE='1/16W',
 TOLERANCE='5%',
 SEC_TYPE='0402',
 MATERIAL='CHIP',
 PHYS_PAGE='152',
 XY='(-6950,4225)',
 ROT='0',
 VER='1',
 VALUE='0.0',
 PACK_TYPE='0402',
 PART_NUMBER='G21497-005',
 LOCATION='R9G34',
 SEC='1',
 CDS_LIB='mstr_discrete',
 CDS_PART_NAME='RES_0402-0.0,5%,1/16W,CHIP,G21A',
 PRIM_FILE='./archive_libs/mstr_discrete/res/chips/chips.prt';

PART_NAME
 R9G35 'RES_0402-2.7K,1%,1/16W,CHIP,G2A':;

SECTION_NUMBER 1
 '@BASEBOARD_FAB2_LIB.BASEBOARD_FAB2(SCH_1):PAGE169_I164@MSTR_DISCRETE.RES(CHIPS)':
 C_PATH='@baseboard_fab2_lib.baseboard_fab2(sch_1):page169_i164@mstr_discrete.re~
s(chips)',
 P_PATH='@baseboard_fab2_lib.baseboard_fab2(sch_1):page169_i164@mstr_discrete.re~
s(chips)',
 PATH='I164',
 DRAWING='@BASEBOARD_FAB2_LIB.BASEBOARD_FAB2(SCH_1):PAGE169',
 WATTAGE='1/16W',
 TOLERANCE='1%',
 SEC_TYPE='0402',
 MATERIAL='CHIP',
 PHYS_PAGE='169',
 XY='(-1400,3025)',
 ROT='0',
 VER='2',
 VALUE='2.7K',
 PACK_TYPE='0402',
 PART_NUMBER='G21796-344',
 LOCATION='R9G35',
 SEC='1',
 CDS_LIB='mstr_discrete',
 CDS_PART_NAME='RES_0402-2.7K,1%,1/16W,CHIP,G2A',
 PRIM_FILE='./archive_libs/mstr_discrete/res/chips/chips.prt';

PART_NAME
 R9L1 'RES_0402-1.00K,1%,1/16W,CHIP,GA':
 ROOM='PROC';

SECTION_NUMBER 1
 '@BASEBOARD_FAB2_LIB.BASEBOARD_FAB2(SCH_1):PAGE100_I40@MSTR_DISCRETE.RES(CHIPS)':
 C_PATH='@baseboard_fab2_lib.baseboard_fab2(sch_1):page100_i40@mstr_discrete.res~
(chips)',
 P_PATH='@baseboard_fab2_lib.baseboard_fab2(sch_1):page100_i40@mstr_discrete.res~
(chips)',
 PATH='I40',
 DRAWING='@BASEBOARD_FAB2_LIB.BASEBOARD_FAB2(SCH_1):PAGE100',
 WATTAGE='1/16W',
 TOLERANCE='1%',
 SEC_TYPE='0402',
 MATERIAL='CHIP',
 BOM_COST='PROC_SOCKET',
 PHYS_PAGE='100',
 XY='(2975,1625)',
 ROT='2',
 VER='2',
 VALUE='1.00K',
 PACK_TYPE='0402',
 PART_NUMBER='G21796-026',
 LOCATION='R9L1',
 ROOM='PROC',
 SEC='1',
 CDS_LIB='mstr_discrete',
 CDS_PART_NAME='RES_0402-1.00K,1%,1/16W,CHIP,GA',
 PRIM_FILE='./archive_libs/mstr_discrete/res/chips/chips.prt';

PART_NAME
 R9L2 'RES_0402-1.00K,1%,1/16W,CHIP,GA':
 ROOM='MEM';

SECTION_NUMBER 1
 '@BASEBOARD_FAB2_LIB.BASEBOARD_FAB2(SCH_1):PAGE100_I38@MSTR_DISCRETE.RES(CHIPS)':
 C_PATH='@baseboard_fab2_lib.baseboard_fab2(sch_1):page100_i38@mstr_discrete.res~
(chips)',
 P_PATH='@baseboard_fab2_lib.baseboard_fab2(sch_1):page100_i38@mstr_discrete.res~
(chips)',
 PATH='I38',
 DRAWING='@BASEBOARD_FAB2_LIB.BASEBOARD_FAB2(SCH_1):PAGE100',
 WATTAGE='1/16W',
 TOLERANCE='1%',
 SEC_TYPE='0402',
 MATERIAL='CHIP',
 BOM_COST='SM_CONTROLLER',
 PHYS_PAGE='100',
 XY='(2900,2275)',
 ROT='2',
 VER='2',
 VALUE='1.00K',
 PACK_TYPE='0402',
 PART_NUMBER='G21796-026',
 LOCATION='R9L2',
 ROOM='MEM',
 SEC='1',
 CDS_LIB='mstr_discrete',
 CDS_PART_NAME='RES_0402-1.00K,1%,1/16W,CHIP,GA',
 PRIM_FILE='./archive_libs/mstr_discrete/res/chips/chips.prt';

PART_NAME
 R9L3 'RES_0402-2,1.0%,1/16W,CHIP,G21A':
 ROOM='PROC';

SECTION_NUMBER 1
 '@BASEBOARD_FAB2_LIB.BASEBOARD_FAB2(SCH_1):PAGE100_I45@MSTR_DISCRETE.RES(CHIPS)':
 C_PATH='@baseboard_fab2_lib.baseboard_fab2(sch_1):page100_i45@mstr_discrete.res~
(chips)',
 P_PATH='@baseboard_fab2_lib.baseboard_fab2(sch_1):page100_i45@mstr_discrete.res~
(chips)',
 PATH='I45',
 DRAWING='@BASEBOARD_FAB2_LIB.BASEBOARD_FAB2(SCH_1):PAGE100',
 WATTAGE='1/16W',
 TOLERANCE='1.0%',
 SEC_TYPE='0402',
 MATERIAL='CHIP',
 BOM_COST='PROC_SOCKET',
 PHYS_PAGE='100',
 XY='(2675,1950)',
 ROT='0',
 VER='1',
 VALUE='2',
 PACK_TYPE='0402',
 PART_NUMBER='G21796-274',
 LOCATION='R9L3',
 ROOM='PROC',
 SEC='1',
 CDS_LIB='mstr_discrete',
 CDS_PART_NAME='RES_0402-2,1.0%,1/16W,CHIP,G21A',
 PRIM_FILE='./archive_libs/mstr_discrete/res/chips/chips.prt';

PART_NAME
 R9L4 'RES_0402-0.0,5%,1/16W,CHIP,G21A':
 ROOM='CPU0';

SECTION_NUMBER 1
 '@BASEBOARD_FAB2_LIB.BASEBOARD_FAB2(SCH_1):PAGE227_I155@MSTR_DISCRETE.RES(CHIPS)':
 C_PATH='@baseboard_fab2_lib.baseboard_fab2(sch_1):page227_i155@mstr_discrete.re~
s(chips)',
 P_PATH='@baseboard_fab2_lib.baseboard_fab2(sch_1):page227_i155@mstr_discrete.re~
s(chips)',
 PATH='I155',
 DRAWING='@BASEBOARD_FAB2_LIB.BASEBOARD_FAB2(SCH_1):PAGE227',
 BOM_SS='NOPOP',
 WATTAGE='1/16W',
 TOLERANCE='5%',
 SEC_TYPE='0402',
 MATERIAL='CHIP',
 BOM_COST='PROC_SIDEBAND',
 PHYS_PAGE='227',
 XY='(-675,800)',
 ROT='0',
 VER='1',
 VALUE='0.0',
 PACK_TYPE='0402',
 PART_NUMBER='G21497-005',
 LOCATION='R9L4',
 ROOM='CPU0',
 SEC='1',
 CDS_LIB='mstr_discrete',
 CDS_PART_NAME='RES_0402-0.0,5%,1/16W,CHIP,G21A',
 PRIM_FILE='./archive_libs/mstr_discrete/res/chips/chips.prt';

PART_NAME
 R9L6 'RES_0402-1.00K,1%,1/16W,CHIP,GA':
 ROOM='PROC';

SECTION_NUMBER 1
 '@BASEBOARD_FAB2_LIB.BASEBOARD_FAB2(SCH_1):PAGE100_I24@MSTR_DISCRETE.RES(CHIPS)':
 C_PATH='@baseboard_fab2_lib.baseboard_fab2(sch_1):page100_i24@mstr_discrete.res~
(chips)',
 P_PATH='@baseboard_fab2_lib.baseboard_fab2(sch_1):page100_i24@mstr_discrete.res~
(chips)',
 PATH='I24',
 DRAWING='@BASEBOARD_FAB2_LIB.BASEBOARD_FAB2(SCH_1):PAGE100',
 WATTAGE='1/16W',
 TOLERANCE='1%',
 SEC_TYPE='0402',
 MATERIAL='CHIP',
 BOM_COST='PROC_SOCKET',
 PHYS_PAGE='100',
 XY='(525,1625)',
 ROT='2',
 VER='2',
 VALUE='1.00K',
 PACK_TYPE='0402',
 PART_NUMBER='G21796-026',
 LOCATION='R9L6',
 ROOM='PROC',
 SEC='1',
 CDS_LIB='mstr_discrete',
 CDS_PART_NAME='RES_0402-1.00K,1%,1/16W,CHIP,GA',
 PRIM_FILE='./archive_libs/mstr_discrete/res/chips/chips.prt';

PART_NAME
 R9L7 'RES_0402-1.00K,1%,1/16W,CHIP,GA':
 ROOM='MEM';

SECTION_NUMBER 1
 '@BASEBOARD_FAB2_LIB.BASEBOARD_FAB2(SCH_1):PAGE100_I22@MSTR_DISCRETE.RES(CHIPS)':
 C_PATH='@baseboard_fab2_lib.baseboard_fab2(sch_1):page100_i22@mstr_discrete.res~
(chips)',
 P_PATH='@baseboard_fab2_lib.baseboard_fab2(sch_1):page100_i22@mstr_discrete.res~
(chips)',
 PATH='I22',
 DRAWING='@BASEBOARD_FAB2_LIB.BASEBOARD_FAB2(SCH_1):PAGE100',
 WATTAGE='1/16W',
 TOLERANCE='1%',
 SEC_TYPE='0402',
 MATERIAL='CHIP',
 BOM_COST='SM_CONTROLLER',
 PHYS_PAGE='100',
 XY='(450,2275)',
 ROT='2',
 VER='2',
 VALUE='1.00K',
 PACK_TYPE='0402',
 PART_NUMBER='G21796-026',
 LOCATION='R9L7',
 ROOM='MEM',
 SEC='1',
 CDS_LIB='mstr_discrete',
 CDS_PART_NAME='RES_0402-1.00K,1%,1/16W,CHIP,GA',
 PRIM_FILE='./archive_libs/mstr_discrete/res/chips/chips.prt';

PART_NAME
 R9L8 'RES_0402-2,1.0%,1/16W,CHIP,G21A':
 ROOM='PROC';

SECTION_NUMBER 1
 '@BASEBOARD_FAB2_LIB.BASEBOARD_FAB2(SCH_1):PAGE100_I29@MSTR_DISCRETE.RES(CHIPS)':
 C_PATH='@baseboard_fab2_lib.baseboard_fab2(sch_1):page100_i29@mstr_discrete.res~
(chips)',
 P_PATH='@baseboard_fab2_lib.baseboard_fab2(sch_1):page100_i29@mstr_discrete.res~
(chips)',
 PATH='I29',
 DRAWING='@BASEBOARD_FAB2_LIB.BASEBOARD_FAB2(SCH_1):PAGE100',
 WATTAGE='1/16W',
 TOLERANCE='1.0%',
 SEC_TYPE='0402',
 MATERIAL='CHIP',
 BOM_COST='PROC_SOCKET',
 PHYS_PAGE='100',
 XY='(225,1950)',
 ROT='0',
 VER='1',
 VALUE='2',
 PACK_TYPE='0402',
 PART_NUMBER='G21796-274',
 LOCATION='R9L8',
 ROOM='PROC',
 SEC='1',
 CDS_LIB='mstr_discrete',
 CDS_PART_NAME='RES_0402-2,1.0%,1/16W,CHIP,G21A',
 PRIM_FILE='./archive_libs/mstr_discrete/res/chips/chips.prt';

PART_NAME
 R9L9 'RES_0402-0.0,5%,1/16W,CHIP,G21A':
 ROOM='CPU0';

SECTION_NUMBER 1
 '@BASEBOARD_FAB2_LIB.BASEBOARD_FAB2(SCH_1):PAGE227_I154@MSTR_DISCRETE.RES(CHIPS)':
 C_PATH='@baseboard_fab2_lib.baseboard_fab2(sch_1):page227_i154@mstr_discrete.re~
s(chips)',
 P_PATH='@baseboard_fab2_lib.baseboard_fab2(sch_1):page227_i154@mstr_discrete.re~
s(chips)',
 PATH='I154',
 DRAWING='@BASEBOARD_FAB2_LIB.BASEBOARD_FAB2(SCH_1):PAGE227',
 WATTAGE='1/16W',
 TOLERANCE='5%',
 SEC_TYPE='0402',
 MATERIAL='CHIP',
 BOM_COST='PROC_SIDEBAND',
 PHYS_PAGE='227',
 XY='(-750,3100)',
 ROT='0',
 VER='1',
 VALUE='0.0',
 PACK_TYPE='0402',
 PART_NUMBER='G21497-005',
 LOCATION='R9L9',
 ROOM='CPU0',
 SEC='1',
 CDS_LIB='mstr_discrete',
 CDS_PART_NAME='RES_0402-0.0,5%,1/16W,CHIP,G21A',
 PRIM_FILE='./archive_libs/mstr_discrete/res/chips/chips.prt';

PART_NAME
 R9L11 'RES_0402-1.00K,1%,1/16W,CHIP,GA':
 ROOM='PROC';

SECTION_NUMBER 1
 '@BASEBOARD_FAB2_LIB.BASEBOARD_FAB2(SCH_1):PAGE100_I4@MSTR_DISCRETE.RES(CHIPS)':
 C_PATH='@baseboard_fab2_lib.baseboard_fab2(sch_1):page100_i4@mstr_discrete.res(~
chips)',
 P_PATH='@baseboard_fab2_lib.baseboard_fab2(sch_1):page100_i4@mstr_discrete.res(~
chips)',
 PATH='I4',
 DRAWING='@BASEBOARD_FAB2_LIB.BASEBOARD_FAB2(SCH_1):PAGE100',
 WATTAGE='1/16W',
 TOLERANCE='1%',
 SEC_TYPE='0402',
 MATERIAL='CHIP',
 BOM_COST='PROC_SOCKET',
 PHYS_PAGE='100',
 XY='(-1825,1625)',
 ROT='2',
 VER='2',
 VALUE='1.00K',
 PACK_TYPE='0402',
 PART_NUMBER='G21796-026',
 LOCATION='R9L11',
 ROOM='PROC',
 SEC='1',
 CDS_LIB='mstr_discrete',
 CDS_PART_NAME='RES_0402-1.00K,1%,1/16W,CHIP,GA',
 PRIM_FILE='./archive_libs/mstr_discrete/res/chips/chips.prt';

PART_NAME
 R9M1 'RES_0402-1.00K,1%,1/16W,CHIP,GA':
 ROOM='MEM';

SECTION_NUMBER 1
 '@BASEBOARD_FAB2_LIB.BASEBOARD_FAB2(SCH_1):PAGE100_I11@MSTR_DISCRETE.RES(CHIPS)':
 C_PATH='@baseboard_fab2_lib.baseboard_fab2(sch_1):page100_i11@mstr_discrete.res~
(chips)',
 P_PATH='@baseboard_fab2_lib.baseboard_fab2(sch_1):page100_i11@mstr_discrete.res~
(chips)',
 PATH='I11',
 DRAWING='@BASEBOARD_FAB2_LIB.BASEBOARD_FAB2(SCH_1):PAGE100',
 WATTAGE='1/16W',
 TOLERANCE='1%',
 SEC_TYPE='0402',
 MATERIAL='CHIP',
 BOM_COST='SM_CONTROLLER',
 PHYS_PAGE='100',
 XY='(-1900,2275)',
 ROT='2',
 VER='2',
 VALUE='1.00K',
 PACK_TYPE='0402',
 PART_NUMBER='G21796-026',
 LOCATION='R9M1',
 ROOM='MEM',
 SEC='1',
 CDS_LIB='mstr_discrete',
 CDS_PART_NAME='RES_0402-1.00K,1%,1/16W,CHIP,GA',
 PRIM_FILE='./archive_libs/mstr_discrete/res/chips/chips.prt';

PART_NAME
 R9M2 'RES_0402-2,1.0%,1/16W,CHIP,G21A':
 ROOM='PROC';

SECTION_NUMBER 1
 '@BASEBOARD_FAB2_LIB.BASEBOARD_FAB2(SCH_1):PAGE100_I13@MSTR_DISCRETE.RES(CHIPS)':
 C_PATH='@baseboard_fab2_lib.baseboard_fab2(sch_1):page100_i13@mstr_discrete.res~
(chips)',
 P_PATH='@baseboard_fab2_lib.baseboard_fab2(sch_1):page100_i13@mstr_discrete.res~
(chips)',
 PATH='I13',
 DRAWING='@BASEBOARD_FAB2_LIB.BASEBOARD_FAB2(SCH_1):PAGE100',
 WATTAGE='1/16W',
 TOLERANCE='1.0%',
 SEC_TYPE='0402',
 MATERIAL='CHIP',
 BOM_COST='PROC_SOCKET',
 PHYS_PAGE='100',
 XY='(-2125,1950)',
 ROT='0',
 VER='1',
 VALUE='2',
 PACK_TYPE='0402',
 PART_NUMBER='G21796-274',
 LOCATION='R9M2',
 ROOM='PROC',
 SEC='1',
 CDS_LIB='mstr_discrete',
 CDS_PART_NAME='RES_0402-2,1.0%,1/16W,CHIP,G21A',
 PRIM_FILE='./archive_libs/mstr_discrete/res/chips/chips.prt';

PART_NAME
 R9M3 'RES_0402-0.0,5%,1/16W,CHIP,G21A':
 ROOM='VDDQ_KLM_PWR_VR';

SECTION_NUMBER 1
 '@BASEBOARD_FAB2_LIB.BASEBOARD_FAB2(SCH_1):PAGE226_I36@MSTR_DISCRETE.RES(CHIPS)':
 C_PATH='@baseboard_fab2_lib.baseboard_fab2(sch_1):page226_i36@mstr_discrete.res~
(chips)',
 P_PATH='@baseboard_fab2_lib.baseboard_fab2(sch_1):page226_i36@mstr_discrete.res~
(chips)',
 PATH='I36',
 DRAWING='@BASEBOARD_FAB2_LIB.BASEBOARD_FAB2(SCH_1):PAGE226',
 WATTAGE='1/16W',
 TOLERANCE='5%',
 SEC_TYPE='0402',
 MATERIAL='CHIP',
 PHYS_PAGE='226',
 XY='(575,2825)',
 ROT='0',
 VER='2',
 VALUE='0.0',
 PACK_TYPE='0402',
 PART_NUMBER='G21497-005',
 LOCATION='R9M3',
 ROOM='VDDQ_KLM_PWR_VR',
 SEC='1',
 CDS_LIB='mstr_discrete',
 CDS_PART_NAME='RES_0402-0.0,5%,1/16W,CHIP,G21A',
 PRIM_FILE='./archive_libs/mstr_discrete/res/chips/chips.prt';

PART_NAME
 R9M4 'RES_1206-0.002,1%,1W,CHIP,G521A':
 ROOM='PVDDQ_ABC_PWR_VR';

SECTION_NUMBER 1
 '@BASEBOARD_FAB2_LIB.BASEBOARD_FAB2(SCH_1):PAGE197_I29@MSTR_DISCRETE.RES(CHIPS)':
 C_PATH='@baseboard_fab2_lib.baseboard_fab2(sch_1):page197_i29@mstr_discrete.res~
(chips)',
 P_PATH='@baseboard_fab2_lib.baseboard_fab2(sch_1):page197_i29@mstr_discrete.res~
(chips)',
 PATH='I29',
 DRAWING='@BASEBOARD_FAB2_LIB.BASEBOARD_FAB2(SCH_1):PAGE197',
 NEW_VALUE='0.004 OHM',
 CONFIG='064.R0045.0711',
 WATTAGE='1W',
 TOLERANCE='1%',
 SEC_TYPE='1206',
 MATERIAL='CHIP',
 BOM_COST='PVDDQ_ABC_VR',
 PHYS_PAGE='197',
 XY='(-1725,2700)',
 ROT='0',
 VER='1',
 VALUE='0.002',
 PACK_TYPE='1206',
 PART_NUMBER='G52199-004',
 LOCATION='R9M4',
 ROOM='PVDDQ_ABC_PWR_VR',
 SEC='1',
 CDS_LIB='mstr_discrete',
 CDS_PART_NAME='RES_1206-0.002,1%,1W,CHIP,G521A',
 PRIM_FILE='./archive_libs/mstr_discrete/res/chips/chips.prt';

PART_NAME
 R9M5 'RES_0402-100.0K,1%,1/16W,EMPTYA':
 ROOM='BMC';

SECTION_NUMBER 1
 '@BASEBOARD_FAB2_LIB.BASEBOARD_FAB2(SCH_1):PAGE226_I34@MSTR_DISCRETE.RES(CHIPS)':
 C_PATH='@baseboard_fab2_lib.baseboard_fab2(sch_1):page226_i34@mstr_discrete.res~
(chips)',
 P_PATH='@baseboard_fab2_lib.baseboard_fab2(sch_1):page226_i34@mstr_discrete.res~
(chips)',
 PATH='I34',
 DRAWING='@BASEBOARD_FAB2_LIB.BASEBOARD_FAB2(SCH_1):PAGE226',
 WATTAGE='1/16W',
 TOLERANCE='1%',
 SEC_TYPE='0402',
 MATERIAL='EMPTY',
 BOM_COST='SM_CONTROLLER',
 PHYS_PAGE='226',
 XY='(-175,2850)',
 ROT='0',
 VER='2',
 VALUE='100.0K',
 PACK_TYPE='0402',
 PART_NUMBER='G21796-010',
 LOCATION='R9M5',
 ROOM='BMC',
 SEC='1',
 CDS_LIB='mstr_discrete',
 CDS_PART_NAME='RES_0402-100.0K,1%,1/16W,EMPTYA',
 PRIM_FILE='./archive_libs/mstr_discrete/res/chips/chips.prt';

PART_NAME
 R9M6 'RES_0402-49.9,1%,1/16W,EMPTY,GA':
 ROOM='VDDQ_GHJ_PWR_VR';

SECTION_NUMBER 1
 '@BASEBOARD_FAB2_LIB.BASEBOARD_FAB2(SCH_1):PAGE226_I70@MSTR_DISCRETE.RES(CHIPS)':
 C_PATH='@baseboard_fab2_lib.baseboard_fab2(sch_1):page226_i70@mstr_discrete.res~
(chips)',
 P_PATH='@baseboard_fab2_lib.baseboard_fab2(sch_1):page226_i70@mstr_discrete.res~
(chips)',
 PATH='I70',
 DRAWING='@BASEBOARD_FAB2_LIB.BASEBOARD_FAB2(SCH_1):PAGE226',
 WATTAGE='1/16W',
 TOLERANCE='1%',
 SEC_TYPE='0402',
 MATERIAL='EMPTY',
 PHYS_PAGE='226',
 XY='(-925,2850)',
 ROT='0',
 VER='2',
 VALUE='49.9',
 PACK_TYPE='0402',
 PART_NUMBER='G21796-047',
 LOCATION='R9M6',
 ROOM='VDDQ_GHJ_PWR_VR',
 SEC='1',
 CDS_LIB='mstr_discrete',
 CDS_PART_NAME='RES_0402-49.9,1%,1/16W,EMPTY,GA',
 PRIM_FILE='./archive_libs/mstr_discrete/res/chips/chips.prt';

PART_NAME
 R9M7 'RES_0402-100.0,1%,1/16W,EMPTY,A':
 ROOM='VDDQ_KLM_PWR_VR';

SECTION_NUMBER 1
 '@BASEBOARD_FAB2_LIB.BASEBOARD_FAB2(SCH_1):PAGE226_I57@MSTR_DISCRETE.RES(CHIPS)':
 C_PATH='@baseboard_fab2_lib.baseboard_fab2(sch_1):page226_i57@mstr_discrete.res~
(chips)',
 P_PATH='@baseboard_fab2_lib.baseboard_fab2(sch_1):page226_i57@mstr_discrete.res~
(chips)',
 PATH='I57',
 DRAWING='@BASEBOARD_FAB2_LIB.BASEBOARD_FAB2(SCH_1):PAGE226',
 WATTAGE='1/16W',
 TOLERANCE='1%',
 SEC_TYPE='0402',
 MATERIAL='EMPTY',
 PHYS_PAGE='226',
 XY='(3750,2075)',
 ROT='0',
 VER='2',
 VALUE='100.0',
 PACK_TYPE='0402',
 PART_NUMBER='G21796-017',
 LOCATION='R9M7',
 ROOM='VDDQ_KLM_PWR_VR',
 SEC='1',
 CDS_LIB='mstr_discrete',
 CDS_PART_NAME='RES_0402-100.0,1%,1/16W,EMPTY,A',
 PRIM_FILE='./archive_libs/mstr_discrete/res/chips/chips.prt';

PART_NAME
 R9M9 'RES_0402-0.0,5%,1/16W,CHIP,G21A':
 ROOM='PVCCIN_CPU0_VR';

SECTION_NUMBER 1
 '@BASEBOARD_FAB2_LIB.BASEBOARD_FAB2(SCH_1):PAGE226_I14@MSTR_DISCRETE.RES(CHIPS)':
 C_PATH='@baseboard_fab2_lib.baseboard_fab2(sch_1):page226_i14@mstr_discrete.res~
(chips)',
 P_PATH='@baseboard_fab2_lib.baseboard_fab2(sch_1):page226_i14@mstr_discrete.res~
(chips)',
 PATH='I14',
 DRAWING='@BASEBOARD_FAB2_LIB.BASEBOARD_FAB2(SCH_1):PAGE226',
 WATTAGE='1/16W',
 TOLERANCE='5%',
 MATERIAL='CHIP',
 PHYS_PAGE='226',
 XY='(-1800,775)',
 ROT='0',
 VER='1',
 VALUE='0.0',
 PACK_TYPE='0402',
 PART_NUMBER='G21497-005',
 LOCATION='R9M9',
 ROOM='PVCCIN_CPU0_VR',
 CDS_LIB='mstr_discrete',
 CDS_PART_NAME='RES_0402-0.0,5%,1/16W,CHIP,G21A',
 PRIM_FILE='./archive_libs/mstr_discrete/res/chips/chips.prt';

PART_NAME
 R9M13 'RES_0402-20.0,1%,1/16W,CHIP,G2A':
 ROOM='SMB_PE_HP_CPU1';

SECTION_NUMBER 1
 '@BASEBOARD_FAB2_LIB.BASEBOARD_FAB2(SCH_1):PAGE163_I21@MSTR_DISCRETE.RES(CHIPS)':
 C_PATH='@baseboard_fab2_lib.baseboard_fab2(sch_1):page163_i21@mstr_discrete.res~
(chips)',
 P_PATH='@baseboard_fab2_lib.baseboard_fab2(sch_1):page163_i21@mstr_discrete.res~
(chips)',
 PATH='I21',
 DRAWING='@BASEBOARD_FAB2_LIB.BASEBOARD_FAB2(SCH_1):PAGE163',
 WATTAGE='1/16W',
 TOLERANCE='1%',
 SEC_TYPE='0402',
 MATERIAL='CHIP',
 PHYS_PAGE='163',
 XY='(200,3250)',
 ROT='0',
 VER='1',
 VALUE='20.0',
 PACK_TYPE='0402',
 PART_NUMBER='G21796-173',
 LOCATION='R9M13',
 ROOM='SMB_PE_HP_CPU1',
 SEC='1',
 CDS_LIB='mstr_discrete',
 CDS_PART_NAME='RES_0402-20.0,1%,1/16W,CHIP,G2A',
 PRIM_FILE='./archive_libs/mstr_discrete/res/chips/chips.prt';

PART_NAME
 R9M14 'RES_0402-20.0,1%,1/16W,CHIP,G2A':
 ROOM='SMB_PE_HP_CPU1';

SECTION_NUMBER 1
 '@BASEBOARD_FAB2_LIB.BASEBOARD_FAB2(SCH_1):PAGE163_I20@MSTR_DISCRETE.RES(CHIPS)':
 C_PATH='@baseboard_fab2_lib.baseboard_fab2(sch_1):page163_i20@mstr_discrete.res~
(chips)',
 P_PATH='@baseboard_fab2_lib.baseboard_fab2(sch_1):page163_i20@mstr_discrete.res~
(chips)',
 PATH='I20',
 DRAWING='@BASEBOARD_FAB2_LIB.BASEBOARD_FAB2(SCH_1):PAGE163',
 WATTAGE='1/16W',
 TOLERANCE='1%',
 SEC_TYPE='0402',
 MATERIAL='CHIP',
 PHYS_PAGE='163',
 XY='(-50,3300)',
 ROT='0',
 VER='1',
 VALUE='20.0',
 PACK_TYPE='0402',
 PART_NUMBER='G21796-173',
 LOCATION='R9M14',
 ROOM='SMB_PE_HP_CPU1',
 SEC='1',
 CDS_LIB='mstr_discrete',
 CDS_PART_NAME='RES_0402-20.0,1%,1/16W,CHIP,G2A',
 PRIM_FILE='./archive_libs/mstr_discrete/res/chips/chips.prt';

PART_NAME
 R9M16 'RES_0402-2.0K,1%,1/16W,CHIP,G2A':
 ROOM='SMB_PE_HP_CPU1';

SECTION_NUMBER 1
 '@BASEBOARD_FAB2_LIB.BASEBOARD_FAB2(SCH_1):PAGE163_I16@MSTR_DISCRETE.RES(CHIPS)':
 C_PATH='@baseboard_fab2_lib.baseboard_fab2(sch_1):page163_i16@mstr_discrete.res~
(chips)',
 P_PATH='@baseboard_fab2_lib.baseboard_fab2(sch_1):page163_i16@mstr_discrete.res~
(chips)',
 PATH='I16',
 DRAWING='@BASEBOARD_FAB2_LIB.BASEBOARD_FAB2(SCH_1):PAGE163',
 WATTAGE='1/16W',
 TOLERANCE='1%',
 SEC_TYPE='0402',
 MATERIAL='CHIP',
 PHYS_PAGE='163',
 XY='(-450,3650)',
 ROT='0',
 VER='2',
 VALUE='2.0K',
 PACK_TYPE='0402',
 PART_NUMBER='G21796-001',
 LOCATION='R9M16',
 ROOM='SMB_PE_HP_CPU1',
 SEC='1',
 CDS_LIB='mstr_discrete',
 CDS_PART_NAME='RES_0402-2.0K,1%,1/16W,CHIP,G2A',
 PRIM_FILE='./archive_libs/mstr_discrete/res/chips/chips.prt';

PART_NAME
 R9M17 'RES_0402-2.0K,1%,1/16W,CHIP,G2A':
 ROOM='SMB_PE_HP_CPU1';

SECTION_NUMBER 1
 '@BASEBOARD_FAB2_LIB.BASEBOARD_FAB2(SCH_1):PAGE163_I15@MSTR_DISCRETE.RES(CHIPS)':
 C_PATH='@baseboard_fab2_lib.baseboard_fab2(sch_1):page163_i15@mstr_discrete.res~
(chips)',
 P_PATH='@baseboard_fab2_lib.baseboard_fab2(sch_1):page163_i15@mstr_discrete.res~
(chips)',
 PATH='I15',
 DRAWING='@BASEBOARD_FAB2_LIB.BASEBOARD_FAB2(SCH_1):PAGE163',
 WATTAGE='1/16W',
 TOLERANCE='1%',
 SEC_TYPE='0402',
 MATERIAL='CHIP',
 PHYS_PAGE='163',
 XY='(-600,3650)',
 ROT='2',
 VER='2',
 VALUE='2.0K',
 PACK_TYPE='0402',
 PART_NUMBER='G21796-001',
 LOCATION='R9M17',
 ROOM='SMB_PE_HP_CPU1',
 SEC='1',
 CDS_LIB='mstr_discrete',
 CDS_PART_NAME='RES_0402-2.0K,1%,1/16W,CHIP,G2A',
 PRIM_FILE='./archive_libs/mstr_discrete/res/chips/chips.prt';

PART_NAME
 R9M18 'RES_0402-240,1.0%,1/16W,CHIP,GA':
 ROOM='SMB_PE_HP_CPU1';

SECTION_NUMBER 1
 '@BASEBOARD_FAB2_LIB.BASEBOARD_FAB2(SCH_1):PAGE163_I6@MSTR_DISCRETE.RES(CHIPS)':
 C_PATH='@baseboard_fab2_lib.baseboard_fab2(sch_1):page163_i6@mstr_discrete.res(~
chips)',
 P_PATH='@baseboard_fab2_lib.baseboard_fab2(sch_1):page163_i6@mstr_discrete.res(~
chips)',
 PATH='I6',
 DRAWING='@BASEBOARD_FAB2_LIB.BASEBOARD_FAB2(SCH_1):PAGE163',
 WATTAGE='1/16W',
 TOLERANCE='1.0%',
 SEC_TYPE='0402',
 MATERIAL='CHIP',
 PHYS_PAGE='163',
 XY='(-2200,3650)',
 ROT='0',
 VER='2',
 VALUE='240',
 PACK_TYPE='0402',
 PART_NUMBER='G21796-294',
 LOCATION='R9M18',
 ROOM='SMB_PE_HP_CPU1',
 SEC='1',
 CDS_LIB='mstr_discrete',
 CDS_PART_NAME='RES_0402-240,1.0%,1/16W,CHIP,GA',
 PRIM_FILE='./archive_libs/mstr_discrete/res/chips/chips.prt';

PART_NAME
 R9M19 'RES_0402-240,1.0%,1/16W,CHIP,GA':
 ROOM='SMB_PE_HP_CPU1';

SECTION_NUMBER 1
 '@BASEBOARD_FAB2_LIB.BASEBOARD_FAB2(SCH_1):PAGE163_I7@MSTR_DISCRETE.RES(CHIPS)':
 C_PATH='@baseboard_fab2_lib.baseboard_fab2(sch_1):page163_i7@mstr_discrete.res(~
chips)',
 P_PATH='@baseboard_fab2_lib.baseboard_fab2(sch_1):page163_i7@mstr_discrete.res(~
chips)',
 PATH='I7',
 DRAWING='@BASEBOARD_FAB2_LIB.BASEBOARD_FAB2(SCH_1):PAGE163',
 WATTAGE='1/16W',
 TOLERANCE='1.0%',
 SEC_TYPE='0402',
 MATERIAL='CHIP',
 PHYS_PAGE='163',
 XY='(-2325,3650)',
 ROT='2',
 VER='2',
 VALUE='240',
 PACK_TYPE='0402',
 PART_NUMBER='G21796-294',
 LOCATION='R9M19',
 ROOM='SMB_PE_HP_CPU1',
 SEC='1',
 CDS_LIB='mstr_discrete',
 CDS_PART_NAME='RES_0402-240,1.0%,1/16W,CHIP,GA',
 PRIM_FILE='./archive_libs/mstr_discrete/res/chips/chips.prt';

PART_NAME
 R9M20 'RES_0402-0.0,5%,1/16W,CHIP,G21A':
 ROOM='CPU1';

SECTION_NUMBER 1
 '@BASEBOARD_FAB2_LIB.BASEBOARD_FAB2(SCH_1):PAGE156_I323@MSTR_DISCRETE.RES(CHIPS)':
 C_PATH='@baseboard_fab2_lib.baseboard_fab2(sch_1):page156_i323@mstr_discrete.re~
s(chips)',
 P_PATH='@baseboard_fab2_lib.baseboard_fab2(sch_1):page156_i323@mstr_discrete.re~
s(chips)',
 PATH='I323',
 DRAWING='@BASEBOARD_FAB2_LIB.BASEBOARD_FAB2(SCH_1):PAGE156',
 WATTAGE='1/16W',
 TOLERANCE='5%',
 SEC_TYPE='0402',
 MATERIAL='CHIP',
 PHYS_PAGE='156',
 XY='(-6425,550)',
 ROT='0',
 VER='1',
 VALUE='0.0',
 PACK_TYPE='0402',
 PART_NUMBER='G21497-005',
 LOCATION='R9M20',
 ROOM='CPU1',
 SEC='1',
 CDS_LIB='mstr_discrete',
 CDS_PART_NAME='RES_0402-0.0,5%,1/16W,CHIP,G21A',
 PRIM_FILE='./archive_libs/mstr_discrete/res/chips/chips.prt';

PART_NAME
 R9M21 'RES_0402-0.0,5%,1/16W,CHIP,G21A':
 ROOM='CPU1';

SECTION_NUMBER 1
 '@BASEBOARD_FAB2_LIB.BASEBOARD_FAB2(SCH_1):PAGE156_I321@MSTR_DISCRETE.RES(CHIPS)':
 C_PATH='@baseboard_fab2_lib.baseboard_fab2(sch_1):page156_i321@mstr_discrete.re~
s(chips)',
 P_PATH='@baseboard_fab2_lib.baseboard_fab2(sch_1):page156_i321@mstr_discrete.re~
s(chips)',
 PATH='I321',
 DRAWING='@BASEBOARD_FAB2_LIB.BASEBOARD_FAB2(SCH_1):PAGE156',
 WATTAGE='1/16W',
 TOLERANCE='5%',
 SEC_TYPE='0402',
 MATERIAL='CHIP',
 PHYS_PAGE='156',
 XY='(-6425,850)',
 ROT='0',
 VER='1',
 VALUE='0.0',
 PACK_TYPE='0402',
 PART_NUMBER='G21497-005',
 LOCATION='R9M21',
 ROOM='CPU1',
 SEC='1',
 CDS_LIB='mstr_discrete',
 CDS_PART_NAME='RES_0402-0.0,5%,1/16W,CHIP,G21A',
 PRIM_FILE='./archive_libs/mstr_discrete/res/chips/chips.prt';

PART_NAME
 R9N1 'RES_0402-49.9,1%,1/16W,CHIP,G2A':
 ROOM='CPU1';

SECTION_NUMBER 1
 '@BASEBOARD_FAB2_LIB.BASEBOARD_FAB2(SCH_1):PAGE55_I4@MSTR_DISCRETE.RES(CHIPS)':
 C_PATH='@baseboard_fab2_lib.baseboard_fab2(sch_1):page55_i4@mstr_discrete.res(c~
hips)',
 P_PATH='@baseboard_fab2_lib.baseboard_fab2(sch_1):page55_i4@mstr_discrete.res(c~
hips)',
 PATH='I4',
 DRAWING='@BASEBOARD_FAB2_LIB.BASEBOARD_FAB2(SCH_1):PAGE55',
 WATTAGE='1/16W',
 TOLERANCE='1%',
 SEC_TYPE='0402',
 MATERIAL='CHIP',
 BOM_COST='PROC_SOCKET',
 PHYS_PAGE='55',
 XY='(13600,3925)',
 ROT='0',
 VER='2',
 VALUE='49.9',
 PACK_TYPE='0402',
 PART_NUMBER='G21796-047',
 LOCATION='R9N1',
 ROOM='CPU1',
 SEC='1',
 CDS_LIB='mstr_discrete',
 CDS_PART_NAME='RES_0402-49.9,1%,1/16W,CHIP,G2A',
 PRIM_FILE='./archive_libs/mstr_discrete/res/chips/chips.prt';

PART_NAME
 R9N2 'RES_0402-100.0,1%,1/16W,CHIP,GA':
 ROOM='CPU1';

SECTION_NUMBER 1
 '@BASEBOARD_FAB2_LIB.BASEBOARD_FAB2(SCH_1):PAGE55_I7@MSTR_DISCRETE.RES(CHIPS)':
 C_PATH='@baseboard_fab2_lib.baseboard_fab2(sch_1):page55_i7@mstr_discrete.res(c~
hips)',
 P_PATH='@baseboard_fab2_lib.baseboard_fab2(sch_1):page55_i7@mstr_discrete.res(c~
hips)',
 PATH='I7',
 DRAWING='@BASEBOARD_FAB2_LIB.BASEBOARD_FAB2(SCH_1):PAGE55',
 WATTAGE='1/16W',
 TOLERANCE='1%',
 SEC_TYPE='0402',
 MATERIAL='CHIP',
 BOM_COST='PROC_SOCKET',
 PHYS_PAGE='55',
 XY='(13325,3925)',
 ROT='0',
 VER='2',
 VALUE='100.0',
 PACK_TYPE='0402',
 PART_NUMBER='G21796-017',
 LOCATION='R9N2',
 ROOM='CPU1',
 SEC='1',
 CDS_LIB='mstr_discrete',
 CDS_PART_NAME='RES_0402-100.0,1%,1/16W,CHIP,GA',
 PRIM_FILE='./archive_libs/mstr_discrete/res/chips/chips.prt';

PART_NAME
 R9N3 'RES_0402-0.0,5%,1/16W,CHIP,G21A':
 ROOM='CPU0';

SECTION_NUMBER 1
 '@BASEBOARD_FAB2_LIB.BASEBOARD_FAB2(SCH_1):PAGE210_I71@MSTR_DISCRETE.RES(CHIPS)':
 C_PATH='@baseboard_fab2_lib.baseboard_fab2(sch_1):page210_i71@mstr_discrete.res~
(chips)',
 P_PATH='@baseboard_fab2_lib.baseboard_fab2(sch_1):page210_i71@mstr_discrete.res~
(chips)',
 PATH='I71',
 DRAWING='@BASEBOARD_FAB2_LIB.BASEBOARD_FAB2(SCH_1):PAGE210',
 WATTAGE='1/16W',
 TOLERANCE='5%',
 SEC_TYPE='0402',
 MATERIAL='CHIP',
 BOM_COST='PROC_SIDEBAND',
 PHYS_PAGE='210',
 XY='(-5725,4425)',
 ROT='0',
 VER='1',
 VALUE='0.0',
 PACK_TYPE='0402',
 PART_NUMBER='G21497-005',
 LOCATION='R9N3',
 ROOM='CPU0',
 SEC='1',
 CDS_LIB='mstr_discrete',
 CDS_PART_NAME='RES_0402-0.0,5%,1/16W,CHIP,G21A',
 PRIM_FILE='./archive_libs/mstr_discrete/res/chips/chips.prt';

PART_NAME
 R9N4 'RES_0402-51.1,1.0%,1/16W,CHIP,A':;

SECTION_NUMBER 1
 '@BASEBOARD_FAB2_LIB.BASEBOARD_FAB2(SCH_1):PAGE210_I45@MSTR_DISCRETE.RES(CHIPS)':
 C_PATH='@baseboard_fab2_lib.baseboard_fab2(sch_1):page210_i45@mstr_discrete.res~
(chips)',
 P_PATH='@baseboard_fab2_lib.baseboard_fab2(sch_1):page210_i45@mstr_discrete.res~
(chips)',
 PATH='I45',
 DRAWING='@BASEBOARD_FAB2_LIB.BASEBOARD_FAB2(SCH_1):PAGE210',
 WATTAGE='1/16W',
 TOLERANCE='1.0%',
 SEC_TYPE='0402',
 MATERIAL='CHIP',
 PHYS_PAGE='210',
 XY='(-650,3100)',
 ROT='0',
 VER='2',
 VALUE='51.1',
 PACK_TYPE='0402',
 PART_NUMBER='G21796-208',
 LOCATION='R9N4',
 SEC='1',
 CDS_LIB='mstr_discrete',
 CDS_PART_NAME='RES_0402-51.1,1.0%,1/16W,CHIP,A',
 PRIM_FILE='./archive_libs/mstr_discrete/res/chips/chips.prt';

PART_NAME
 R9N7 'RES_0402-3.16K,1%,1/16W,CHIP,GA':
 ROOM='PVCCIN_CPU1_VR';

SECTION_NUMBER 1
 '@BASEBOARD_FAB2_LIB.BASEBOARD_FAB2(SCH_1):PAGE206_I111@MSTR_DISCRETE.RES(CHIPS)':
 C_PATH='@baseboard_fab2_lib.baseboard_fab2(sch_1):page206_i111@mstr_discrete.re~
s(chips)',
 P_PATH='@baseboard_fab2_lib.baseboard_fab2(sch_1):page206_i111@mstr_discrete.re~
s(chips)',
 PATH='I111',
 DRAWING='@BASEBOARD_FAB2_LIB.BASEBOARD_FAB2(SCH_1):PAGE206',
 WATTAGE='1/16W',
 TOLERANCE='1%',
 SEC_TYPE='0402',
 MATERIAL='CHIP',
 PHYS_PAGE='206',
 XY='(-4500,925)',
 ROT='0',
 VER='2',
 VALUE='3.16K',
 PACK_TYPE='0402',
 PART_NUMBER='G21796-043',
 LOCATION='R9N7',
 ROOM='PVCCIN_CPU1_VR',
 SEC='1',
 CDS_LIB='mstr_discrete',
 CDS_PART_NAME='RES_0402-3.16K,1%,1/16W,CHIP,GA',
 PRIM_FILE='./archive_libs/mstr_discrete/res/chips/chips.prt';

PART_NAME
 R9N8 'RES_0402-4.02K,1%,1/16W,CHIP,GA':
 ROOM='PVCCIN_CPU1_VR';

SECTION_NUMBER 1
 '@BASEBOARD_FAB2_LIB.BASEBOARD_FAB2(SCH_1):PAGE206_I112@MSTR_DISCRETE.RES(CHIPS)':
 C_PATH='@baseboard_fab2_lib.baseboard_fab2(sch_1):page206_i112@mstr_discrete.re~
s(chips)',
 P_PATH='@baseboard_fab2_lib.baseboard_fab2(sch_1):page206_i112@mstr_discrete.re~
s(chips)',
 PATH='I112',
 DRAWING='@BASEBOARD_FAB2_LIB.BASEBOARD_FAB2(SCH_1):PAGE206',
 WATTAGE='1/16W',
 TOLERANCE='1%',
 SEC_TYPE='0402',
 MATERIAL='CHIP',
 PHYS_PAGE='206',
 XY='(-4825,925)',
 ROT='0',
 VER='2',
 VALUE='4.02K',
 PACK_TYPE='0402',
 PART_NUMBER='G21796-082',
 LOCATION='R9N8',
 ROOM='PVCCIN_CPU1_VR',
 SEC='1',
 CDS_LIB='mstr_discrete',
 CDS_PART_NAME='RES_0402-4.02K,1%,1/16W,CHIP,GA',
 PRIM_FILE='./archive_libs/mstr_discrete/res/chips/chips.prt';

PART_NAME
 R9N14 'RES_0402-1.00K,1%,1/16W,CHIP,GA':
 ROOM='BMC';

SECTION_NUMBER 1
 '@BASEBOARD_FAB2_LIB.BASEBOARD_FAB2(SCH_1):PAGE206_I120@MSTR_DISCRETE.RES(CHIPS)':
 C_PATH='@baseboard_fab2_lib.baseboard_fab2(sch_1):page206_i120@mstr_discrete.re~
s(chips)',
 P_PATH='@baseboard_fab2_lib.baseboard_fab2(sch_1):page206_i120@mstr_discrete.re~
s(chips)',
 PATH='I120',
 DRAWING='@BASEBOARD_FAB2_LIB.BASEBOARD_FAB2(SCH_1):PAGE206',
 WATTAGE='1/16W',
 TOLERANCE='1%',
 SEC_TYPE='0402',
 MATERIAL='CHIP',
 BOM_COST='SM_CONTROLLER',
 PHYS_PAGE='206',
 XY='(-4650,4400)',
 ROT='0',
 VER='2',
 VALUE='1.00K',
 PACK_TYPE='0402',
 PART_NUMBER='G21796-026',
 LOCATION='R9N14',
 ROOM='BMC',
 SEC='1',
 CDS_LIB='mstr_discrete',
 CDS_PART_NAME='RES_0402-1.00K,1%,1/16W,CHIP,GA',
 PRIM_FILE='./archive_libs/mstr_discrete/res/chips/chips.prt';

PART_NAME
 R9N16 'RES_0402-0.0,5%,1/16W,CHIP,G21A':
 ROOM='PVCCIN_CPU0_VR';

SECTION_NUMBER 1
 '@BASEBOARD_FAB2_LIB.BASEBOARD_FAB2(SCH_1):PAGE206_I119@MSTR_DISCRETE.RES(CHIPS)':
 C_PATH='@baseboard_fab2_lib.baseboard_fab2(sch_1):page206_i119@mstr_discrete.re~
s(chips)',
 P_PATH='@baseboard_fab2_lib.baseboard_fab2(sch_1):page206_i119@mstr_discrete.re~
s(chips)',
 PATH='I119',
 DRAWING='@BASEBOARD_FAB2_LIB.BASEBOARD_FAB2(SCH_1):PAGE206',
 WATTAGE='1/16W',
 TOLERANCE='5%',
 SEC_TYPE='0402',
 MATERIAL='CHIP',
 PHYS_PAGE='206',
 XY='(-5200,2275)',
 ROT='0',
 VER='1',
 VALUE='0.0',
 PACK_TYPE='0402',
 PART_NUMBER='G21497-005',
 LOCATION='R9N16',
 ROOM='PVCCIN_CPU0_VR',
 SEC='1',
 CDS_LIB='mstr_discrete',
 CDS_PART_NAME='RES_0402-0.0,5%,1/16W,CHIP,G21A',
 PRIM_FILE='./archive_libs/mstr_discrete/res/chips/chips.prt';

PART_NAME
 R9P1 'RES_0402-100.0,1%,1/16W,CHIP,GA':
 ROOM='PVCCIN_CPU1_VR';

SECTION_NUMBER 1
 '@BASEBOARD_FAB2_LIB.BASEBOARD_FAB2(SCH_1):PAGE206_I4@MSTR_DISCRETE.RES(CHIPS)':
 C_PATH='@baseboard_fab2_lib.baseboard_fab2(sch_1):page206_i4@mstr_discrete.res(~
chips)',
 P_PATH='@baseboard_fab2_lib.baseboard_fab2(sch_1):page206_i4@mstr_discrete.res(~
chips)',
 PATH='I4',
 DRAWING='@BASEBOARD_FAB2_LIB.BASEBOARD_FAB2(SCH_1):PAGE206',
 WATTAGE='1/16W',
 TOLERANCE='1%',
 SEC_TYPE='0402',
 MATERIAL='CHIP',
 PHYS_PAGE='206',
 XY='(-1375,3750)',
 ROT='0',
 VER='2',
 VALUE='100.0',
 PACK_TYPE='0402',
 PART_NUMBER='G21796-017',
 LOCATION='R9P1',
 ROOM='PVCCIN_CPU1_VR',
 SEC='1',
 CDS_LIB='mstr_discrete',
 CDS_PART_NAME='RES_0402-100.0,1%,1/16W,CHIP,GA',
 PRIM_FILE='./archive_libs/mstr_discrete/res/chips/chips.prt';

PART_NAME
 R9P2 'RES_0402-49.9,1%,1/16W,CHIP,G2A':
 ROOM='PVCCIN_CPU1_VR';

SECTION_NUMBER 1
 '@BASEBOARD_FAB2_LIB.BASEBOARD_FAB2(SCH_1):PAGE206_I53@MSTR_DISCRETE.RES(CHIPS)':
 C_PATH='@baseboard_fab2_lib.baseboard_fab2(sch_1):page206_i53@mstr_discrete.res~
(chips)',
 P_PATH='@baseboard_fab2_lib.baseboard_fab2(sch_1):page206_i53@mstr_discrete.res~
(chips)',
 PATH='I53',
 DRAWING='@BASEBOARD_FAB2_LIB.BASEBOARD_FAB2(SCH_1):PAGE206',
 WATTAGE='1/16W',
 TOLERANCE='1%',
 SEC_TYPE='0402',
 MATERIAL='CHIP',
 PHYS_PAGE='206',
 XY='(-5650,4450)',
 ROT='0',
 VER='2',
 VALUE='49.9',
 PACK_TYPE='0402',
 PART_NUMBER='G21796-047',
 LOCATION='R9P2',
 ROOM='PVCCIN_CPU1_VR',
 SEC='1',
 CDS_LIB='mstr_discrete',
 CDS_PART_NAME='RES_0402-49.9,1%,1/16W,CHIP,G2A',
 PRIM_FILE='./archive_libs/mstr_discrete/res/chips/chips.prt';

PART_NAME
 R9P3 'RES_0402-33.2,1%,1/16W,CHIP,G2A':;

SECTION_NUMBER 1
 '@BASEBOARD_FAB2_LIB.BASEBOARD_FAB2(SCH_1):PAGE206_I117@MSTR_DISCRETE.RES(CHIPS)':
 C_PATH='@baseboard_fab2_lib.baseboard_fab2(sch_1):page206_i117@mstr_discrete.re~
s(chips)',
 P_PATH='@baseboard_fab2_lib.baseboard_fab2(sch_1):page206_i117@mstr_discrete.re~
s(chips)',
 PATH='I117',
 DRAWING='@BASEBOARD_FAB2_LIB.BASEBOARD_FAB2(SCH_1):PAGE206',
 WATTAGE='1/16W',
 TOLERANCE='1%',
 SEC_TYPE='0402',
 MATERIAL='CHIP',
 PHYS_PAGE='206',
 XY='(-2375,3025)',
 ROT='0',
 VER='1',
 VALUE='33.2',
 PACK_TYPE='0402',
 PART_NUMBER='G21796-074',
 LOCATION='R9P3',
 SEC='1',
 CDS_LIB='mstr_discrete',
 CDS_PART_NAME='RES_0402-33.2,1%,1/16W,CHIP,G2A',
 PRIM_FILE='./archive_libs/mstr_discrete/res/chips/chips.prt';

PART_NAME
 R9P4 'RES_0402-2.7K,1%,1/16W,CHIP,G2A':
 ROOM='HOT_SWAP';

SECTION_NUMBER 1
 '@BASEBOARD_FAB2_LIB.BASEBOARD_FAB2(SCH_1):PAGE200_I210@MSTR_DISCRETE.RES(CHIPS)':
 C_PATH='@baseboard_fab2_lib.baseboard_fab2(sch_1):page200_i210@mstr_discrete.re~
s(chips)',
 P_PATH='@baseboard_fab2_lib.baseboard_fab2(sch_1):page200_i210@mstr_discrete.re~
s(chips)',
 PATH='I210',
 DRAWING='@BASEBOARD_FAB2_LIB.BASEBOARD_FAB2(SCH_1):PAGE200',
 WATTAGE='1/16W',
 TOLERANCE='1%',
 SEC_TYPE='0402',
 MATERIAL='CHIP',
 PHYS_PAGE='200',
 XY='(1750,225)',
 ROT='0',
 VER='2',
 VALUE='2.7K',
 PACK_TYPE='0402',
 PART_NUMBER='G21796-344',
 LOCATION='R9P4',
 ROOM='HOT_SWAP',
 SEC='1',
 CDS_LIB='mstr_discrete',
 CDS_PART_NAME='RES_0402-2.7K,1%,1/16W,CHIP,G2A',
 PRIM_FILE='./archive_libs/mstr_discrete/res/chips/chips.prt';

PART_NAME
 R9P5 'RES_0402-10.0K,1%,1/16W,CHIP,GA':
 ROOM='HOT_SWAP';

SECTION_NUMBER 1
 '@BASEBOARD_FAB2_LIB.BASEBOARD_FAB2(SCH_1):PAGE200_I215@MSTR_DISCRETE.RES(CHIPS)':
 C_PATH='@baseboard_fab2_lib.baseboard_fab2(sch_1):page200_i215@mstr_discrete.re~
s(chips)',
 P_PATH='@baseboard_fab2_lib.baseboard_fab2(sch_1):page200_i215@mstr_discrete.re~
s(chips)',
 PATH='I215',
 DRAWING='@BASEBOARD_FAB2_LIB.BASEBOARD_FAB2(SCH_1):PAGE200',
 WATTAGE='1/16W',
 TOLERANCE='1%',
 SEC_TYPE='0402',
 MATERIAL='CHIP',
 PHYS_PAGE='200',
 XY='(1500,1125)',
 ROT='0',
 VER='2',
 VALUE='10.0K',
 PACK_TYPE='0402',
 PART_NUMBER='G21796-016',
 LOCATION='R9P5',
 ROOM='HOT_SWAP',
 SEC='1',
 CDS_LIB='mstr_discrete',
 CDS_PART_NAME='RES_0402-10.0K,1%,1/16W,CHIP,GA',
 PRIM_FILE='./archive_libs/mstr_discrete/res/chips/chips.prt';

PART_NAME
 R9P6 'RES_0402-10.0K,1%,1/16W,CHIP,GA':
 ROOM='HOT_SWAP';

SECTION_NUMBER 1
 '@BASEBOARD_FAB2_LIB.BASEBOARD_FAB2(SCH_1):PAGE200_I149@MSTR_DISCRETE.RES(CHIPS)':
 C_PATH='@baseboard_fab2_lib.baseboard_fab2(sch_1):page200_i149@mstr_discrete.re~
s(chips)',
 P_PATH='@baseboard_fab2_lib.baseboard_fab2(sch_1):page200_i149@mstr_discrete.re~
s(chips)',
 PATH='I149',
 DRAWING='@BASEBOARD_FAB2_LIB.BASEBOARD_FAB2(SCH_1):PAGE200',
 WATTAGE='1/16W',
 TOLERANCE='1%',
 SEC_TYPE='0402',
 MATERIAL='CHIP',
 PHYS_PAGE='200',
 XY='(600,1100)',
 ROT='0',
 VER='2',
 VALUE='10.0K',
 PACK_TYPE='0402',
 PART_NUMBER='G21796-016',
 LOCATION='R9P6',
 ROOM='HOT_SWAP',
 SEC='1',
 CDS_LIB='mstr_discrete',
 CDS_PART_NAME='RES_0402-10.0K,1%,1/16W,CHIP,GA',
 PRIM_FILE='./archive_libs/mstr_discrete/res/chips/chips.prt';

PART_NAME
 R9P7 'RES_0402-100.0K,1%,1/16W,CHIP,A':
 ROOM='V_SUPER';

SECTION_NUMBER 1
 '@BASEBOARD_FAB2_LIB.BASEBOARD_FAB2(SCH_1):PAGE200_I252@MSTR_DISCRETE.RES(CHIPS)':
 C_PATH='@baseboard_fab2_lib.baseboard_fab2(sch_1):page200_i252@mstr_discrete.re~
s(chips)',
 P_PATH='@baseboard_fab2_lib.baseboard_fab2(sch_1):page200_i252@mstr_discrete.re~
s(chips)',
 PATH='I252',
 DRAWING='@BASEBOARD_FAB2_LIB.BASEBOARD_FAB2(SCH_1):PAGE200',
 WATTAGE='1/16W',
 TOLERANCE='1%',
 SEC_TYPE='0402',
 MATERIAL='CHIP',
 PHYS_PAGE='200',
 XY='(-1975,800)',
 ROT='0',
 VER='2',
 VALUE='100.0K',
 PACK_TYPE='0402',
 PART_NUMBER='G21796-010',
 LOCATION='R9P7',
 ROOM='V_SUPER',
 SEC='1',
 CDS_LIB='mstr_discrete',
 CDS_PART_NAME='RES_0402-100.0K,1%,1/16W,CHIP,A',
 PRIM_FILE='./archive_libs/mstr_discrete/res/chips/chips.prt';

PART_NAME
 R9P8 'RES_0402-0.0,5%,1/16W,CHIP,G21A':
 ROOM='CPU0';

SECTION_NUMBER 1
 '@BASEBOARD_FAB2_LIB.BASEBOARD_FAB2(SCH_1):PAGE208_I115@MSTR_DISCRETE.RES(CHIPS)':
 C_PATH='@baseboard_fab2_lib.baseboard_fab2(sch_1):page208_i115@mstr_discrete.re~
s(chips)',
 P_PATH='@baseboard_fab2_lib.baseboard_fab2(sch_1):page208_i115@mstr_discrete.re~
s(chips)',
 PATH='I115',
 DRAWING='@BASEBOARD_FAB2_LIB.BASEBOARD_FAB2(SCH_1):PAGE208',
 WATTAGE='1/16W',
 TOLERANCE='5%',
 SEC_TYPE='0402',
 MATERIAL='CHIP',
 BOM_COST='PROC_SIDEBAND',
 PHYS_PAGE='208',
 XY='(-5450,2025)',
 ROT='0',
 VER='1',
 VALUE='0.0',
 PACK_TYPE='0402',
 PART_NUMBER='G21497-005',
 LOCATION='R9P8',
 ROOM='CPU0',
 SEC='1',
 CDS_LIB='mstr_discrete',
 CDS_PART_NAME='RES_0402-0.0,5%,1/16W,CHIP,G21A',
 PRIM_FILE='./archive_libs/mstr_discrete/res/chips/chips.prt';

PART_NAME
 R9P9 'RES_0402-3.74K,1%,1/16W,CHIP,GA':
 ROOM='V_SUPER';

SECTION_NUMBER 1
 '@BASEBOARD_FAB2_LIB.BASEBOARD_FAB2(SCH_1):PAGE200_I251@MSTR_DISCRETE.RES(CHIPS)':
 C_PATH='@baseboard_fab2_lib.baseboard_fab2(sch_1):page200_i251@mstr_discrete.re~
s(chips)',
 P_PATH='@baseboard_fab2_lib.baseboard_fab2(sch_1):page200_i251@mstr_discrete.re~
s(chips)',
 PATH='I251',
 DRAWING='@BASEBOARD_FAB2_LIB.BASEBOARD_FAB2(SCH_1):PAGE200',
 WATTAGE='1/16W',
 TOLERANCE='1%',
 SEC_TYPE='0402',
 MATERIAL='CHIP',
 PHYS_PAGE='200',
 XY='(-1975,375)',
 ROT='0',
 VER='2',
 VALUE='3.74K',
 PACK_TYPE='0402',
 PART_NUMBER='G21796-059',
 LOCATION='R9P9',
 ROOM='V_SUPER',
 SEC='1',
 CDS_LIB='mstr_discrete',
 CDS_PART_NAME='RES_0402-3.74K,1%,1/16W,CHIP,GA',
 PRIM_FILE='./archive_libs/mstr_discrete/res/chips/chips.prt';

PART_NAME
 R9P10 'RES_0402-10.0K,1%,1/16W,CHIP,GA':
 ROOM='HOT_SWAP';

SECTION_NUMBER 1
 '@BASEBOARD_FAB2_LIB.BASEBOARD_FAB2(SCH_1):PAGE200_I192@MSTR_DISCRETE.RES(CHIPS)':
 C_PATH='@baseboard_fab2_lib.baseboard_fab2(sch_1):page200_i192@mstr_discrete.re~
s(chips)',
 P_PATH='@baseboard_fab2_lib.baseboard_fab2(sch_1):page200_i192@mstr_discrete.re~
s(chips)',
 PATH='I192',
 DRAWING='@BASEBOARD_FAB2_LIB.BASEBOARD_FAB2(SCH_1):PAGE200',
 WATTAGE='1/16W',
 TOLERANCE='1%',
 SEC_TYPE='0402',
 MATERIAL='CHIP',
 PHYS_PAGE='200',
 XY='(275,1075)',
 ROT='0',
 VER='2',
 VALUE='10.0K',
 PACK_TYPE='0402',
 PART_NUMBER='G21796-016',
 LOCATION='R9P10',
 ROOM='HOT_SWAP',
 SEC='1',
 CDS_LIB='mstr_discrete',
 CDS_PART_NAME='RES_0402-10.0K,1%,1/16W,CHIP,GA',
 PRIM_FILE='./archive_libs/mstr_discrete/res/chips/chips.prt';

PART_NAME
 R9P11 'RES_0402-10.0K,1%,1/16W,CHIP,GA':
 ROOM='HOT_SWAP';

SECTION_NUMBER 1
 '@BASEBOARD_FAB2_LIB.BASEBOARD_FAB2(SCH_1):PAGE200_I108@MSTR_DISCRETE.RES(CHIPS)':
 C_PATH='@baseboard_fab2_lib.baseboard_fab2(sch_1):page200_i108@mstr_discrete.re~
s(chips)',
 P_PATH='@baseboard_fab2_lib.baseboard_fab2(sch_1):page200_i108@mstr_discrete.re~
s(chips)',
 PATH='I108',
 DRAWING='@BASEBOARD_FAB2_LIB.BASEBOARD_FAB2(SCH_1):PAGE200',
 CONFIG='64.1002D.6DL',
 WATTAGE='1/16W',
 TOLERANCE='1%',
 SEC_TYPE='0402',
 MATERIAL='CHIP',
 PHYS_PAGE='200',
 XY='(-1650,-150)',
 ROT='0',
 VER='2',
 VALUE='10.0K',
 PACK_TYPE='0402',
 PART_NUMBER='G21796-016',
 LOCATION='R9P11',
 ROOM='HOT_SWAP',
 SEC='1',
 CDS_LIB='mstr_discrete',
 CDS_PART_NAME='RES_0402-10.0K,1%,1/16W,CHIP,GA',
 PRIM_FILE='./archive_libs/mstr_discrete/res/chips/chips.prt';

PART_NAME
 R9P12 'RES_0402-4.99K,1%,1/16W,CHIP,GA':
 ROOM='HOT_SWAP';

SECTION_NUMBER 1
 '@BASEBOARD_FAB2_LIB.BASEBOARD_FAB2(SCH_1):PAGE200_I218@MSTR_DISCRETE.RES(CHIPS)':
 C_PATH='@baseboard_fab2_lib.baseboard_fab2(sch_1):page200_i218@mstr_discrete.re~
s(chips)',
 P_PATH='@baseboard_fab2_lib.baseboard_fab2(sch_1):page200_i218@mstr_discrete.re~
s(chips)',
 PATH='I218',
 DRAWING='@BASEBOARD_FAB2_LIB.BASEBOARD_FAB2(SCH_1):PAGE200',
 WATTAGE='1/16W',
 TOLERANCE='1%',
 SEC_TYPE='0402',
 MATERIAL='CHIP',
 PHYS_PAGE='200',
 XY='(-3950,-475)',
 ROT='0',
 VER='2',
 VALUE='4.99K',
 PACK_TYPE='0402',
 PART_NUMBER='G21796-013',
 LOCATION='R9P12',
 ROOM='HOT_SWAP',
 SEC='1',
 CDS_LIB='mstr_discrete',
 CDS_PART_NAME='RES_0402-4.99K,1%,1/16W,CHIP,GA',
 PRIM_FILE='./archive_libs/mstr_discrete/res/chips/chips.prt';

PART_NAME
 R9P13 '270KR2F-GP_RCL_GP-270KR2F-GP,6A':;

SECTION_NUMBER 1
 '@BASEBOARD_FAB2_LIB.BASEBOARD_FAB2(SCH_1):PAGE200_I249@W_HDL.270KR2F-GP(CHIPS)':
 C_PATH='@baseboard_fab2_lib.baseboard_fab2(sch_1):page200_i249@w_hdl.\270kr2f-g~
p\(chips)',
 P_PATH='@baseboard_fab2_lib.baseboard_fab2(sch_1):page200_i249@w_hdl.\270kr2f-g~
p\(chips)',
 PATH='I249',
 DRAWING='@BASEBOARD_FAB2_LIB.BASEBOARD_FAB2(SCH_1):PAGE200',
 PACK_SIZE='0402',
 RATED='1/16W',
 ATTRIBUTE='270KOHM',
 TOLERANCE='1%',
 SEC_TYPE='RCL_GP',
 PHYS_PAGE='200',
 XY='(-1650,275)',
 ROT='0',
 VER='1',
 VALUE='270KR2F-GP',
 PACK_TYPE='RCL_GP',
 PART_NUMBER='64.27035.6DL',
 LOCATION='R9P13',
 SEC='1',
 CDS_LIB='w_hdl',
 CDS_PART_NAME='270KR2F-GP_RCL_GP-270KR2F-GP,6A',
 PRIM_FILE='C:/<user>/w_hdl/270kr2f#2dgp/chips/chips.prt';

PART_NAME
 R9P15 'RES_0402-0.0,5%,1/16W,CHIP,G21A':;

SECTION_NUMBER 1
 '@BASEBOARD_FAB2_LIB.BASEBOARD_FAB2(SCH_1):PAGE200_I243@MSTR_DISCRETE.RES(CHIPS)':
 C_PATH='@baseboard_fab2_lib.baseboard_fab2(sch_1):page200_i243@mstr_discrete.re~
s(chips)',
 P_PATH='@baseboard_fab2_lib.baseboard_fab2(sch_1):page200_i243@mstr_discrete.re~
s(chips)',
 PATH='I243',
 DRAWING='@BASEBOARD_FAB2_LIB.BASEBOARD_FAB2(SCH_1):PAGE200',
 WATTAGE='1/16W',
 TOLERANCE='5%',
 SEC_TYPE='0402',
 MATERIAL='CHIP',
 PHYS_PAGE='200',
 XY='(-1750,3800)',
 ROT='0',
 VER='1',
 VALUE='0.0',
 PACK_TYPE='0402',
 PART_NUMBER='G21497-005',
 LOCATION='R9P15',
 SEC='1',
 CDS_LIB='mstr_discrete',
 CDS_PART_NAME='RES_0402-0.0,5%,1/16W,CHIP,G21A',
 PRIM_FILE='./archive_libs/mstr_discrete/res/chips/chips.prt';

PART_NAME
 R9P16 'RES_0402-0.0,5%,1/16W,CHIP,G21A':
 ROOM='HOT_SWAP';

SECTION_NUMBER 1
 '@BASEBOARD_FAB2_LIB.BASEBOARD_FAB2(SCH_1):PAGE199_I36@MSTR_DISCRETE.RES(CHIPS)':
 C_PATH='@baseboard_fab2_lib.baseboard_fab2(sch_1):page199_i36@mstr_discrete.res~
(chips)',
 P_PATH='@baseboard_fab2_lib.baseboard_fab2(sch_1):page199_i36@mstr_discrete.res~
(chips)',
 PATH='I36',
 DRAWING='@BASEBOARD_FAB2_LIB.BASEBOARD_FAB2(SCH_1):PAGE199',
 BOM_DS='NOPOP',
 WATTAGE='1/16W',
 TOLERANCE='5%',
 SEC_TYPE='0402',
 MATERIAL='CHIP',
 PHYS_PAGE='199',
 XY='(-7675,2375)',
 ROT='0',
 VER='2',
 VALUE='0.0',
 PACK_TYPE='0402',
 PART_NUMBER='G21497-005',
 LOCATION='R9P16',
 ROOM='HOT_SWAP',
 SEC='1',
 CDS_LIB='mstr_discrete',
 CDS_PART_NAME='RES_0402-0.0,5%,1/16W,CHIP,G21A',
 PRIM_FILE='./archive_libs/mstr_discrete/res/chips/chips.prt';

PART_NAME
 R9P17 'RES_0402-150.0K,1%,1/16W,CHIP,A':
 ROOM='HOT_SWAP';

SECTION_NUMBER 1
 '@BASEBOARD_FAB2_LIB.BASEBOARD_FAB2(SCH_1):PAGE199_I33@MSTR_DISCRETE.RES(CHIPS)':
 C_PATH='@baseboard_fab2_lib.baseboard_fab2(sch_1):page199_i33@mstr_discrete.res~
(chips)',
 P_PATH='@baseboard_fab2_lib.baseboard_fab2(sch_1):page199_i33@mstr_discrete.res~
(chips)',
 PATH='I33',
 DRAWING='@BASEBOARD_FAB2_LIB.BASEBOARD_FAB2(SCH_1):PAGE199',
 WATTAGE='1/16W',
 TOLERANCE='1%',
 SEC_TYPE='0402',
 MATERIAL='CHIP',
 PHYS_PAGE='199',
 XY='(-8000,2375)',
 ROT='0',
 VER='2',
 VALUE='150.0K',
 PACK_TYPE='0402',
 PART_NUMBER='G21796-109',
 LOCATION='R9P17',
 ROOM='HOT_SWAP',
 SEC='1',
 CDS_LIB='mstr_discrete',
 CDS_PART_NAME='RES_0402-150.0K,1%,1/16W,CHIP,A',
 PRIM_FILE='./archive_libs/mstr_discrete/res/chips/chips.prt';

PART_NAME
 R9P18 'RES_0402-15.0K,1%,1/16W,CHIP,GA':
 ROOM='HOT_SWAP';

SECTION_NUMBER 1
 '@BASEBOARD_FAB2_LIB.BASEBOARD_FAB2(SCH_1):PAGE199_I41@MSTR_DISCRETE.RES(CHIPS)':
 C_PATH='@baseboard_fab2_lib.baseboard_fab2(sch_1):page199_i41@mstr_discrete.res~
(chips)',
 P_PATH='@baseboard_fab2_lib.baseboard_fab2(sch_1):page199_i41@mstr_discrete.res~
(chips)',
 PATH='I41',
 DRAWING='@BASEBOARD_FAB2_LIB.BASEBOARD_FAB2(SCH_1):PAGE199',
 WATTAGE='1/16W',
 TOLERANCE='1%',
 SEC_TYPE='0402',
 MATERIAL='CHIP',
 BOM_COST='MIO_USB',
 PHYS_PAGE='199',
 XY='(-3125,1075)',
 ROT='2',
 VER='2',
 VALUE='15.0K',
 PACK_TYPE='0402',
 PART_NUMBER='G21796-107',
 LOCATION='R9P18',
 ROOM='HOT_SWAP',
 SEC='1',
 CDS_LIB='mstr_discrete',
 CDS_PART_NAME='RES_0402-15.0K,1%,1/16W,CHIP,GA',
 PRIM_FILE='./archive_libs/mstr_discrete/res/chips/chips.prt';

PART_NAME
 R9P19 'RES_0402-10.0K,1%,1/16W,EMPTY,A':
 ROOM='HOT_SWAP';

SECTION_NUMBER 1
 '@BASEBOARD_FAB2_LIB.BASEBOARD_FAB2(SCH_1):PAGE200_I70@MSTR_DISCRETE.RES(CHIPS)':
 C_PATH='@baseboard_fab2_lib.baseboard_fab2(sch_1):page200_i70@mstr_discrete.res~
(chips)',
 P_PATH='@baseboard_fab2_lib.baseboard_fab2(sch_1):page200_i70@mstr_discrete.res~
(chips)',
 PATH='I70',
 DRAWING='@BASEBOARD_FAB2_LIB.BASEBOARD_FAB2(SCH_1):PAGE200',
 WATTAGE='1/16W',
 TOLERANCE='1%',
 SEC_TYPE='0402',
 MATERIAL='EMPTY',
 PHYS_PAGE='200',
 XY='(-4400,-400)',
 ROT='0',
 VER='2',
 VALUE='10.0K',
 PACK_TYPE='0402',
 PART_NUMBER='G21796-016',
 LOCATION='R9P19',
 ROOM='HOT_SWAP',
 SEC='1',
 CDS_LIB='mstr_discrete',
 CDS_PART_NAME='RES_0402-10.0K,1%,1/16W,EMPTY,A',
 PRIM_FILE='./archive_libs/mstr_discrete/res/chips/chips.prt';

PART_NAME
 R9P20 'RES_0402-2.7K,1%,1/16W,CHIP,G2A':
 ROOM='HOT_SWAP';

SECTION_NUMBER 1
 '@BASEBOARD_FAB2_LIB.BASEBOARD_FAB2(SCH_1):PAGE200_I86@MSTR_DISCRETE.RES(CHIPS)':
 C_PATH='@baseboard_fab2_lib.baseboard_fab2(sch_1):page200_i86@mstr_discrete.res~
(chips)',
 P_PATH='@baseboard_fab2_lib.baseboard_fab2(sch_1):page200_i86@mstr_discrete.res~
(chips)',
 PATH='I86',
 DRAWING='@BASEBOARD_FAB2_LIB.BASEBOARD_FAB2(SCH_1):PAGE200',
 WATTAGE='1/16W',
 TOLERANCE='1%',
 SEC_TYPE='0402',
 MATERIAL='CHIP',
 PHYS_PAGE='200',
 XY='(-3300,450)',
 ROT='0',
 VER='2',
 VALUE='2.7K',
 PACK_TYPE='0402',
 PART_NUMBER='G21796-344',
 LOCATION='R9P20',
 ROOM='HOT_SWAP',
 SEC='1',
 CDS_LIB='mstr_discrete',
 CDS_PART_NAME='RES_0402-2.7K,1%,1/16W,CHIP,G2A',
 PRIM_FILE='./archive_libs/mstr_discrete/res/chips/chips.prt';

PART_NAME
 R9P21 'RES_0402-0.0,5%,1/16W,CHIP,G21A':
 ROOM='HOT_SWAP';

SECTION_NUMBER 1
 '@BASEBOARD_FAB2_LIB.BASEBOARD_FAB2(SCH_1):PAGE200_I71@MSTR_DISCRETE.RES(CHIPS)':
 C_PATH='@baseboard_fab2_lib.baseboard_fab2(sch_1):page200_i71@mstr_discrete.res~
(chips)',
 P_PATH='@baseboard_fab2_lib.baseboard_fab2(sch_1):page200_i71@mstr_discrete.res~
(chips)',
 PATH='I71',
 DRAWING='@BASEBOARD_FAB2_LIB.BASEBOARD_FAB2(SCH_1):PAGE200',
 WATTAGE='1/16W',
 TOLERANCE='5%',
 SEC_TYPE='0402',
 MATERIAL='CHIP',
 PHYS_PAGE='200',
 XY='(-4400,250)',
 ROT='0',
 VER='2',
 VALUE='0.0',
 PACK_TYPE='0402',
 PART_NUMBER='G21497-005',
 LOCATION='R9P21',
 ROOM='HOT_SWAP',
 SEC='1',
 CDS_LIB='mstr_discrete',
 CDS_PART_NAME='RES_0402-0.0,5%,1/16W,CHIP,G21A',
 PRIM_FILE='./archive_libs/mstr_discrete/res/chips/chips.prt';

PART_NAME
 R9P22 'RES_0402-0.0,5%,1/16W,CHIP,G21A':
 ROOM='CPU0';

SECTION_NUMBER 1
 '@BASEBOARD_FAB2_LIB.BASEBOARD_FAB2(SCH_1):PAGE208_I114@MSTR_DISCRETE.RES(CHIPS)':
 C_PATH='@baseboard_fab2_lib.baseboard_fab2(sch_1):page208_i114@mstr_discrete.re~
s(chips)',
 P_PATH='@baseboard_fab2_lib.baseboard_fab2(sch_1):page208_i114@mstr_discrete.re~
s(chips)',
 PATH='I114',
 DRAWING='@BASEBOARD_FAB2_LIB.BASEBOARD_FAB2(SCH_1):PAGE208',
 WATTAGE='1/16W',
 TOLERANCE='5%',
 SEC_TYPE='0402',
 MATERIAL='CHIP',
 BOM_COST='PROC_SIDEBAND',
 PHYS_PAGE='208',
 XY='(-5350,4700)',
 ROT='0',
 VER='1',
 VALUE='0.0',
 PACK_TYPE='0402',
 PART_NUMBER='G21497-005',
 LOCATION='R9P22',
 ROOM='CPU0',
 SEC='1',
 CDS_LIB='mstr_discrete',
 CDS_PART_NAME='RES_0402-0.0,5%,1/16W,CHIP,G21A',
 PRIM_FILE='./archive_libs/mstr_discrete/res/chips/chips.prt';

PART_NAME
 R9P23 'RES_0402-100.0K,1%,1/16W,CHIP,A':
 ROOM='HOT_SWAP';

SECTION_NUMBER 1
 '@BASEBOARD_FAB2_LIB.BASEBOARD_FAB2(SCH_1):PAGE199_I54@MSTR_DISCRETE.RES(CHIPS)':
 C_PATH='@baseboard_fab2_lib.baseboard_fab2(sch_1):page199_i54@mstr_discrete.res~
(chips)',
 P_PATH='@baseboard_fab2_lib.baseboard_fab2(sch_1):page199_i54@mstr_discrete.res~
(chips)',
 PATH='I54',
 DRAWING='@BASEBOARD_FAB2_LIB.BASEBOARD_FAB2(SCH_1):PAGE199',
 WATTAGE='1/16W',
 TOLERANCE='1%',
 SEC_TYPE='0402',
 MATERIAL='CHIP',
 PHYS_PAGE='199',
 XY='(-6725,2025)',
 ROT='0',
 VER='2',
 VALUE='100.0K',
 PACK_TYPE='0402',
 PART_NUMBER='G21796-010',
 LOCATION='R9P23',
 ROOM='HOT_SWAP',
 SEC='1',
 CDS_LIB='mstr_discrete',
 CDS_PART_NAME='RES_0402-100.0K,1%,1/16W,CHIP,A',
 PRIM_FILE='./archive_libs/mstr_discrete/res/chips/chips.prt';

PART_NAME
 R9P24 'RES_0402-12.1K,1%,1/16W,CHIP,GA':
 ROOM='HOT_SWAP';

SECTION_NUMBER 1
 '@BASEBOARD_FAB2_LIB.BASEBOARD_FAB2(SCH_1):PAGE199_I55@MSTR_DISCRETE.RES(CHIPS)':
 C_PATH='@baseboard_fab2_lib.baseboard_fab2(sch_1):page199_i55@mstr_discrete.res~
(chips)',
 P_PATH='@baseboard_fab2_lib.baseboard_fab2(sch_1):page199_i55@mstr_discrete.res~
(chips)',
 PATH='I55',
 DRAWING='@BASEBOARD_FAB2_LIB.BASEBOARD_FAB2(SCH_1):PAGE199',
 WATTAGE='1/16W',
 TOLERANCE='1%',
 SEC_TYPE='0402',
 MATERIAL='CHIP',
 BOM_COST='MIO_USB',
 PHYS_PAGE='199',
 XY='(-6725,1725)',
 ROT='2',
 VER='2',
 VALUE='12.1K',
 PACK_TYPE='0402',
 PART_NUMBER='G21796-089',
 LOCATION='R9P24',
 ROOM='HOT_SWAP',
 SEC='1',
 CDS_LIB='mstr_discrete',
 CDS_PART_NAME='RES_0402-12.1K,1%,1/16W,CHIP,GA',
 PRIM_FILE='./archive_libs/mstr_discrete/res/chips/chips.prt';

PART_NAME
 R9P26 'RES_0402-10.0,1%,1/16W,CHIP,G2A':
 ROOM='HOT_SWAP';

SECTION_NUMBER 1
 '@BASEBOARD_FAB2_LIB.BASEBOARD_FAB2(SCH_1):PAGE200_I51@MSTR_DISCRETE.RES(CHIPS)':
 C_PATH='@baseboard_fab2_lib.baseboard_fab2(sch_1):page200_i51@mstr_discrete.res~
(chips)',
 P_PATH='@baseboard_fab2_lib.baseboard_fab2(sch_1):page200_i51@mstr_discrete.res~
(chips)',
 PATH='I51',
 DRAWING='@BASEBOARD_FAB2_LIB.BASEBOARD_FAB2(SCH_1):PAGE200',
 WATTAGE='1/16W',
 TOLERANCE='1%',
 MATERIAL='CHIP',
 PHYS_PAGE='200',
 XY='(1350,2800)',
 ROT='2',
 VER='2',
 VALUE='10.0',
 PACK_TYPE='0402',
 PART_NUMBER='G21796-066',
 LOCATION='R9P26',
 ROOM='HOT_SWAP',
 CDS_LIB='mstr_discrete',
 CDS_PART_NAME='RES_0402-10.0,1%,1/16W,CHIP,G2A',
 PRIM_FILE='./archive_libs/mstr_discrete/res/chips/chips.prt';

PART_NAME
 R9P27 'RES_0402-10.0,1%,1/16W,CHIP,G2A':
 ROOM='HOT_SWAP';

SECTION_NUMBER 1
 '@BASEBOARD_FAB2_LIB.BASEBOARD_FAB2(SCH_1):PAGE200_I47@MSTR_DISCRETE.RES(CHIPS)':
 C_PATH='@baseboard_fab2_lib.baseboard_fab2(sch_1):page200_i47@mstr_discrete.res~
(chips)',
 P_PATH='@baseboard_fab2_lib.baseboard_fab2(sch_1):page200_i47@mstr_discrete.res~
(chips)',
 PATH='I47',
 DRAWING='@BASEBOARD_FAB2_LIB.BASEBOARD_FAB2(SCH_1):PAGE200',
 WATTAGE='1/16W',
 TOLERANCE='1%',
 MATERIAL='CHIP',
 PHYS_PAGE='200',
 XY='(875,2800)',
 ROT='0',
 VER='2',
 VALUE='10.0',
 PACK_TYPE='0402',
 PART_NUMBER='G21796-066',
 LOCATION='R9P27',
 ROOM='HOT_SWAP',
 CDS_LIB='mstr_discrete',
 CDS_PART_NAME='RES_0402-10.0,1%,1/16W,CHIP,G2A',
 PRIM_FILE='./archive_libs/mstr_discrete/res/chips/chips.prt';

PART_NAME
 R9P28 'RES_0402-100.0K,1%,1/16W,CHIP,A':
 ROOM='HOT_SWAP';

SECTION_NUMBER 1
 '@BASEBOARD_FAB2_LIB.BASEBOARD_FAB2(SCH_1):PAGE199_I138@MSTR_DISCRETE.RES(CHIPS)':
 C_PATH='@baseboard_fab2_lib.baseboard_fab2(sch_1):page199_i138@mstr_discrete.re~
s(chips)',
 P_PATH='@baseboard_fab2_lib.baseboard_fab2(sch_1):page199_i138@mstr_discrete.re~
s(chips)',
 PATH='I138',
 DRAWING='@BASEBOARD_FAB2_LIB.BASEBOARD_FAB2(SCH_1):PAGE199',
 WATTAGE='1/16W',
 TOLERANCE='1%',
 SEC_TYPE='0402',
 MATERIAL='CHIP',
 PHYS_PAGE='199',
 XY='(-7200,4025)',
 ROT='0',
 VER='2',
 VALUE='100.0K',
 PACK_TYPE='0402',
 PART_NUMBER='G21796-010',
 LOCATION='R9P28',
 ROOM='HOT_SWAP',
 SEC='1',
 CDS_LIB='mstr_discrete',
 CDS_PART_NAME='RES_0402-100.0K,1%,1/16W,CHIP,A',
 PRIM_FILE='./archive_libs/mstr_discrete/res/chips/chips.prt';

PART_NAME
 R9P29 'RES_0402-100.0K,1%,1/16W,CHIP,A':
 ROOM='HOT_SWAP';

SECTION_NUMBER 1
 '@BASEBOARD_FAB2_LIB.BASEBOARD_FAB2(SCH_1):PAGE199_I12@MSTR_DISCRETE.RES(CHIPS)':
 C_PATH='@baseboard_fab2_lib.baseboard_fab2(sch_1):page199_i12@mstr_discrete.res~
(chips)',
 P_PATH='@baseboard_fab2_lib.baseboard_fab2(sch_1):page199_i12@mstr_discrete.res~
(chips)',
 PATH='I12',
 DRAWING='@BASEBOARD_FAB2_LIB.BASEBOARD_FAB2(SCH_1):PAGE199',
 WATTAGE='1/16W',
 TOLERANCE='1%',
 SEC_TYPE='0402',
 MATERIAL='CHIP',
 PHYS_PAGE='199',
 XY='(-6500,4050)',
 ROT='0',
 VER='2',
 VALUE='100.0K',
 PACK_TYPE='0402',
 PART_NUMBER='G21796-010',
 LOCATION='R9P29',
 ROOM='HOT_SWAP',
 SEC='1',
 CDS_LIB='mstr_discrete',
 CDS_PART_NAME='RES_0402-100.0K,1%,1/16W,CHIP,A',
 PRIM_FILE='./archive_libs/mstr_discrete/res/chips/chips.prt';

PART_NAME
 R9P30 'RES_0603-10.0,1%,1/10W,CHIP,G2A':
 ROOM='HOT_SWAP';

SECTION_NUMBER 1
 '@BASEBOARD_FAB2_LIB.BASEBOARD_FAB2(SCH_1):PAGE199_I2@MSTR_DISCRETE.RES(CHIPS)':
 C_PATH='@baseboard_fab2_lib.baseboard_fab2(sch_1):page199_i2@mstr_discrete.res(~
chips)',
 P_PATH='@baseboard_fab2_lib.baseboard_fab2(sch_1):page199_i2@mstr_discrete.res(~
chips)',
 PATH='I2',
 DRAWING='@BASEBOARD_FAB2_LIB.BASEBOARD_FAB2(SCH_1):PAGE199',
 WATTAGE='1/10W',
 TOLERANCE='1%',
 SEC_TYPE='0603',
 MATERIAL='CHIP',
 PHYS_PAGE='199',
 XY='(-5525,4025)',
 ROT='0',
 VER='2',
 VALUE='10.0',
 PACK_TYPE='0603',
 PART_NUMBER='G22026-041',
 LOCATION='R9P30',
 ROOM='HOT_SWAP',
 SEC='1',
 CDS_LIB='mstr_discrete',
 CDS_PART_NAME='RES_0603-10.0,1%,1/10W,CHIP,G2A',
 PRIM_FILE='./archive_libs/mstr_discrete/res/chips/chips.prt';

PART_NAME
 R9P32 'RES_0402-0.0,5%,1/16W,CHIP,G21A':
 ROOM='CPU0';

SECTION_NUMBER 1
 '@BASEBOARD_FAB2_LIB.BASEBOARD_FAB2(SCH_1):PAGE209_I79@MSTR_DISCRETE.RES(CHIPS)':
 C_PATH='@baseboard_fab2_lib.baseboard_fab2(sch_1):page209_i79@mstr_discrete.res~
(chips)',
 P_PATH='@baseboard_fab2_lib.baseboard_fab2(sch_1):page209_i79@mstr_discrete.res~
(chips)',
 PATH='I79',
 DRAWING='@BASEBOARD_FAB2_LIB.BASEBOARD_FAB2(SCH_1):PAGE209',
 WATTAGE='1/16W',
 TOLERANCE='5%',
 SEC_TYPE='0402',
 MATERIAL='CHIP',
 BOM_COST='PROC_SIDEBAND',
 PHYS_PAGE='209',
 XY='(-5425,4650)',
 ROT='0',
 VER='1',
 VALUE='0.0',
 PACK_TYPE='0402',
 PART_NUMBER='G21497-005',
 LOCATION='R9P32',
 ROOM='CPU0',
 SEC='1',
 CDS_LIB='mstr_discrete',
 CDS_PART_NAME='RES_0402-0.0,5%,1/16W,CHIP,G21A',
 PRIM_FILE='./archive_libs/mstr_discrete/res/chips/chips.prt';

PART_NAME
 R9P33 'RES_0402-100.0K,1%,1/16W,CHIP,A':
 ROOM='HOT_SWAP';

SECTION_NUMBER 1
 '@BASEBOARD_FAB2_LIB.BASEBOARD_FAB2(SCH_1):PAGE200_I222@MSTR_DISCRETE.RES(CHIPS)':
 C_PATH='@baseboard_fab2_lib.baseboard_fab2(sch_1):page200_i222@mstr_discrete.re~
s(chips)',
 P_PATH='@baseboard_fab2_lib.baseboard_fab2(sch_1):page200_i222@mstr_discrete.re~
s(chips)',
 PATH='I222',
 DRAWING='@BASEBOARD_FAB2_LIB.BASEBOARD_FAB2(SCH_1):PAGE200',
 WATTAGE='1/16W',
 TOLERANCE='1%',
 MATERIAL='CHIP',
 PHYS_PAGE='200',
 XY='(-3950,200)',
 ROT='2',
 VER='2',
 VALUE='100.0K',
 PACK_TYPE='0402',
 PART_NUMBER='G21796-010',
 LOCATION='R9P33',
 ROOM='HOT_SWAP',
 CDS_LIB='mstr_discrete',
 CDS_PART_NAME='RES_0402-100.0K,1%,1/16W,CHIP,A',
 PRIM_FILE='./archive_libs/mstr_discrete/res/chips/chips.prt';

PART_NAME
 R9R1 'RES_PWR_6PAD-0.001,1%,3W,CHIP,A':
 ROOM='HOT_SWAP';

SECTION_NUMBER 1
 '@BASEBOARD_FAB2_LIB.BASEBOARD_FAB2(SCH_1):PAGE200_I49@MSTR_DISCRETE.RES_PWR(CHIPS)':
 C_PATH='@baseboard_fab2_lib.baseboard_fab2(sch_1):page200_i49@mstr_discrete.res~
_pwr(chips)',
 P_PATH='@baseboard_fab2_lib.baseboard_fab2(sch_1):page200_i49@mstr_discrete.res~
_pwr(chips)',
 PATH='I49',
 DRAWING='@BASEBOARD_FAB2_LIB.BASEBOARD_FAB2(SCH_1):PAGE200',
 BOM_DS='064.0U505.0C71',
 WATTAGE='3W',
 TOLERANCE='1%',
 SEC_TYPE='6PAD',
 MATERIAL='CHIP',
 PHYS_PAGE='200',
 XY='(1125,3200)',
 ROT='0',
 VER='2',
 VALUE='0.001',
 PACK_TYPE='6PAD',
 PART_NUMBER='E74391-005',
 LOCATION='R9R1',
 ROOM='HOT_SWAP',
 SEC='1',
 CDS_LIB='mstr_discrete',
 CDS_PART_NAME='RES_PWR_6PAD-0.001,1%,3W,CHIP,A',
 PRIM_FILE='./archive_libs/mstr_discrete/res_pwr/chips/chips.prt';

PART_NAME
 R9R2 'RES_0402-0.0,5%,1/16W,CHIP,G21A':
 ROOM='CPU0';

SECTION_NUMBER 1
 '@BASEBOARD_FAB2_LIB.BASEBOARD_FAB2(SCH_1):PAGE207_I106@MSTR_DISCRETE.RES(CHIPS)':
 C_PATH='@baseboard_fab2_lib.baseboard_fab2(sch_1):page207_i106@mstr_discrete.re~
s(chips)',
 P_PATH='@baseboard_fab2_lib.baseboard_fab2(sch_1):page207_i106@mstr_discrete.re~
s(chips)',
 PATH='I106',
 DRAWING='@BASEBOARD_FAB2_LIB.BASEBOARD_FAB2(SCH_1):PAGE207',
 WATTAGE='1/16W',
 TOLERANCE='5%',
 SEC_TYPE='0402',
 MATERIAL='CHIP',
 BOM_COST='PROC_SIDEBAND',
 PHYS_PAGE='207',
 XY='(-5400,4650)',
 ROT='0',
 VER='1',
 VALUE='0.0',
 PACK_TYPE='0402',
 PART_NUMBER='G21497-005',
 LOCATION='R9R2',
 ROOM='CPU0',
 SEC='1',
 CDS_LIB='mstr_discrete',
 CDS_PART_NAME='RES_0402-0.0,5%,1/16W,CHIP,G21A',
 PRIM_FILE='./archive_libs/mstr_discrete/res/chips/chips.prt';

PART_NAME
 R9R4 'RES_0402-10.0,1%,1/16W,CHIP,G2A':
 ROOM='HOT_SWAP';

SECTION_NUMBER 1
 '@BASEBOARD_FAB2_LIB.BASEBOARD_FAB2(SCH_1):PAGE200_I58@MSTR_DISCRETE.RES(CHIPS)':
 C_PATH='@baseboard_fab2_lib.baseboard_fab2(sch_1):page200_i58@mstr_discrete.res~
(chips)',
 P_PATH='@baseboard_fab2_lib.baseboard_fab2(sch_1):page200_i58@mstr_discrete.res~
(chips)',
 PATH='I58',
 DRAWING='@BASEBOARD_FAB2_LIB.BASEBOARD_FAB2(SCH_1):PAGE200',
 WATTAGE='1/16W',
 TOLERANCE='1%',
 MATERIAL='CHIP',
 PHYS_PAGE='200',
 XY='(2000,2525)',
 ROT='0',
 VER='1',
 VALUE='10.0',
 PACK_TYPE='0402',
 PART_NUMBER='G21796-066',
 LOCATION='R9R4',
 ROOM='HOT_SWAP',
 CDS_LIB='mstr_discrete',
 CDS_PART_NAME='RES_0402-10.0,1%,1/16W,CHIP,G2A',
 PRIM_FILE='./archive_libs/mstr_discrete/res/chips/chips.prt';

PART_NAME
 R9R5 'RES_0402-49.9,1%,1/16W,CHIP,G2A':
 ROOM='TEMP_SENSORS';

SECTION_NUMBER 1
 '@BASEBOARD_FAB2_LIB.BASEBOARD_FAB2(SCH_1):PAGE167_I25@MSTR_DISCRETE.RES(CHIPS)':
 C_PATH='@baseboard_fab2_lib.baseboard_fab2(sch_1):page167_i25@mstr_discrete.res~
(chips)',
 P_PATH='@baseboard_fab2_lib.baseboard_fab2(sch_1):page167_i25@mstr_discrete.res~
(chips)',
 PATH='I25',
 DRAWING='@BASEBOARD_FAB2_LIB.BASEBOARD_FAB2(SCH_1):PAGE167',
 WATTAGE='1/16W',
 TOLERANCE='1%',
 SEC_TYPE='0402',
 MATERIAL='CHIP',
 BOM_COST='SM_THERM',
 PHYS_PAGE='167',
 XY='(-5000,3325)',
 ROT='0',
 VER='1',
 VALUE='49.9',
 PACK_TYPE='0402',
 PART_NUMBER='G21796-047',
 LOCATION='R9R5',
 ROOM='TEMP_SENSORS',
 SEC='1',
 CDS_LIB='mstr_discrete',
 CDS_PART_NAME='RES_0402-49.9,1%,1/16W,CHIP,G2A',
 PRIM_FILE='./archive_libs/mstr_discrete/res/chips/chips.prt';

PART_NAME
 R9R6 'RES_0402-49.9,1%,1/16W,CHIP,G2A':
 ROOM='TEMP_SENSORS';

SECTION_NUMBER 1
 '@BASEBOARD_FAB2_LIB.BASEBOARD_FAB2(SCH_1):PAGE167_I26@MSTR_DISCRETE.RES(CHIPS)':
 C_PATH='@baseboard_fab2_lib.baseboard_fab2(sch_1):page167_i26@mstr_discrete.res~
(chips)',
 P_PATH='@baseboard_fab2_lib.baseboard_fab2(sch_1):page167_i26@mstr_discrete.res~
(chips)',
 PATH='I26',
 DRAWING='@BASEBOARD_FAB2_LIB.BASEBOARD_FAB2(SCH_1):PAGE167',
 WATTAGE='1/16W',
 TOLERANCE='1%',
 SEC_TYPE='0402',
 MATERIAL='CHIP',
 BOM_COST='SM_THERM',
 PHYS_PAGE='167',
 XY='(-4975,3000)',
 ROT='0',
 VER='1',
 VALUE='49.9',
 PACK_TYPE='0402',
 PART_NUMBER='G21796-047',
 LOCATION='R9R6',
 ROOM='TEMP_SENSORS',
 SEC='1',
 CDS_LIB='mstr_discrete',
 CDS_PART_NAME='RES_0402-49.9,1%,1/16W,CHIP,G2A',
 PRIM_FILE='./archive_libs/mstr_discrete/res/chips/chips.prt';

PART_NAME
 R9R7 'RES_0402-20.0,1%,1/16W,CHIP,G2A':
 ROOM='TEMP_SENSORS';

SECTION_NUMBER 1
 '@BASEBOARD_FAB2_LIB.BASEBOARD_FAB2(SCH_1):PAGE167_I75@MSTR_DISCRETE.RES(CHIPS)':
 C_PATH='@baseboard_fab2_lib.baseboard_fab2(sch_1):page167_i75@mstr_discrete.res~
(chips)',
 P_PATH='@baseboard_fab2_lib.baseboard_fab2(sch_1):page167_i75@mstr_discrete.res~
(chips)',
 PATH='I75',
 DRAWING='@BASEBOARD_FAB2_LIB.BASEBOARD_FAB2(SCH_1):PAGE167',
 WATTAGE='1/16W',
 TOLERANCE='1%',
 SEC_TYPE='0402',
 MATERIAL='CHIP',
 BOM_COST='SM_THERM',
 PHYS_PAGE='167',
 XY='(-2300,3000)',
 ROT='0',
 VER='1',
 VALUE='20.0',
 PACK_TYPE='0402',
 PART_NUMBER='G21796-173',
 LOCATION='R9R7',
 ROOM='TEMP_SENSORS',
 SEC='1',
 CDS_LIB='mstr_discrete',
 CDS_PART_NAME='RES_0402-20.0,1%,1/16W,CHIP,G2A',
 PRIM_FILE='./archive_libs/mstr_discrete/res/chips/chips.prt';

PART_NAME
 R9R8 'RES_0402-20.0,1%,1/16W,CHIP,G2A':
 ROOM='TEMP_SENSORS';

SECTION_NUMBER 1
 '@BASEBOARD_FAB2_LIB.BASEBOARD_FAB2(SCH_1):PAGE167_I76@MSTR_DISCRETE.RES(CHIPS)':
 C_PATH='@baseboard_fab2_lib.baseboard_fab2(sch_1):page167_i76@mstr_discrete.res~
(chips)',
 P_PATH='@baseboard_fab2_lib.baseboard_fab2(sch_1):page167_i76@mstr_discrete.res~
(chips)',
 PATH='I76',
 DRAWING='@BASEBOARD_FAB2_LIB.BASEBOARD_FAB2(SCH_1):PAGE167',
 WATTAGE='1/16W',
 TOLERANCE='1%',
 SEC_TYPE='0402',
 MATERIAL='CHIP',
 BOM_COST='SM_THERM',
 PHYS_PAGE='167',
 XY='(-2625,3050)',
 ROT='0',
 VER='1',
 VALUE='20.0',
 PACK_TYPE='0402',
 PART_NUMBER='G21796-173',
 LOCATION='R9R8',
 ROOM='TEMP_SENSORS',
 SEC='1',
 CDS_LIB='mstr_discrete',
 CDS_PART_NAME='RES_0402-20.0,1%,1/16W,CHIP,G2A',
 PRIM_FILE='./archive_libs/mstr_discrete/res/chips/chips.prt';

PART_NAME
 R9R9 'RES_0402-0.0,5%,1/16W,CHIP,G21A':;

SECTION_NUMBER 1
 '@BASEBOARD_FAB2_LIB.BASEBOARD_FAB2(SCH_1):PAGE181_I32@MSTR_DISCRETE.RES(CHIPS)':
 C_PATH='@baseboard_fab2_lib.baseboard_fab2(sch_1):page181_i32@mstr_discrete.res~
(chips)',
 P_PATH='@baseboard_fab2_lib.baseboard_fab2(sch_1):page181_i32@mstr_discrete.res~
(chips)',
 PATH='I32',
 DRAWING='@BASEBOARD_FAB2_LIB.BASEBOARD_FAB2(SCH_1):PAGE181',
 WATTAGE='1/16W',
 TOLERANCE='5%',
 SEC_TYPE='0402',
 MATERIAL='CHIP',
 PHYS_PAGE='181',
 XY='(-1525,2950)',
 ROT='0',
 VER='1',
 VALUE='0.0',
 PACK_TYPE='0402',
 PART_NUMBER='G21497-005',
 LOCATION='R9R9',
 SEC='1',
 CDS_LIB='mstr_discrete',
 CDS_PART_NAME='RES_0402-0.0,5%,1/16W,CHIP,G21A',
 PRIM_FILE='./archive_libs/mstr_discrete/res/chips/chips.prt';

PART_NAME
 R9R10 'RES_0402-0.0,5%,1/16W,CHIP,G21A':;

SECTION_NUMBER 1
 '@BASEBOARD_FAB2_LIB.BASEBOARD_FAB2(SCH_1):PAGE181_I31@MSTR_DISCRETE.RES(CHIPS)':
 C_PATH='@baseboard_fab2_lib.baseboard_fab2(sch_1):page181_i31@mstr_discrete.res~
(chips)',
 P_PATH='@baseboard_fab2_lib.baseboard_fab2(sch_1):page181_i31@mstr_discrete.res~
(chips)',
 PATH='I31',
 DRAWING='@BASEBOARD_FAB2_LIB.BASEBOARD_FAB2(SCH_1):PAGE181',
 WATTAGE='1/16W',
 TOLERANCE='5%',
 SEC_TYPE='0402',
 MATERIAL='CHIP',
 PHYS_PAGE='181',
 XY='(-1525,2850)',
 ROT='0',
 VER='1',
 VALUE='0.0',
 PACK_TYPE='0402',
 PART_NUMBER='G21497-005',
 LOCATION='R9R10',
 SEC='1',
 CDS_LIB='mstr_discrete',
 CDS_PART_NAME='RES_0402-0.0,5%,1/16W,CHIP,G21A',
 PRIM_FILE='./archive_libs/mstr_discrete/res/chips/chips.prt';

PART_NAME
 R9R11 'RES_0402-0.0,5%,1/16W,CHIP,G21A':
 ROOM='CPU0';

SECTION_NUMBER 1
 '@BASEBOARD_FAB2_LIB.BASEBOARD_FAB2(SCH_1):PAGE207_I105@MSTR_DISCRETE.RES(CHIPS)':
 C_PATH='@baseboard_fab2_lib.baseboard_fab2(sch_1):page207_i105@mstr_discrete.re~
s(chips)',
 P_PATH='@baseboard_fab2_lib.baseboard_fab2(sch_1):page207_i105@mstr_discrete.re~
s(chips)',
 PATH='I105',
 DRAWING='@BASEBOARD_FAB2_LIB.BASEBOARD_FAB2(SCH_1):PAGE207',
 WATTAGE='1/16W',
 TOLERANCE='5%',
 SEC_TYPE='0402',
 MATERIAL='CHIP',
 BOM_COST='PROC_SIDEBAND',
 PHYS_PAGE='207',
 XY='(-5300,2050)',
 ROT='0',
 VER='1',
 VALUE='0.0',
 PACK_TYPE='0402',
 PART_NUMBER='G21497-005',
 LOCATION='R9R11',
 ROOM='CPU0',
 SEC='1',
 CDS_LIB='mstr_discrete',
 CDS_PART_NAME='RES_0402-0.0,5%,1/16W,CHIP,G21A',
 PRIM_FILE='./archive_libs/mstr_discrete/res/chips/chips.prt';

PART_NAME
 R9R12 'RES_0402-0.0,5%,1/16W,CHIP,G21A':;

SECTION_NUMBER 1
 '@BASEBOARD_FAB2_LIB.BASEBOARD_FAB2(SCH_1):PAGE181_I27@MSTR_DISCRETE.RES(CHIPS)':
 C_PATH='@baseboard_fab2_lib.baseboard_fab2(sch_1):page181_i27@mstr_discrete.res~
(chips)',
 P_PATH='@baseboard_fab2_lib.baseboard_fab2(sch_1):page181_i27@mstr_discrete.res~
(chips)',
 PATH='I27',
 DRAWING='@BASEBOARD_FAB2_LIB.BASEBOARD_FAB2(SCH_1):PAGE181',
 WATTAGE='1/16W',
 TOLERANCE='5%',
 SEC_TYPE='0402',
 MATERIAL='CHIP',
 PHYS_PAGE='181',
 XY='(-2225,2900)',
 ROT='0',
 VER='1',
 VALUE='0.0',
 PACK_TYPE='0402',
 PART_NUMBER='G21497-005',
 LOCATION='R9R12',
 SEC='1',
 CDS_LIB='mstr_discrete',
 CDS_PART_NAME='RES_0402-0.0,5%,1/16W,CHIP,G21A',
 PRIM_FILE='./archive_libs/mstr_discrete/res/chips/chips.prt';

PART_NAME
 R9T1 'RES_0402-0.0,5%,1/16W,CHIP,G21A':;

SECTION_NUMBER 1
 '@BASEBOARD_FAB2_LIB.BASEBOARD_FAB2(SCH_1):PAGE181_I26@MSTR_DISCRETE.RES(CHIPS)':
 C_PATH='@baseboard_fab2_lib.baseboard_fab2(sch_1):page181_i26@mstr_discrete.res~
(chips)',
 P_PATH='@baseboard_fab2_lib.baseboard_fab2(sch_1):page181_i26@mstr_discrete.res~
(chips)',
 PATH='I26',
 DRAWING='@BASEBOARD_FAB2_LIB.BASEBOARD_FAB2(SCH_1):PAGE181',
 WATTAGE='1/16W',
 TOLERANCE='5%',
 SEC_TYPE='0402',
 MATERIAL='CHIP',
 PHYS_PAGE='181',
 XY='(-1500,2700)',
 ROT='0',
 VER='1',
 VALUE='0.0',
 PACK_TYPE='0402',
 PART_NUMBER='G21497-005',
 LOCATION='R9T1',
 SEC='1',
 CDS_LIB='mstr_discrete',
 CDS_PART_NAME='RES_0402-0.0,5%,1/16W,CHIP,G21A',
 PRIM_FILE='./archive_libs/mstr_discrete/res/chips/chips.prt';

PART_NAME
 R9T3 'RES_0402-6.19K,1%,1/16W,CHIP,GA':
 ROOM='IO_SLOT';

SECTION_NUMBER 1
 '@BASEBOARD_FAB2_LIB.BASEBOARD_FAB2(SCH_1):PAGE181_I64@MSTR_DISCRETE.RES(CHIPS)':
 C_PATH='@baseboard_fab2_lib.baseboard_fab2(sch_1):page181_i64@mstr_discrete.res~
(chips)',
 P_PATH='@baseboard_fab2_lib.baseboard_fab2(sch_1):page181_i64@mstr_discrete.res~
(chips)',
 PATH='I64',
 DRAWING='@BASEBOARD_FAB2_LIB.BASEBOARD_FAB2(SCH_1):PAGE181',
 WATTAGE='1/16W',
 TOLERANCE='1%',
 SEC_TYPE='0402',
 MATERIAL='CHIP',
 BOM_COST='IO_SLOT',
 PHYS_PAGE='181',
 XY='(1150,1550)',
 ROT='0',
 VER='2',
 VALUE='6.19K',
 PACK_TYPE='0402',
 PART_NUMBER='G21796-161',
 LOCATION='R9T3',
 ROOM='IO_SLOT',
 SEC='1',
 CDS_LIB='mstr_discrete',
 CDS_PART_NAME='RES_0402-6.19K,1%,1/16W,CHIP,GA',
 PRIM_FILE='./archive_libs/mstr_discrete/res/chips/chips.prt';

PART_NAME
 R9T6 'RES_0402-15.0K,1%,1/16W,CHIP,GA':
 ROOM='IO_SLOT';

SECTION_NUMBER 1
 '@BASEBOARD_FAB2_LIB.BASEBOARD_FAB2(SCH_1):PAGE181_I68@MSTR_DISCRETE.RES(CHIPS)':
 C_PATH='@baseboard_fab2_lib.baseboard_fab2(sch_1):page181_i68@mstr_discrete.res~
(chips)',
 P_PATH='@baseboard_fab2_lib.baseboard_fab2(sch_1):page181_i68@mstr_discrete.res~
(chips)',
 PATH='I68',
 DRAWING='@BASEBOARD_FAB2_LIB.BASEBOARD_FAB2(SCH_1):PAGE181',
 WATTAGE='1/16W',
 TOLERANCE='1%',
 SEC_TYPE='0402',
 MATERIAL='CHIP',
 BOM_COST='IO_SLOT',
 PHYS_PAGE='181',
 XY='(1050,1900)',
 ROT='2',
 VER='2',
 VALUE='15.0K',
 PACK_TYPE='0402',
 PART_NUMBER='G21796-107',
 LOCATION='R9T6',
 ROOM='IO_SLOT',
 SEC='1',
 CDS_LIB='mstr_discrete',
 CDS_PART_NAME='RES_0402-15.0K,1%,1/16W,CHIP,GA',
 PRIM_FILE='./archive_libs/mstr_discrete/res/chips/chips.prt';

PART_NAME
 R9T8 'RES_0402-0.0,5%,1/16W,CHIP,G21A':
 ROOM='PROC_SIDEBAND';

SECTION_NUMBER 1
 '@BASEBOARD_FAB2_LIB.BASEBOARD_FAB2(SCH_1):PAGE181_I137@MSTR_DISCRETE.RES(CHIPS)':
 C_PATH='@baseboard_fab2_lib.baseboard_fab2(sch_1):page181_i137@mstr_discrete.re~
s(chips)',
 P_PATH='@baseboard_fab2_lib.baseboard_fab2(sch_1):page181_i137@mstr_discrete.re~
s(chips)',
 PATH='I137',
 DRAWING='@BASEBOARD_FAB2_LIB.BASEBOARD_FAB2(SCH_1):PAGE181',
 WATTAGE='1/16W',
 TOLERANCE='5%',
 SEC_TYPE='0402',
 MATERIAL='CHIP',
 BOM_COST='PROC',
 PHYS_PAGE='181',
 XY='(-2200,1300)',
 ROT='3',
 VER='1',
 VALUE='0.0',
 PACK_TYPE='0402',
 PART_NUMBER='G21497-005',
 LOCATION='R9T8',
 ROOM='PROC_SIDEBAND',
 SEC='1',
 CDS_LIB='mstr_discrete',
 CDS_PART_NAME='RES_0402-0.0,5%,1/16W,CHIP,G21A',
 PRIM_FILE='./archive_libs/mstr_discrete/res/chips/chips.prt';

PART_NAME
 R9T9 'RES_0402-4.75K,1%,1/16W,CHIP,GA':
 ROOM='IO_SLOT';

SECTION_NUMBER 1
 '@BASEBOARD_FAB2_LIB.BASEBOARD_FAB2(SCH_1):PAGE181_I4@MSTR_DISCRETE.RES(CHIPS)':
 C_PATH='@baseboard_fab2_lib.baseboard_fab2(sch_1):page181_i4@mstr_discrete.res(~
chips)',
 P_PATH='@baseboard_fab2_lib.baseboard_fab2(sch_1):page181_i4@mstr_discrete.res(~
chips)',
 PATH='I4',
 DRAWING='@BASEBOARD_FAB2_LIB.BASEBOARD_FAB2(SCH_1):PAGE181',
 WATTAGE='1/16W',
 TOLERANCE='1%',
 SEC_TYPE='0402',
 MATERIAL='CHIP',
 BOM_COST='IO_SLOT',
 PHYS_PAGE='181',
 XY='(-2200,1750)',
 ROT='0',
 VER='2',
 VALUE='4.75K',
 PACK_TYPE='0402',
 PART_NUMBER='G21796-072',
 LOCATION='R9T9',
 ROOM='IO_SLOT',
 SEC='1',
 CDS_LIB='mstr_discrete',
 CDS_PART_NAME='RES_0402-4.75K,1%,1/16W,CHIP,GA',
 PRIM_FILE='./archive_libs/mstr_discrete/res/chips/chips.prt';

PART_NAME
 R9U1 'RES_0402-0.0,5%,1/16W,CHIP,G21A':
 ROOM='CPU0';

SECTION_NUMBER 1
 '@BASEBOARD_FAB2_LIB.BASEBOARD_FAB2(SCH_1):PAGE224_I150@MSTR_DISCRETE.RES(CHIPS)':
 C_PATH='@baseboard_fab2_lib.baseboard_fab2(sch_1):page224_i150@mstr_discrete.re~
s(chips)',
 P_PATH='@baseboard_fab2_lib.baseboard_fab2(sch_1):page224_i150@mstr_discrete.re~
s(chips)',
 PATH='I150',
 DRAWING='@BASEBOARD_FAB2_LIB.BASEBOARD_FAB2(SCH_1):PAGE224',
 WATTAGE='1/16W',
 TOLERANCE='5%',
 SEC_TYPE='0402',
 MATERIAL='CHIP',
 BOM_COST='PROC_SIDEBAND',
 PHYS_PAGE='224',
 XY='(-700,3050)',
 ROT='0',
 VER='1',
 VALUE='0.0',
 PACK_TYPE='0402',
 PART_NUMBER='G21497-005',
 LOCATION='R9U1',
 ROOM='CPU0',
 SEC='1',
 CDS_LIB='mstr_discrete',
 CDS_PART_NAME='RES_0402-0.0,5%,1/16W,CHIP,G21A',
 PRIM_FILE='./archive_libs/mstr_discrete/res/chips/chips.prt';

PART_NAME
 R9U3 'RES_0402-100.0,1%,1/16W,CHIP,GA':
 ROOM='VDDQ_GHJ_PWR_VR';

SECTION_NUMBER 1
 '@BASEBOARD_FAB2_LIB.BASEBOARD_FAB2(SCH_1):PAGE223_I57@MSTR_DISCRETE.RES(CHIPS)':
 C_PATH='@baseboard_fab2_lib.baseboard_fab2(sch_1):page223_i57@mstr_discrete.res~
(chips)',
 P_PATH='@baseboard_fab2_lib.baseboard_fab2(sch_1):page223_i57@mstr_discrete.res~
(chips)',
 PATH='I57',
 DRAWING='@BASEBOARD_FAB2_LIB.BASEBOARD_FAB2(SCH_1):PAGE223',
 WATTAGE='1/16W',
 TOLERANCE='1%',
 SEC_TYPE='0402',
 MATERIAL='CHIP',
 PHYS_PAGE='223',
 XY='(4100,2425)',
 ROT='0',
 VER='2',
 VALUE='100.0',
 PACK_TYPE='0402',
 PART_NUMBER='G21796-017',
 LOCATION='R9U3',
 ROOM='VDDQ_GHJ_PWR_VR',
 SEC='1',
 CDS_LIB='mstr_discrete',
 CDS_PART_NAME='RES_0402-100.0,1%,1/16W,CHIP,GA',
 PRIM_FILE='./archive_libs/mstr_discrete/res/chips/chips.prt';

PART_NAME
 R9U4 'RES_0402-49.9,1%,1/16W,CHIP,G2A':
 ROOM='VDDQ_KLM_PWR_VR';

SECTION_NUMBER 1
 '@BASEBOARD_FAB2_LIB.BASEBOARD_FAB2(SCH_1):PAGE223_I70@MSTR_DISCRETE.RES(CHIPS)':
 C_PATH='@baseboard_fab2_lib.baseboard_fab2(sch_1):page223_i70@mstr_discrete.res~
(chips)',
 P_PATH='@baseboard_fab2_lib.baseboard_fab2(sch_1):page223_i70@mstr_discrete.res~
(chips)',
 PATH='I70',
 DRAWING='@BASEBOARD_FAB2_LIB.BASEBOARD_FAB2(SCH_1):PAGE223',
 WATTAGE='1/16W',
 TOLERANCE='1%',
 SEC_TYPE='0402',
 MATERIAL='CHIP',
 PHYS_PAGE='223',
 XY='(-625,3000)',
 ROT='0',
 VER='2',
 VALUE='49.9',
 PACK_TYPE='0402',
 PART_NUMBER='G21796-047',
 LOCATION='R9U4',
 ROOM='VDDQ_KLM_PWR_VR',
 SEC='1',
 CDS_LIB='mstr_discrete',
 CDS_PART_NAME='RES_0402-49.9,1%,1/16W,CHIP,G2A',
 PRIM_FILE='./archive_libs/mstr_discrete/res/chips/chips.prt';

PART_NAME
 R9U7 'RES_0402-0.0,5%,1/16W,CHIP,G21A':
 ROOM='PVCCIN_CPU0_VR';

SECTION_NUMBER 1
 '@BASEBOARD_FAB2_LIB.BASEBOARD_FAB2(SCH_1):PAGE223_I14@MSTR_DISCRETE.RES(CHIPS)':
 C_PATH='@baseboard_fab2_lib.baseboard_fab2(sch_1):page223_i14@mstr_discrete.res~
(chips)',
 P_PATH='@baseboard_fab2_lib.baseboard_fab2(sch_1):page223_i14@mstr_discrete.res~
(chips)',
 PATH='I14',
 DRAWING='@BASEBOARD_FAB2_LIB.BASEBOARD_FAB2(SCH_1):PAGE223',
 WATTAGE='1/16W',
 TOLERANCE='5%',
 SEC_TYPE='0402',
 MATERIAL='CHIP',
 PHYS_PAGE='223',
 XY='(-1500,1150)',
 ROT='0',
 VER='1',
 VALUE='0.0',
 PACK_TYPE='0402',
 PART_NUMBER='G21497-005',
 LOCATION='R9U7',
 ROOM='PVCCIN_CPU0_VR',
 SEC='1',
 CDS_LIB='mstr_discrete',
 CDS_PART_NAME='RES_0402-0.0,5%,1/16W,CHIP,G21A',
 PRIM_FILE='./archive_libs/mstr_discrete/res/chips/chips.prt';

PART_NAME
 R9U8 'RES_0402-100.0K,1%,1/16W,EMPTYA':
 ROOM='BMC';

SECTION_NUMBER 1
 '@BASEBOARD_FAB2_LIB.BASEBOARD_FAB2(SCH_1):PAGE223_I31@MSTR_DISCRETE.RES(CHIPS)':
 C_PATH='@baseboard_fab2_lib.baseboard_fab2(sch_1):page223_i31@mstr_discrete.res~
(chips)',
 P_PATH='@baseboard_fab2_lib.baseboard_fab2(sch_1):page223_i31@mstr_discrete.res~
(chips)',
 PATH='I31',
 DRAWING='@BASEBOARD_FAB2_LIB.BASEBOARD_FAB2(SCH_1):PAGE223',
 WATTAGE='1/16W',
 TOLERANCE='1%',
 SEC_TYPE='0402',
 MATERIAL='EMPTY',
 BOM_COST='SM_CONTROLLER',
 PHYS_PAGE='223',
 XY='(175,3075)',
 ROT='0',
 VER='2',
 VALUE='100.0K',
 PACK_TYPE='0402',
 PART_NUMBER='G21796-010',
 LOCATION='R9U8',
 ROOM='BMC',
 SEC='1',
 CDS_LIB='mstr_discrete',
 CDS_PART_NAME='RES_0402-100.0K,1%,1/16W,EMPTYA',
 PRIM_FILE='./archive_libs/mstr_discrete/res/chips/chips.prt';

PART_NAME
 R9U10 'RES_0402-0.0,5%,1/16W,CHIP,G21A':
 ROOM='VDDQ_GHJ_PWR_VR';

SECTION_NUMBER 1
 '@BASEBOARD_FAB2_LIB.BASEBOARD_FAB2(SCH_1):PAGE223_I32@MSTR_DISCRETE.RES(CHIPS)':
 C_PATH='@baseboard_fab2_lib.baseboard_fab2(sch_1):page223_i32@mstr_discrete.res~
(chips)',
 P_PATH='@baseboard_fab2_lib.baseboard_fab2(sch_1):page223_i32@mstr_discrete.res~
(chips)',
 PATH='I32',
 DRAWING='@BASEBOARD_FAB2_LIB.BASEBOARD_FAB2(SCH_1):PAGE223',
 WATTAGE='1/16W',
 TOLERANCE='5%',
 SEC_TYPE='0402',
 MATERIAL='CHIP',
 PHYS_PAGE='223',
 XY='(900,3100)',
 ROT='0',
 VER='2',
 VALUE='0.0',
 PACK_TYPE='0402',
 PART_NUMBER='G21497-005',
 LOCATION='R9U10',
 ROOM='VDDQ_GHJ_PWR_VR',
 SEC='1',
 CDS_LIB='mstr_discrete',
 CDS_PART_NAME='RES_0402-0.0,5%,1/16W,CHIP,G21A',
 PRIM_FILE='./archive_libs/mstr_discrete/res/chips/chips.prt';

PART_NAME
 R9U12 'RES_0402-0.0,5%,1/16W,CHIP,G21A':
 ROOM='CPU0';

SECTION_NUMBER 1
 '@BASEBOARD_FAB2_LIB.BASEBOARD_FAB2(SCH_1):PAGE224_I151@MSTR_DISCRETE.RES(CHIPS)':
 C_PATH='@baseboard_fab2_lib.baseboard_fab2(sch_1):page224_i151@mstr_discrete.re~
s(chips)',
 P_PATH='@baseboard_fab2_lib.baseboard_fab2(sch_1):page224_i151@mstr_discrete.re~
s(chips)',
 PATH='I151',
 DRAWING='@BASEBOARD_FAB2_LIB.BASEBOARD_FAB2(SCH_1):PAGE224',
 BOM_SS='NOPOP',
 WATTAGE='1/16W',
 TOLERANCE='5%',
 SEC_TYPE='0402',
 MATERIAL='CHIP',
 BOM_COST='PROC_SIDEBAND',
 PHYS_PAGE='224',
 XY='(-550,675)',
 ROT='0',
 VER='1',
 VALUE='0.0',
 PACK_TYPE='0402',
 PART_NUMBER='G21497-005',
 LOCATION='R9U12',
 ROOM='CPU0',
 SEC='1',
 CDS_LIB='mstr_discrete',
 CDS_PART_NAME='RES_0402-0.0,5%,1/16W,CHIP,G21A',
 PRIM_FILE='./archive_libs/mstr_discrete/res/chips/chips.prt';

PART_NAME
 R9W1 'RES_0402-10.0K,1%,1/16W,CHIP,GA':
 ROOM='CPU0';

SECTION_NUMBER 1
 '@BASEBOARD_FAB2_LIB.BASEBOARD_FAB2(SCH_1):PAGE186_I356@MSTR_DISCRETE.RES(CHIPS)':
 C_PATH='@baseboard_fab2_lib.baseboard_fab2(sch_1):page186_i356@mstr_discrete.re~
s(chips)',
 P_PATH='@baseboard_fab2_lib.baseboard_fab2(sch_1):page186_i356@mstr_discrete.re~
s(chips)',
 PATH='I356',
 DRAWING='@BASEBOARD_FAB2_LIB.BASEBOARD_FAB2(SCH_1):PAGE186',
 WATTAGE='1/16W',
 TOLERANCE='1%',
 SEC_TYPE='0402',
 MATERIAL='CHIP',
 BOM_COST='PROC_SIDEBAND',
 PHYS_PAGE='186',
 XY='(6300,4000)',
 ROT='0',
 VER='2',
 VALUE='10.0K',
 PACK_TYPE='0402',
 PART_NUMBER='G21796-016',
 LOCATION='R9W1',
 ROOM='CPU0',
 SEC='1',
 CDS_LIB='mstr_discrete',
 CDS_PART_NAME='RES_0402-10.0K,1%,1/16W,CHIP,GA',
 PRIM_FILE='./archive_libs/mstr_discrete/res/chips/chips.prt';

PART_NAME
 R9W12 'RES_0402-10.0K,1%,1/16W,CHIP,GA':
 ROOM='P1V538_BMC_STBY_VR';

SECTION_NUMBER 1
 '@BASEBOARD_FAB2_LIB.BASEBOARD_FAB2(SCH_1):PAGE239_I79@MSTR_DISCRETE.RES(CHIPS)':
 C_PATH='@baseboard_fab2_lib.baseboard_fab2(sch_1):page239_i79@mstr_discrete.res~
(chips)',
 P_PATH='@baseboard_fab2_lib.baseboard_fab2(sch_1):page239_i79@mstr_discrete.res~
(chips)',
 PATH='I79',
 DRAWING='@BASEBOARD_FAB2_LIB.BASEBOARD_FAB2(SCH_1):PAGE239',
 P1V5_STBY_IBMC_VR='',
 P1V5_STBY_IBMC='',
 WATTAGE='1/16W',
 TOLERANCE='1%',
 SEC_TYPE='0402',
 MATERIAL='CHIP',
 BOM_COST='P1V538_BMC_STBY_VR',
 PHYS_PAGE='239',
 XY='(9200,2450)',
 ROT='0',
 VER='2',
 VALUE='10.0K',
 PACK_TYPE='0402',
 PART_NUMBER='G21796-016',
 LOCATION='R9W12',
 ROOM='P1V538_BMC_STBY_VR',
 SEC='1',
 CDS_LIB='mstr_discrete',
 CDS_PART_NAME='RES_0402-10.0K,1%,1/16W,CHIP,GA',
 PRIM_FILE='./archive_libs/mstr_discrete/res/chips/chips.prt';

PART_NAME
 R9W13 'RES_0402-20.0,1%,1/16W,CHIP,G2A':
 ROOM='SMB_PE_HP_CPU1';

SECTION_NUMBER 1
 '@BASEBOARD_FAB2_LIB.BASEBOARD_FAB2(SCH_1):PAGE248_I38@MSTR_DISCRETE.RES(CHIPS)':
 C_PATH='@baseboard_fab2_lib.baseboard_fab2(sch_1):page248_i38@mstr_discrete.res~
(chips)',
 P_PATH='@baseboard_fab2_lib.baseboard_fab2(sch_1):page248_i38@mstr_discrete.res~
(chips)',
 PATH='I38',
 DRAWING='@BASEBOARD_FAB2_LIB.BASEBOARD_FAB2(SCH_1):PAGE248',
 WATTAGE='1/16W',
 TOLERANCE='1%',
 SEC_TYPE='0402',
 MATERIAL='CHIP',
 PHYS_PAGE='248',
 XY='(-2200,3475)',
 ROT='0',
 VER='1',
 VALUE='20.0',
 PACK_TYPE='0402',
 PART_NUMBER='G21796-173',
 LOCATION='R9W13',
 ROOM='SMB_PE_HP_CPU1',
 SEC='1',
 CDS_LIB='mstr_discrete',
 CDS_PART_NAME='RES_0402-20.0,1%,1/16W,CHIP,G2A',
 PRIM_FILE='./archive_libs/mstr_discrete/res/chips/chips.prt';

PART_NAME
 R9W14 'RES_0402-20.0,1%,1/16W,CHIP,G2A':
 ROOM='SMB_PE_HP_CPU1';

SECTION_NUMBER 1
 '@BASEBOARD_FAB2_LIB.BASEBOARD_FAB2(SCH_1):PAGE248_I37@MSTR_DISCRETE.RES(CHIPS)':
 C_PATH='@baseboard_fab2_lib.baseboard_fab2(sch_1):page248_i37@mstr_discrete.res~
(chips)',
 P_PATH='@baseboard_fab2_lib.baseboard_fab2(sch_1):page248_i37@mstr_discrete.res~
(chips)',
 PATH='I37',
 DRAWING='@BASEBOARD_FAB2_LIB.BASEBOARD_FAB2(SCH_1):PAGE248',
 WATTAGE='1/16W',
 TOLERANCE='1%',
 SEC_TYPE='0402',
 MATERIAL='CHIP',
 PHYS_PAGE='248',
 XY='(-2450,3525)',
 ROT='0',
 VER='1',
 VALUE='20.0',
 PACK_TYPE='0402',
 PART_NUMBER='G21796-173',
 LOCATION='R9W14',
 ROOM='SMB_PE_HP_CPU1',
 SEC='1',
 CDS_LIB='mstr_discrete',
 CDS_PART_NAME='RES_0402-20.0,1%,1/16W,CHIP,G2A',
 PRIM_FILE='./archive_libs/mstr_discrete/res/chips/chips.prt';

PART_NAME
 R9W16 'RES_0402-2.0K,1%,1/16W,CHIP,G2A':
 ROOM='SMB_PE_HP_CPU1';

SECTION_NUMBER 1
 '@BASEBOARD_FAB2_LIB.BASEBOARD_FAB2(SCH_1):PAGE248_I34@MSTR_DISCRETE.RES(CHIPS)':
 C_PATH='@baseboard_fab2_lib.baseboard_fab2(sch_1):page248_i34@mstr_discrete.res~
(chips)',
 P_PATH='@baseboard_fab2_lib.baseboard_fab2(sch_1):page248_i34@mstr_discrete.res~
(chips)',
 PATH='I34',
 DRAWING='@BASEBOARD_FAB2_LIB.BASEBOARD_FAB2(SCH_1):PAGE248',
 WATTAGE='1/16W',
 TOLERANCE='1%',
 SEC_TYPE='0402',
 MATERIAL='CHIP',
 PHYS_PAGE='248',
 XY='(-2850,3875)',
 ROT='0',
 VER='2',
 VALUE='2.0K',
 PACK_TYPE='0402',
 PART_NUMBER='G21796-001',
 LOCATION='R9W16',
 ROOM='SMB_PE_HP_CPU1',
 SEC='1',
 CDS_LIB='mstr_discrete',
 CDS_PART_NAME='RES_0402-2.0K,1%,1/16W,CHIP,G2A',
 PRIM_FILE='./archive_libs/mstr_discrete/res/chips/chips.prt';

PART_NAME
 R9W17 'RES_0402-2.0K,1%,1/16W,CHIP,G2A':
 ROOM='SMB_PE_HP_CPU1';

SECTION_NUMBER 1
 '@BASEBOARD_FAB2_LIB.BASEBOARD_FAB2(SCH_1):PAGE248_I35@MSTR_DISCRETE.RES(CHIPS)':
 C_PATH='@baseboard_fab2_lib.baseboard_fab2(sch_1):page248_i35@mstr_discrete.res~
(chips)',
 P_PATH='@baseboard_fab2_lib.baseboard_fab2(sch_1):page248_i35@mstr_discrete.res~
(chips)',
 PATH='I35',
 DRAWING='@BASEBOARD_FAB2_LIB.BASEBOARD_FAB2(SCH_1):PAGE248',
 WATTAGE='1/16W',
 TOLERANCE='1%',
 SEC_TYPE='0402',
 MATERIAL='CHIP',
 PHYS_PAGE='248',
 XY='(-3000,3875)',
 ROT='2',
 VER='2',
 VALUE='2.0K',
 PACK_TYPE='0402',
 PART_NUMBER='G21796-001',
 LOCATION='R9W17',
 ROOM='SMB_PE_HP_CPU1',
 SEC='1',
 CDS_LIB='mstr_discrete',
 CDS_PART_NAME='RES_0402-2.0K,1%,1/16W,CHIP,G2A',
 PRIM_FILE='./archive_libs/mstr_discrete/res/chips/chips.prt';

PART_NAME
 R9W18 'RES_0402-240,1.0%,1/16W,CHIP,GA':
 ROOM='SMB_PE_HP_CPU1';

SECTION_NUMBER 1
 '@BASEBOARD_FAB2_LIB.BASEBOARD_FAB2(SCH_1):PAGE248_I27@MSTR_DISCRETE.RES(CHIPS)':
 C_PATH='@baseboard_fab2_lib.baseboard_fab2(sch_1):page248_i27@mstr_discrete.res~
(chips)',
 P_PATH='@baseboard_fab2_lib.baseboard_fab2(sch_1):page248_i27@mstr_discrete.res~
(chips)',
 PATH='I27',
 DRAWING='@BASEBOARD_FAB2_LIB.BASEBOARD_FAB2(SCH_1):PAGE248',
 WATTAGE='1/16W',
 TOLERANCE='1.0%',
 SEC_TYPE='0402',
 MATERIAL='CHIP',
 PHYS_PAGE='248',
 XY='(-4600,3875)',
 ROT='0',
 VER='2',
 VALUE='240',
 PACK_TYPE='0402',
 PART_NUMBER='G21796-294',
 LOCATION='R9W18',
 ROOM='SMB_PE_HP_CPU1',
 SEC='1',
 CDS_LIB='mstr_discrete',
 CDS_PART_NAME='RES_0402-240,1.0%,1/16W,CHIP,GA',
 PRIM_FILE='./archive_libs/mstr_discrete/res/chips/chips.prt';

PART_NAME
 R9W19 'RES_0402-240,1.0%,1/16W,CHIP,GA':
 ROOM='SMB_PE_HP_CPU1';

SECTION_NUMBER 1
 '@BASEBOARD_FAB2_LIB.BASEBOARD_FAB2(SCH_1):PAGE248_I26@MSTR_DISCRETE.RES(CHIPS)':
 C_PATH='@baseboard_fab2_lib.baseboard_fab2(sch_1):page248_i26@mstr_discrete.res~
(chips)',
 P_PATH='@baseboard_fab2_lib.baseboard_fab2(sch_1):page248_i26@mstr_discrete.res~
(chips)',
 PATH='I26',
 DRAWING='@BASEBOARD_FAB2_LIB.BASEBOARD_FAB2(SCH_1):PAGE248',
 WATTAGE='1/16W',
 TOLERANCE='1.0%',
 SEC_TYPE='0402',
 MATERIAL='CHIP',
 PHYS_PAGE='248',
 XY='(-4750,3875)',
 ROT='2',
 VER='2',
 VALUE='240',
 PACK_TYPE='0402',
 PART_NUMBER='G21796-294',
 LOCATION='R9W19',
 ROOM='SMB_PE_HP_CPU1',
 SEC='1',
 CDS_LIB='mstr_discrete',
 CDS_PART_NAME='RES_0402-240,1.0%,1/16W,CHIP,GA',
 PRIM_FILE='./archive_libs/mstr_discrete/res/chips/chips.prt';

PART_NAME
 R9W31 '21K5R2F-GP_RCL_GP-21K5R2F-GP,6A':;

SECTION_NUMBER 1
 '@BASEBOARD_FAB2_LIB.BASEBOARD_FAB2(SCH_1):PAGE239_I102@W_HDL.21K5R2F-GP(CHIPS)':
 C_PATH='@baseboard_fab2_lib.baseboard_fab2(sch_1):page239_i102@w_hdl.\21k5r2f-g~
p\(chips)',
 P_PATH='@baseboard_fab2_lib.baseboard_fab2(sch_1):page239_i102@w_hdl.\21k5r2f-g~
p\(chips)',
 PATH='I102',
 DRAWING='@BASEBOARD_FAB2_LIB.BASEBOARD_FAB2(SCH_1):PAGE239',
 PACK_SIZE='0402',
 RATED='1/16W',
 ATTRIBUTE='21.5KOHM',
 TOLERANCE='1%',
 SEC_TYPE='RCL_GP',
 PHYS_PAGE='239',
 XY='(9925,1325)',
 ROT='0',
 VER='1',
 VALUE='21K5R2F-GP',
 PACK_TYPE='RCL_GP',
 PART_NUMBER='64.21525.6DL',
 LOCATION='R9W31',
 SEC='1',
 CDS_LIB='w_hdl',
 CDS_PART_NAME='21K5R2F-GP_RCL_GP-21K5R2F-GP,6A',
 PRIM_FILE='C:/<user>/w_hdl/21k5r2f#2dgp/chips/chips.prt';

PART_NAME
 R9W32 'RES_0402-10.0K,1%,1/16W,CHIP,GA':
 ROOM='CPU0';

SECTION_NUMBER 1
 '@BASEBOARD_FAB2_LIB.BASEBOARD_FAB2(SCH_1):PAGE239_I101@MSTR_DISCRETE.RES(CHIPS)':
 C_PATH='@baseboard_fab2_lib.baseboard_fab2(sch_1):page239_i101@mstr_discrete.re~
s(chips)',
 P_PATH='@baseboard_fab2_lib.baseboard_fab2(sch_1):page239_i101@mstr_discrete.re~
s(chips)',
 PATH='I101',
 DRAWING='@BASEBOARD_FAB2_LIB.BASEBOARD_FAB2(SCH_1):PAGE239',
 WATTAGE='1/16W',
 TOLERANCE='1%',
 SEC_TYPE='0402',
 MATERIAL='CHIP',
 BOM_COST='PROC_SIDEBAND',
 PHYS_PAGE='239',
 XY='(9925,800)',
 ROT='0',
 VER='2',
 VALUE='10.0K',
 PACK_TYPE='0402',
 PART_NUMBER='G21796-016',
 LOCATION='R9W32',
 ROOM='CPU0',
 SEC='1',
 CDS_LIB='mstr_discrete',
 CDS_PART_NAME='RES_0402-10.0K,1%,1/16W,CHIP,GA',
 PRIM_FILE='./archive_libs/mstr_discrete/res/chips/chips.prt';

PART_NAME
 R9W33 'RES_0402-4.75K,1%,1/16W,CHIP,GA':
 ROOM='BMC_MISC';

SECTION_NUMBER 1
 '@BASEBOARD_FAB2_LIB.BASEBOARD_FAB2(SCH_1):PAGE158_I153@MSTR_DISCRETE.RES(CHIPS)':
 C_PATH='@baseboard_fab2_lib.baseboard_fab2(sch_1):page158_i153@mstr_discrete.re~
s(chips)',
 P_PATH='@baseboard_fab2_lib.baseboard_fab2(sch_1):page158_i153@mstr_discrete.re~
s(chips)',
 PATH='I153',
 DRAWING='@BASEBOARD_FAB2_LIB.BASEBOARD_FAB2(SCH_1):PAGE158',
 POP='NOPOP',
 WATTAGE='1/16W',
 TOLERANCE='1%',
 SEC_TYPE='0402',
 MATERIAL='CHIP',
 BOM_COST='SM_CONTROLLER',
 PHYS_PAGE='158',
 XY='(-2300,1200)',
 ROT='0',
 VER='2',
 VALUE='4.75K',
 PACK_TYPE='0402',
 PART_NUMBER='G21796-072',
 LOCATION='R9W33',
 ROOM='BMC_MISC',
 SEC='1',
 CDS_LIB='mstr_discrete',
 CDS_PART_NAME='RES_0402-4.75K,1%,1/16W,CHIP,GA',
 PRIM_FILE='./archive_libs/mstr_discrete/res/chips/chips.prt';

PART_NAME
 R9W34 'RES_0402-4.75K,1%,1/16W,CHIP,GA':
 ROOM='BMC_MISC';

SECTION_NUMBER 1
 '@BASEBOARD_FAB2_LIB.BASEBOARD_FAB2(SCH_1):PAGE158_I154@MSTR_DISCRETE.RES(CHIPS)':
 C_PATH='@baseboard_fab2_lib.baseboard_fab2(sch_1):page158_i154@mstr_discrete.re~
s(chips)',
 P_PATH='@baseboard_fab2_lib.baseboard_fab2(sch_1):page158_i154@mstr_discrete.re~
s(chips)',
 PATH='I154',
 DRAWING='@BASEBOARD_FAB2_LIB.BASEBOARD_FAB2(SCH_1):PAGE158',
 POP='NOPOP',
 WATTAGE='1/16W',
 TOLERANCE='1%',
 SEC_TYPE='0402',
 MATERIAL='CHIP',
 BOM_COST='SM_CONTROLLER',
 PHYS_PAGE='158',
 XY='(-2025,1200)',
 ROT='0',
 VER='2',
 VALUE='4.75K',
 PACK_TYPE='0402',
 PART_NUMBER='G21796-072',
 LOCATION='R9W34',
 ROOM='BMC_MISC',
 SEC='1',
 CDS_LIB='mstr_discrete',
 CDS_PART_NAME='RES_0402-4.75K,1%,1/16W,CHIP,GA',
 PRIM_FILE='./archive_libs/mstr_discrete/res/chips/chips.prt';

PART_NAME
 R9W35 'RES_0402-4.75K,1%,1/16W,CHIP,GA':
 ROOM='BMC_MISC';

SECTION_NUMBER 1
 '@BASEBOARD_FAB2_LIB.BASEBOARD_FAB2(SCH_1):PAGE158_I155@MSTR_DISCRETE.RES(CHIPS)':
 C_PATH='@baseboard_fab2_lib.baseboard_fab2(sch_1):page158_i155@mstr_discrete.re~
s(chips)',
 P_PATH='@baseboard_fab2_lib.baseboard_fab2(sch_1):page158_i155@mstr_discrete.re~
s(chips)',
 PATH='I155',
 DRAWING='@BASEBOARD_FAB2_LIB.BASEBOARD_FAB2(SCH_1):PAGE158',
 POP='NOPOP',
 WATTAGE='1/16W',
 TOLERANCE='1%',
 SEC_TYPE='0402',
 MATERIAL='CHIP',
 BOM_COST='SM_CONTROLLER',
 PHYS_PAGE='158',
 XY='(-1750,1200)',
 ROT='0',
 VER='2',
 VALUE='4.75K',
 PACK_TYPE='0402',
 PART_NUMBER='G21796-072',
 LOCATION='R9W35',
 ROOM='BMC_MISC',
 SEC='1',
 CDS_LIB='mstr_discrete',
 CDS_PART_NAME='RES_0402-4.75K,1%,1/16W,CHIP,GA',
 PRIM_FILE='./archive_libs/mstr_discrete/res/chips/chips.prt';

PART_NAME
 R9W36 'RES_0402-10.0K,1%,1/16W,CHIP,GA':
 GROUP='NI_I210&RJ45',
 ROOM='NIC_SPRV';

SECTION_NUMBER 1
 '@BASEBOARD_FAB2_LIB.BASEBOARD_FAB2(SCH_1):PAGE139_I252@MSTR_DISCRETE.RES(CHIPS)':
 C_PATH='@baseboard_fab2_lib.baseboard_fab2(sch_1):page139_i252@mstr_discrete.re~
s(chips)',
 P_PATH='@baseboard_fab2_lib.baseboard_fab2(sch_1):page139_i252@mstr_discrete.re~
s(chips)',
 PATH='I252',
 DRAWING='@BASEBOARD_FAB2_LIB.BASEBOARD_FAB2(SCH_1):PAGE139',
 WATTAGE='1/16W',
 TOLERANCE='1%',
 SEC_TYPE='0402',
 MATERIAL='CHIP',
 BOM_COST='NT_GBE_BASE',
 PHYS_PAGE='139',
 XY='(-6950,3275)',
 ROT='0',
 VER='2',
 VALUE='10.0K',
 PACK_TYPE='0402',
 PART_NUMBER='G21796-016',
 LOCATION='R9W36',
 ROOM='NIC_SPRV',
 GROUP='NI_I210&RJ45',
 SEC='1',
 CDS_LIB='mstr_discrete',
 CDS_PART_NAME='RES_0402-10.0K,1%,1/16W,CHIP,GA',
 PRIM_FILE='./archive_libs/mstr_discrete/res/chips/chips.prt';

PART_NAME
 R10W1 'RES_0402-100.0,1%,1/16W,CHIP,GA':
 ROOM='CPU_FANS',
 NO_XNET_CONNECTION='1';

SECTION_NUMBER 1
 '@BASEBOARD_FAB2_LIB.BASEBOARD_FAB2(SCH_1):PAGE251_I13@MSTR_DISCRETE.RES(CHIPS)':
 C_PATH='@baseboard_fab2_lib.baseboard_fab2(sch_1):page251_i13@mstr_discrete.res~
(chips)',
 P_PATH='@baseboard_fab2_lib.baseboard_fab2(sch_1):page251_i13@mstr_discrete.res~
(chips)',
 PATH='I13',
 DRAWING='@BASEBOARD_FAB2_LIB.BASEBOARD_FAB2(SCH_1):PAGE251',
 WATTAGE='1/16W',
 TOLERANCE='1%',
 SEC_TYPE='0402',
 MATERIAL='CHIP',
 BOM_COST='SM_THERM',
 NO_XNET_CONNECTION='1',
 PHYS_PAGE='251',
 XY='(-4650,5250)',
 ROT='0',
 VER='1',
 VALUE='100.0',
 PACK_TYPE='0402',
 PART_NUMBER='G21796-017',
 LOCATION='R10W1',
 ROOM='CPU_FANS',
 SEC='1',
 CDS_LIB='mstr_discrete',
 CDS_PART_NAME='RES_0402-100.0,1%,1/16W,CHIP,GA',
 PRIM_FILE='./archive_libs/mstr_discrete/res/chips/chips.prt';

PART_NAME
 R10W2 'RES_0402-4.75K,1%,1/16W,CHIP,GA':
 ROOM='CPU_FANS';

SECTION_NUMBER 1
 '@BASEBOARD_FAB2_LIB.BASEBOARD_FAB2(SCH_1):PAGE251_I15@MSTR_DISCRETE.RES(CHIPS)':
 C_PATH='@baseboard_fab2_lib.baseboard_fab2(sch_1):page251_i15@mstr_discrete.res~
(chips)',
 P_PATH='@baseboard_fab2_lib.baseboard_fab2(sch_1):page251_i15@mstr_discrete.res~
(chips)',
 PATH='I15',
 DRAWING='@BASEBOARD_FAB2_LIB.BASEBOARD_FAB2(SCH_1):PAGE251',
 WATTAGE='1/16W',
 TOLERANCE='1%',
 SEC_TYPE='0402',
 MATERIAL='CHIP',
 BOM_COST='SM_THERM',
 PHYS_PAGE='251',
 XY='(-5300,5450)',
 ROT='0',
 VER='2',
 VALUE='4.75K',
 PACK_TYPE='0402',
 PART_NUMBER='G21796-072',
 LOCATION='R10W2',
 ROOM='CPU_FANS',
 SEC='1',
 CDS_LIB='mstr_discrete',
 CDS_PART_NAME='RES_0402-4.75K,1%,1/16W,CHIP,GA',
 PRIM_FILE='./archive_libs/mstr_discrete/res/chips/chips.prt';

PART_NAME
 R10W3 'RES_0402-4.75K,1%,1/16W,CHIP,GA':
 ROOM='CPU_FANS';

SECTION_NUMBER 1
 '@BASEBOARD_FAB2_LIB.BASEBOARD_FAB2(SCH_1):PAGE251_I11@MSTR_DISCRETE.RES(CHIPS)':
 C_PATH='@baseboard_fab2_lib.baseboard_fab2(sch_1):page251_i11@mstr_discrete.res~
(chips)',
 P_PATH='@baseboard_fab2_lib.baseboard_fab2(sch_1):page251_i11@mstr_discrete.res~
(chips)',
 PATH='I11',
 DRAWING='@BASEBOARD_FAB2_LIB.BASEBOARD_FAB2(SCH_1):PAGE251',
 WATTAGE='1/16W',
 TOLERANCE='1%',
 SEC_TYPE='0402',
 MATERIAL='CHIP',
 BOM_COST='SM_THERM',
 PHYS_PAGE='251',
 XY='(-3250,4650)',
 ROT='2',
 VER='2',
 VALUE='4.75K',
 PACK_TYPE='0402',
 PART_NUMBER='G21796-072',
 LOCATION='R10W3',
 ROOM='CPU_FANS',
 SEC='1',
 CDS_LIB='mstr_discrete',
 CDS_PART_NAME='RES_0402-4.75K,1%,1/16W,CHIP,GA',
 PRIM_FILE='./archive_libs/mstr_discrete/res/chips/chips.prt';

PART_NAME
 R10W4 'RES_0402-221,1.0%,1/16W,CHIP,GA':
 ROOM='CPU_FANS';

SECTION_NUMBER 1
 '@BASEBOARD_FAB2_LIB.BASEBOARD_FAB2(SCH_1):PAGE251_I14@MSTR_DISCRETE.RES(CHIPS)':
 C_PATH='@baseboard_fab2_lib.baseboard_fab2(sch_1):page251_i14@mstr_discrete.res~
(chips)',
 P_PATH='@baseboard_fab2_lib.baseboard_fab2(sch_1):page251_i14@mstr_discrete.res~
(chips)',
 PATH='I14',
 DRAWING='@BASEBOARD_FAB2_LIB.BASEBOARD_FAB2(SCH_1):PAGE251',
 WATTAGE='1/16W',
 TOLERANCE='1.0%',
 SEC_TYPE='0402',
 MATERIAL='CHIP',
 BOM_COST='SM_THERM',
 PHYS_PAGE='251',
 XY='(-4650,4450)',
 ROT='0',
 VER='1',
 VALUE='221',
 PACK_TYPE='0402',
 PART_NUMBER='G21796-271',
 LOCATION='R10W4',
 ROOM='CPU_FANS',
 SEC='1',
 CDS_LIB='mstr_discrete',
 CDS_PART_NAME='RES_0402-221,1.0%,1/16W,CHIP,GA',
 PRIM_FILE='./archive_libs/mstr_discrete/res/chips/chips.prt';

PART_NAME
 R10W5 'RES_0805-0.0,5%,1/8W,CHIP,G221A':
 ROOM='HOT_SWAP';

SECTION_NUMBER 1
 '@BASEBOARD_FAB2_LIB.BASEBOARD_FAB2(SCH_1):PAGE251_I5@MSTR_DISCRETE.RES(CHIPS)':
 C_PATH='@baseboard_fab2_lib.baseboard_fab2(sch_1):page251_i5@mstr_discrete.res(~
chips)',
 P_PATH='@baseboard_fab2_lib.baseboard_fab2(sch_1):page251_i5@mstr_discrete.res(~
chips)',
 PATH='I5',
 DRAWING='@BASEBOARD_FAB2_LIB.BASEBOARD_FAB2(SCH_1):PAGE251',
 WATTAGE='1/8W',
 TOLERANCE='5%',
 SEC_TYPE='0805',
 MATERIAL='CHIP',
 PHYS_PAGE='251',
 XY='(-3025,6025)',
 ROT='0',
 VER='1',
 VALUE='0.0',
 PACK_TYPE='0805',
 PART_NUMBER='G22179-004',
 LOCATION='R10W5',
 ROOM='HOT_SWAP',
 SEC='1',
 CDS_LIB='mstr_discrete',
 CDS_PART_NAME='RES_0805-0.0,5%,1/8W,CHIP,G221A',
 PRIM_FILE='./archive_libs/mstr_discrete/res/chips/chips.prt';

PART_NAME
 R10W6 'RES_0402-100.0,1%,1/16W,CHIP,GA':
 ROOM='CPU_FANS',
 NO_XNET_CONNECTION='1';

SECTION_NUMBER 1
 '@BASEBOARD_FAB2_LIB.BASEBOARD_FAB2(SCH_1):PAGE251_I27@MSTR_DISCRETE.RES(CHIPS)':
 C_PATH='@baseboard_fab2_lib.baseboard_fab2(sch_1):page251_i27@mstr_discrete.res~
(chips)',
 P_PATH='@baseboard_fab2_lib.baseboard_fab2(sch_1):page251_i27@mstr_discrete.res~
(chips)',
 PATH='I27',
 DRAWING='@BASEBOARD_FAB2_LIB.BASEBOARD_FAB2(SCH_1):PAGE251',
 WATTAGE='1/16W',
 TOLERANCE='1%',
 SEC_TYPE='0402',
 MATERIAL='CHIP',
 BOM_COST='SM_THERM',
 NO_XNET_CONNECTION='1',
 PHYS_PAGE='251',
 XY='(-4650,3700)',
 ROT='0',
 VER='1',
 VALUE='100.0',
 PACK_TYPE='0402',
 PART_NUMBER='G21796-017',
 LOCATION='R10W6',
 ROOM='CPU_FANS',
 SEC='1',
 CDS_LIB='mstr_discrete',
 CDS_PART_NAME='RES_0402-100.0,1%,1/16W,CHIP,GA',
 PRIM_FILE='./archive_libs/mstr_discrete/res/chips/chips.prt';

PART_NAME
 R10W7 'RES_0402-4.75K,1%,1/16W,CHIP,GA':
 ROOM='CPU_FANS';

SECTION_NUMBER 1
 '@BASEBOARD_FAB2_LIB.BASEBOARD_FAB2(SCH_1):PAGE251_I31@MSTR_DISCRETE.RES(CHIPS)':
 C_PATH='@baseboard_fab2_lib.baseboard_fab2(sch_1):page251_i31@mstr_discrete.res~
(chips)',
 P_PATH='@baseboard_fab2_lib.baseboard_fab2(sch_1):page251_i31@mstr_discrete.res~
(chips)',
 PATH='I31',
 DRAWING='@BASEBOARD_FAB2_LIB.BASEBOARD_FAB2(SCH_1):PAGE251',
 WATTAGE='1/16W',
 TOLERANCE='1%',
 SEC_TYPE='0402',
 MATERIAL='CHIP',
 BOM_COST='SM_THERM',
 PHYS_PAGE='251',
 XY='(-5300,3900)',
 ROT='0',
 VER='2',
 VALUE='4.75K',
 PACK_TYPE='0402',
 PART_NUMBER='G21796-072',
 LOCATION='R10W7',
 ROOM='CPU_FANS',
 SEC='1',
 CDS_LIB='mstr_discrete',
 CDS_PART_NAME='RES_0402-4.75K,1%,1/16W,CHIP,GA',
 PRIM_FILE='./archive_libs/mstr_discrete/res/chips/chips.prt';

PART_NAME
 R12W1 '665KR5B-1-GP_SMD-RG3-665KR5B-1A':;

SECTION_NUMBER 1
 '@BASEBOARD_FAB2_LIB.BASEBOARD_FAB2(SCH_1):PAGE197_I101@W_HDL.665KR5B-1-GP(CHIPS)':
 C_PATH='@baseboard_fab2_lib.baseboard_fab2(sch_1):page197_i101@w_hdl.\665kr5b-1~
-gp\(chips)',
 P_PATH='@baseboard_fab2_lib.baseboard_fab2(sch_1):page197_i101@w_hdl.\665kr5b-1~
-gp\(chips)',
 PATH='I101',
 DRAWING='@BASEBOARD_FAB2_LIB.BASEBOARD_FAB2(SCH_1):PAGE197',
 NEW_VALUE='100K OHM',
 PACK_SIZE='AT0805',
 RATED='1/8W',
 ATTRIBUTE='665K OHM',
 CONFIG='064.1003F.M001',
 TOLERANCE='0.1%',
 PHYS_PAGE='197',
 XY='(-4475,4125)',
 ROT='0',
 VER='1',
 VALUE='665KR5B-1-GP',
 PACK_TYPE='SMD-RG3',
 PART_NUMBER='064.6653F.M001',
 LOCATION='R12W1',
 CDS_LIB='w_hdl',
 CDS_PART_NAME='665KR5B-1-GP_SMD-RG3-665KR5B-1A',
 PRIM_FILE='C:/<user>/w_hdl/665kr5b#2d1#2dgp/chips/chips.prt';

PART_NAME
 R12W2 '665KR5B-1-GP_SMD-RG3-665KR5B-1A':;

SECTION_NUMBER 1
 '@BASEBOARD_FAB2_LIB.BASEBOARD_FAB2(SCH_1):PAGE197_I117@W_HDL.665KR5B-1-GP(CHIPS)':
 C_PATH='@baseboard_fab2_lib.baseboard_fab2(sch_1):page197_i117@w_hdl.\665kr5b-1~
-gp\(chips)',
 P_PATH='@baseboard_fab2_lib.baseboard_fab2(sch_1):page197_i117@w_hdl.\665kr5b-1~
-gp\(chips)',
 PATH='I117',
 DRAWING='@BASEBOARD_FAB2_LIB.BASEBOARD_FAB2(SCH_1):PAGE197',
 NEW_VALUE='100K OHM',
 PACK_SIZE='AT0805',
 RATED='1/8W',
 ATTRIBUTE='665K OHM',
 CONFIG='064.1003F.M001',
 TOLERANCE='0.1%',
 PHYS_PAGE='197',
 XY='(-4025,4125)',
 ROT='0',
 VER='1',
 VALUE='665KR5B-1-GP',
 PACK_TYPE='SMD-RG3',
 PART_NUMBER='064.6653F.M001',
 LOCATION='R12W2',
 CDS_LIB='w_hdl',
 CDS_PART_NAME='665KR5B-1-GP_SMD-RG3-665KR5B-1A',
 PRIM_FILE='C:/<user>/w_hdl/665kr5b#2d1#2dgp/chips/chips.prt';

PART_NAME
 R12W3 '4D02R2F-GP_SMD-RG2-4D02R2F-GP,A':;

SECTION_NUMBER 1
 '@BASEBOARD_FAB2_LIB.BASEBOARD_FAB2(SCH_1):PAGE197_I115@W_HDL.4D02R2F-GP(CHIPS)':
 C_PATH='@baseboard_fab2_lib.baseboard_fab2(sch_1):page197_i115@w_hdl.\4d02r2f-g~
p\(chips)',
 P_PATH='@baseboard_fab2_lib.baseboard_fab2(sch_1):page197_i115@w_hdl.\4d02r2f-g~
p\(chips)',
 PATH='I115',
 DRAWING='@BASEBOARD_FAB2_LIB.BASEBOARD_FAB2(SCH_1):PAGE197',
 PACK_SIZE='0402',
 RATED='1/16W',
 ATTRIBUTE='4.02OHM',
 TOLERANCE='1%',
 SEC_TYPE='SMD-RG2',
 PHYS_PAGE='197',
 XY='(-4250,4550)',
 ROT='1',
 VER='1',
 VALUE='4D02R2F-GP',
 PACK_TYPE='SMD-RG2',
 PART_NUMBER='64.4R025.6DL',
 LOCATION='R12W3',
 SEC='1',
 CDS_LIB='w_hdl',
 CDS_PART_NAME='4D02R2F-GP_SMD-RG2-4D02R2F-GP,A',
 PRIM_FILE='C:/<user>/w_hdl/4d02r2f#2dgp/chips/chips.prt';

PART_NAME
 R12W4 'RES_0603-100.0K,1%,1/10W,CHIP,A':
 ROOM='CPU0';

SECTION_NUMBER 1
 '@BASEBOARD_FAB2_LIB.BASEBOARD_FAB2(SCH_1):PAGE197_I45@MSTR_DISCRETE.RES(CHIPS)':
 C_PATH='@baseboard_fab2_lib.baseboard_fab2(sch_1):page197_i45@mstr_discrete.res~
(chips)',
 P_PATH='@baseboard_fab2_lib.baseboard_fab2(sch_1):page197_i45@mstr_discrete.res~
(chips)',
 PATH='I45',
 DRAWING='@BASEBOARD_FAB2_LIB.BASEBOARD_FAB2(SCH_1):PAGE197',
 WATTAGE='1/10W',
 TOLERANCE='1%',
 SEC_TYPE='0603',
 MATERIAL='CHIP',
 BOM_COST='PROC_SOCKET',
 PHYS_PAGE='197',
 XY='(-2725,4500)',
 ROT='0',
 VER='2',
 VALUE='100.0K',
 PACK_TYPE='0603',
 PART_NUMBER='G22026-050',
 LOCATION='R12W4',
 ROOM='CPU0',
 SEC='1',
 CDS_LIB='mstr_discrete',
 CDS_PART_NAME='RES_0603-100.0K,1%,1/10W,CHIP,A',
 PRIM_FILE='./archive_libs/mstr_discrete/res/chips/chips.prt';

PART_NAME
 R12W5 '665KR2B-GP_SMD-RG2-665KR2B-GP,A':;

SECTION_NUMBER 1
 '@BASEBOARD_FAB2_LIB.BASEBOARD_FAB2(SCH_1):PAGE197_I111@W_HDL.665KR2B-GP(CHIPS)':
 C_PATH='@baseboard_fab2_lib.baseboard_fab2(sch_1):page197_i111@w_hdl.\665kr2b-g~
p\(chips)',
 P_PATH='@baseboard_fab2_lib.baseboard_fab2(sch_1):page197_i111@w_hdl.\665kr2b-g~
p\(chips)',
 PATH='I111',
 DRAWING='@BASEBOARD_FAB2_LIB.BASEBOARD_FAB2(SCH_1):PAGE197',
 PACK_SIZE='0402',
 RATED='1/16W',
 ATTRIBUTE='665KOHM',
 POP='NOPOP',
 TOLERANCE='0.1%',
 SEC_TYPE='SMD-RG2',
 PHYS_PAGE='197',
 XY='(-4250,3800)',
 ROT='1',
 VER='1',
 VALUE='665KR2B-GP',
 PACK_TYPE='SMD-RG2',
 PART_NUMBER='064.6653D.06DD',
 LOCATION='R12W5',
 SEC='1',
 CDS_LIB='w_hdl',
 CDS_PART_NAME='665KR2B-GP_SMD-RG2-665KR2B-GP,A',
 PRIM_FILE='C:/<user>/w_hdl/665kr2b#2dgp/chips/chips.prt';

PART_NAME
 R12W6 '665KR5B-1-GP_SMD-RG3-665KR5B-1A':;

SECTION_NUMBER 1
 '@BASEBOARD_FAB2_LIB.BASEBOARD_FAB2(SCH_1):PAGE197_I120@W_HDL.665KR5B-1-GP(CHIPS)':
 C_PATH='@baseboard_fab2_lib.baseboard_fab2(sch_1):page197_i120@w_hdl.\665kr5b-1~
-gp\(chips)',
 P_PATH='@baseboard_fab2_lib.baseboard_fab2(sch_1):page197_i120@w_hdl.\665kr5b-1~
-gp\(chips)',
 PATH='I120',
 DRAWING='@BASEBOARD_FAB2_LIB.BASEBOARD_FAB2(SCH_1):PAGE197',
 NEW_VALUE='100K OHM',
 PACK_SIZE='AT0805',
 RATED='1/8W',
 ATTRIBUTE='665K OHM',
 CONFIG='064.1003F.M001',
 TOLERANCE='0.1%',
 PHYS_PAGE='197',
 XY='(-4475,2025)',
 ROT='0',
 VER='1',
 VALUE='665KR5B-1-GP',
 PACK_TYPE='SMD-RG3',
 PART_NUMBER='064.6653F.M001',
 LOCATION='R12W6',
 CDS_LIB='w_hdl',
 CDS_PART_NAME='665KR5B-1-GP_SMD-RG3-665KR5B-1A',
 PRIM_FILE='C:/<user>/w_hdl/665kr5b#2d1#2dgp/chips/chips.prt';

PART_NAME
 R12W7 '665KR5B-1-GP_SMD-RG3-665KR5B-1A':;

SECTION_NUMBER 1
 '@BASEBOARD_FAB2_LIB.BASEBOARD_FAB2(SCH_1):PAGE197_I121@W_HDL.665KR5B-1-GP(CHIPS)':
 C_PATH='@baseboard_fab2_lib.baseboard_fab2(sch_1):page197_i121@w_hdl.\665kr5b-1~
-gp\(chips)',
 P_PATH='@baseboard_fab2_lib.baseboard_fab2(sch_1):page197_i121@w_hdl.\665kr5b-1~
-gp\(chips)',
 PATH='I121',
 DRAWING='@BASEBOARD_FAB2_LIB.BASEBOARD_FAB2(SCH_1):PAGE197',
 NEW_VALUE='100K OHM',
 PACK_SIZE='AT0805',
 RATED='1/8W',
 ATTRIBUTE='665K OHM',
 CONFIG='064.1003F.M001',
 TOLERANCE='0.1%',
 PHYS_PAGE='197',
 XY='(-4025,2025)',
 ROT='0',
 VER='1',
 VALUE='665KR5B-1-GP',
 PACK_TYPE='SMD-RG3',
 PART_NUMBER='064.6653F.M001',
 LOCATION='R12W7',
 CDS_LIB='w_hdl',
 CDS_PART_NAME='665KR5B-1-GP_SMD-RG3-665KR5B-1A',
 PRIM_FILE='C:/<user>/w_hdl/665kr5b#2d1#2dgp/chips/chips.prt';

PART_NAME
 R12W8 '4D02R2F-GP_SMD-RG2-4D02R2F-GP,A':;

SECTION_NUMBER 1
 '@BASEBOARD_FAB2_LIB.BASEBOARD_FAB2(SCH_1):PAGE197_I113@W_HDL.4D02R2F-GP(CHIPS)':
 C_PATH='@baseboard_fab2_lib.baseboard_fab2(sch_1):page197_i113@w_hdl.\4d02r2f-g~
p\(chips)',
 P_PATH='@baseboard_fab2_lib.baseboard_fab2(sch_1):page197_i113@w_hdl.\4d02r2f-g~
p\(chips)',
 PATH='I113',
 DRAWING='@BASEBOARD_FAB2_LIB.BASEBOARD_FAB2(SCH_1):PAGE197',
 PACK_SIZE='0402',
 RATED='1/16W',
 ATTRIBUTE='4.02OHM',
 TOLERANCE='1%',
 SEC_TYPE='SMD-RG2',
 PHYS_PAGE='197',
 XY='(-4250,2450)',
 ROT='1',
 VER='1',
 VALUE='4D02R2F-GP',
 PACK_TYPE='SMD-RG2',
 PART_NUMBER='64.4R025.6DL',
 LOCATION='R12W8',
 SEC='1',
 CDS_LIB='w_hdl',
 CDS_PART_NAME='4D02R2F-GP_SMD-RG2-4D02R2F-GP,A',
 PRIM_FILE='C:/<user>/w_hdl/4d02r2f#2dgp/chips/chips.prt';

PART_NAME
 R12W9 'RES_0603-100.0K,1%,1/10W,CHIP,A':
 ROOM='CPU0';

SECTION_NUMBER 1
 '@BASEBOARD_FAB2_LIB.BASEBOARD_FAB2(SCH_1):PAGE197_I21@MSTR_DISCRETE.RES(CHIPS)':
 C_PATH='@baseboard_fab2_lib.baseboard_fab2(sch_1):page197_i21@mstr_discrete.res~
(chips)',
 P_PATH='@baseboard_fab2_lib.baseboard_fab2(sch_1):page197_i21@mstr_discrete.res~
(chips)',
 PATH='I21',
 DRAWING='@BASEBOARD_FAB2_LIB.BASEBOARD_FAB2(SCH_1):PAGE197',
 WATTAGE='1/10W',
 TOLERANCE='1%',
 SEC_TYPE='0603',
 MATERIAL='CHIP',
 BOM_COST='PROC_SOCKET',
 PHYS_PAGE='197',
 XY='(-2725,2400)',
 ROT='0',
 VER='2',
 VALUE='100.0K',
 PACK_TYPE='0603',
 PART_NUMBER='G22026-050',
 LOCATION='R12W9',
 ROOM='CPU0',
 SEC='1',
 CDS_LIB='mstr_discrete',
 CDS_PART_NAME='RES_0603-100.0K,1%,1/10W,CHIP,A',
 PRIM_FILE='./archive_libs/mstr_discrete/res/chips/chips.prt';

PART_NAME
 R12W10 '665KR2B-GP_SMD-RG2-665KR2B-GP,A':;

SECTION_NUMBER 1
 '@BASEBOARD_FAB2_LIB.BASEBOARD_FAB2(SCH_1):PAGE197_I109@W_HDL.665KR2B-GP(CHIPS)':
 C_PATH='@baseboard_fab2_lib.baseboard_fab2(sch_1):page197_i109@w_hdl.\665kr2b-g~
p\(chips)',
 P_PATH='@baseboard_fab2_lib.baseboard_fab2(sch_1):page197_i109@w_hdl.\665kr2b-g~
p\(chips)',
 PATH='I109',
 DRAWING='@BASEBOARD_FAB2_LIB.BASEBOARD_FAB2(SCH_1):PAGE197',
 PACK_SIZE='0402',
 RATED='1/16W',
 ATTRIBUTE='665KOHM',
 POP='NOPOP',
 TOLERANCE='0.1%',
 SEC_TYPE='SMD-RG2',
 PHYS_PAGE='197',
 XY='(-4250,1700)',
 ROT='1',
 VER='1',
 VALUE='665KR2B-GP',
 PACK_TYPE='SMD-RG2',
 PART_NUMBER='064.6653D.06DD',
 LOCATION='R12W10',
 SEC='1',
 CDS_LIB='w_hdl',
 CDS_PART_NAME='665KR2B-GP_SMD-RG2-665KR2B-GP,A',
 PRIM_FILE='C:/<user>/w_hdl/665kr2b#2dgp/chips/chips.prt';

PART_NAME
 R12W11 '665KR5B-1-GP_SMD-RG3-665KR5B-1A':;

SECTION_NUMBER 1
 '@BASEBOARD_FAB2_LIB.BASEBOARD_FAB2(SCH_1):PAGE197_I118@W_HDL.665KR5B-1-GP(CHIPS)':
 C_PATH='@baseboard_fab2_lib.baseboard_fab2(sch_1):page197_i118@w_hdl.\665kr5b-1~
-gp\(chips)',
 P_PATH='@baseboard_fab2_lib.baseboard_fab2(sch_1):page197_i118@w_hdl.\665kr5b-1~
-gp\(chips)',
 PATH='I118',
 DRAWING='@BASEBOARD_FAB2_LIB.BASEBOARD_FAB2(SCH_1):PAGE197',
 NEW_VALUE='100K OHM',
 PACK_SIZE='AT0805',
 RATED='1/8W',
 ATTRIBUTE='665K OHM',
 CONFIG='064.1003F.M001',
 TOLERANCE='0.1%',
 PHYS_PAGE='197',
 XY='(-1925,4125)',
 ROT='0',
 VER='1',
 VALUE='665KR5B-1-GP',
 PACK_TYPE='SMD-RG3',
 PART_NUMBER='064.6653F.M001',
 LOCATION='R12W11',
 CDS_LIB='w_hdl',
 CDS_PART_NAME='665KR5B-1-GP_SMD-RG3-665KR5B-1A',
 PRIM_FILE='C:/<user>/w_hdl/665kr5b#2d1#2dgp/chips/chips.prt';

PART_NAME
 R12W12 '665KR5B-1-GP_SMD-RG3-665KR5B-1A':;

SECTION_NUMBER 1
 '@BASEBOARD_FAB2_LIB.BASEBOARD_FAB2(SCH_1):PAGE197_I119@W_HDL.665KR5B-1-GP(CHIPS)':
 C_PATH='@baseboard_fab2_lib.baseboard_fab2(sch_1):page197_i119@w_hdl.\665kr5b-1~
-gp\(chips)',
 P_PATH='@baseboard_fab2_lib.baseboard_fab2(sch_1):page197_i119@w_hdl.\665kr5b-1~
-gp\(chips)',
 PATH='I119',
 DRAWING='@BASEBOARD_FAB2_LIB.BASEBOARD_FAB2(SCH_1):PAGE197',
 NEW_VALUE='100K OHM',
 PACK_SIZE='AT0805',
 RATED='1/8W',
 ATTRIBUTE='665K OHM',
 CONFIG='064.1003F.M001',
 TOLERANCE='0.1%',
 PHYS_PAGE='197',
 XY='(-1475,4125)',
 ROT='0',
 VER='1',
 VALUE='665KR5B-1-GP',
 PACK_TYPE='SMD-RG3',
 PART_NUMBER='064.6653F.M001',
 LOCATION='R12W12',
 CDS_LIB='w_hdl',
 CDS_PART_NAME='665KR5B-1-GP_SMD-RG3-665KR5B-1A',
 PRIM_FILE='C:/<user>/w_hdl/665kr5b#2d1#2dgp/chips/chips.prt';

PART_NAME
 R12W13 '4D02R2F-GP_SMD-RG2-4D02R2F-GP,A':;

SECTION_NUMBER 1
 '@BASEBOARD_FAB2_LIB.BASEBOARD_FAB2(SCH_1):PAGE197_I116@W_HDL.4D02R2F-GP(CHIPS)':
 C_PATH='@baseboard_fab2_lib.baseboard_fab2(sch_1):page197_i116@w_hdl.\4d02r2f-g~
p\(chips)',
 P_PATH='@baseboard_fab2_lib.baseboard_fab2(sch_1):page197_i116@w_hdl.\4d02r2f-g~
p\(chips)',
 PATH='I116',
 DRAWING='@BASEBOARD_FAB2_LIB.BASEBOARD_FAB2(SCH_1):PAGE197',
 PACK_SIZE='0402',
 RATED='1/16W',
 ATTRIBUTE='4.02OHM',
 TOLERANCE='1%',
 SEC_TYPE='SMD-RG2',
 PHYS_PAGE='197',
 XY='(-1700,4550)',
 ROT='1',
 VER='1',
 VALUE='4D02R2F-GP',
 PACK_TYPE='SMD-RG2',
 PART_NUMBER='64.4R025.6DL',
 LOCATION='R12W13',
 SEC='1',
 CDS_LIB='w_hdl',
 CDS_PART_NAME='4D02R2F-GP_SMD-RG2-4D02R2F-GP,A',
 PRIM_FILE='C:/<user>/w_hdl/4d02r2f#2dgp/chips/chips.prt';

PART_NAME
 R12W14 'RES_0603-100.0K,1%,1/10W,CHIP,A':
 ROOM='CPU0';

SECTION_NUMBER 1
 '@BASEBOARD_FAB2_LIB.BASEBOARD_FAB2(SCH_1):PAGE197_I53@MSTR_DISCRETE.RES(CHIPS)':
 C_PATH='@baseboard_fab2_lib.baseboard_fab2(sch_1):page197_i53@mstr_discrete.res~
(chips)',
 P_PATH='@baseboard_fab2_lib.baseboard_fab2(sch_1):page197_i53@mstr_discrete.res~
(chips)',
 PATH='I53',
 DRAWING='@BASEBOARD_FAB2_LIB.BASEBOARD_FAB2(SCH_1):PAGE197',
 WATTAGE='1/10W',
 TOLERANCE='1%',
 SEC_TYPE='0603',
 MATERIAL='CHIP',
 BOM_COST='PROC_SOCKET',
 PHYS_PAGE='197',
 XY='(-175,4500)',
 ROT='0',
 VER='2',
 VALUE='100.0K',
 PACK_TYPE='0603',
 PART_NUMBER='G22026-050',
 LOCATION='R12W14',
 ROOM='CPU0',
 SEC='1',
 CDS_LIB='mstr_discrete',
 CDS_PART_NAME='RES_0603-100.0K,1%,1/10W,CHIP,A',
 PRIM_FILE='./archive_libs/mstr_discrete/res/chips/chips.prt';

PART_NAME
 R12W15 '665KR2B-GP_SMD-RG2-665KR2B-GP,A':;

SECTION_NUMBER 1
 '@BASEBOARD_FAB2_LIB.BASEBOARD_FAB2(SCH_1):PAGE197_I112@W_HDL.665KR2B-GP(CHIPS)':
 C_PATH='@baseboard_fab2_lib.baseboard_fab2(sch_1):page197_i112@w_hdl.\665kr2b-g~
p\(chips)',
 P_PATH='@baseboard_fab2_lib.baseboard_fab2(sch_1):page197_i112@w_hdl.\665kr2b-g~
p\(chips)',
 PATH='I112',
 DRAWING='@BASEBOARD_FAB2_LIB.BASEBOARD_FAB2(SCH_1):PAGE197',
 PACK_SIZE='0402',
 RATED='1/16W',
 ATTRIBUTE='665KOHM',
 POP='NOPOP',
 TOLERANCE='0.1%',
 SEC_TYPE='SMD-RG2',
 PHYS_PAGE='197',
 XY='(-1700,3800)',
 ROT='1',
 VER='1',
 VALUE='665KR2B-GP',
 PACK_TYPE='SMD-RG2',
 PART_NUMBER='064.6653D.06DD',
 LOCATION='R12W15',
 SEC='1',
 CDS_LIB='w_hdl',
 CDS_PART_NAME='665KR2B-GP_SMD-RG2-665KR2B-GP,A',
 PRIM_FILE='C:/<user>/w_hdl/665kr2b#2dgp/chips/chips.prt';

PART_NAME
 R12W16 '665KR5B-1-GP_SMD-RG3-665KR5B-1A':;

SECTION_NUMBER 1
 '@BASEBOARD_FAB2_LIB.BASEBOARD_FAB2(SCH_1):PAGE197_I122@W_HDL.665KR5B-1-GP(CHIPS)':
 C_PATH='@baseboard_fab2_lib.baseboard_fab2(sch_1):page197_i122@w_hdl.\665kr5b-1~
-gp\(chips)',
 P_PATH='@baseboard_fab2_lib.baseboard_fab2(sch_1):page197_i122@w_hdl.\665kr5b-1~
-gp\(chips)',
 PATH='I122',
 DRAWING='@BASEBOARD_FAB2_LIB.BASEBOARD_FAB2(SCH_1):PAGE197',
 NEW_VALUE='100K OHM',
 PACK_SIZE='AT0805',
 RATED='1/8W',
 ATTRIBUTE='665K OHM',
 CONFIG='064.1003F.M001',
 TOLERANCE='0.1%',
 PHYS_PAGE='197',
 XY='(-1925,2025)',
 ROT='0',
 VER='1',
 VALUE='665KR5B-1-GP',
 PACK_TYPE='SMD-RG3',
 PART_NUMBER='064.6653F.M001',
 LOCATION='R12W16',
 CDS_LIB='w_hdl',
 CDS_PART_NAME='665KR5B-1-GP_SMD-RG3-665KR5B-1A',
 PRIM_FILE='C:/<user>/w_hdl/665kr5b#2d1#2dgp/chips/chips.prt';

PART_NAME
 R12W17 '665KR5B-1-GP_SMD-RG3-665KR5B-1A':;

SECTION_NUMBER 1
 '@BASEBOARD_FAB2_LIB.BASEBOARD_FAB2(SCH_1):PAGE197_I123@W_HDL.665KR5B-1-GP(CHIPS)':
 C_PATH='@baseboard_fab2_lib.baseboard_fab2(sch_1):page197_i123@w_hdl.\665kr5b-1~
-gp\(chips)',
 P_PATH='@baseboard_fab2_lib.baseboard_fab2(sch_1):page197_i123@w_hdl.\665kr5b-1~
-gp\(chips)',
 PATH='I123',
 DRAWING='@BASEBOARD_FAB2_LIB.BASEBOARD_FAB2(SCH_1):PAGE197',
 NEW_VALUE='100K OHM',
 PACK_SIZE='AT0805',
 RATED='1/8W',
 ATTRIBUTE='665K OHM',
 CONFIG='064.1003F.M001',
 TOLERANCE='0.1%',
 PHYS_PAGE='197',
 XY='(-1475,2025)',
 ROT='0',
 VER='1',
 VALUE='665KR5B-1-GP',
 PACK_TYPE='SMD-RG3',
 PART_NUMBER='064.6653F.M001',
 LOCATION='R12W17',
 CDS_LIB='w_hdl',
 CDS_PART_NAME='665KR5B-1-GP_SMD-RG3-665KR5B-1A',
 PRIM_FILE='C:/<user>/w_hdl/665kr5b#2d1#2dgp/chips/chips.prt';

PART_NAME
 R12W18 '4D02R2F-GP_SMD-RG2-4D02R2F-GP,A':;

SECTION_NUMBER 1
 '@BASEBOARD_FAB2_LIB.BASEBOARD_FAB2(SCH_1):PAGE197_I114@W_HDL.4D02R2F-GP(CHIPS)':
 C_PATH='@baseboard_fab2_lib.baseboard_fab2(sch_1):page197_i114@w_hdl.\4d02r2f-g~
p\(chips)',
 P_PATH='@baseboard_fab2_lib.baseboard_fab2(sch_1):page197_i114@w_hdl.\4d02r2f-g~
p\(chips)',
 PATH='I114',
 DRAWING='@BASEBOARD_FAB2_LIB.BASEBOARD_FAB2(SCH_1):PAGE197',
 PACK_SIZE='0402',
 RATED='1/16W',
 ATTRIBUTE='4.02OHM',
 TOLERANCE='1%',
 SEC_TYPE='SMD-RG2',
 PHYS_PAGE='197',
 XY='(-1700,2450)',
 ROT='1',
 VER='1',
 VALUE='4D02R2F-GP',
 PACK_TYPE='SMD-RG2',
 PART_NUMBER='64.4R025.6DL',
 LOCATION='R12W18',
 SEC='1',
 CDS_LIB='w_hdl',
 CDS_PART_NAME='4D02R2F-GP_SMD-RG2-4D02R2F-GP,A',
 PRIM_FILE='C:/<user>/w_hdl/4d02r2f#2dgp/chips/chips.prt';

PART_NAME
 R12W19 'RES_0603-100.0K,1%,1/10W,CHIP,A':
 ROOM='CPU0';

SECTION_NUMBER 1
 '@BASEBOARD_FAB2_LIB.BASEBOARD_FAB2(SCH_1):PAGE197_I37@MSTR_DISCRETE.RES(CHIPS)':
 C_PATH='@baseboard_fab2_lib.baseboard_fab2(sch_1):page197_i37@mstr_discrete.res~
(chips)',
 P_PATH='@baseboard_fab2_lib.baseboard_fab2(sch_1):page197_i37@mstr_discrete.res~
(chips)',
 PATH='I37',
 DRAWING='@BASEBOARD_FAB2_LIB.BASEBOARD_FAB2(SCH_1):PAGE197',
 WATTAGE='1/10W',
 TOLERANCE='1%',
 SEC_TYPE='0603',
 MATERIAL='CHIP',
 BOM_COST='PROC_SOCKET',
 PHYS_PAGE='197',
 XY='(-175,2400)',
 ROT='0',
 VER='2',
 VALUE='100.0K',
 PACK_TYPE='0603',
 PART_NUMBER='G22026-050',
 LOCATION='R12W19',
 ROOM='CPU0',
 SEC='1',
 CDS_LIB='mstr_discrete',
 CDS_PART_NAME='RES_0603-100.0K,1%,1/10W,CHIP,A',
 PRIM_FILE='./archive_libs/mstr_discrete/res/chips/chips.prt';

PART_NAME
 R12W20 '665KR2B-GP_SMD-RG2-665KR2B-GP,A':;

SECTION_NUMBER 1
 '@BASEBOARD_FAB2_LIB.BASEBOARD_FAB2(SCH_1):PAGE197_I110@W_HDL.665KR2B-GP(CHIPS)':
 C_PATH='@baseboard_fab2_lib.baseboard_fab2(sch_1):page197_i110@w_hdl.\665kr2b-g~
p\(chips)',
 P_PATH='@baseboard_fab2_lib.baseboard_fab2(sch_1):page197_i110@w_hdl.\665kr2b-g~
p\(chips)',
 PATH='I110',
 DRAWING='@BASEBOARD_FAB2_LIB.BASEBOARD_FAB2(SCH_1):PAGE197',
 PACK_SIZE='0402',
 RATED='1/16W',
 ATTRIBUTE='665KOHM',
 POP='NOPOP',
 TOLERANCE='0.1%',
 SEC_TYPE='SMD-RG2',
 PHYS_PAGE='197',
 XY='(-1700,1700)',
 ROT='1',
 VER='1',
 VALUE='665KR2B-GP',
 PACK_TYPE='SMD-RG2',
 PART_NUMBER='064.6653D.06DD',
 LOCATION='R12W20',
 SEC='1',
 CDS_LIB='w_hdl',
 CDS_PART_NAME='665KR2B-GP_SMD-RG2-665KR2B-GP,A',
 PRIM_FILE='C:/<user>/w_hdl/665kr2b#2dgp/chips/chips.prt';

PART_NAME
 R12W25 'RES_0402-0.0,5%,1/16W,CHIP,G21A':
 ROOM='CPU0';

SECTION_NUMBER 1
 '@BASEBOARD_FAB2_LIB.BASEBOARD_FAB2(SCH_1):PAGE215_I74@MSTR_DISCRETE.RES(CHIPS)':
 C_PATH='@baseboard_fab2_lib.baseboard_fab2(sch_1):page215_i74@mstr_discrete.res~
(chips)',
 P_PATH='@baseboard_fab2_lib.baseboard_fab2(sch_1):page215_i74@mstr_discrete.res~
(chips)',
 PATH='I74',
 DRAWING='@BASEBOARD_FAB2_LIB.BASEBOARD_FAB2(SCH_1):PAGE215',
 WATTAGE='1/16W',
 TOLERANCE='5%',
 SEC_TYPE='0402',
 MATERIAL='CHIP',
 BOM_COST='PROC_SIDEBAND',
 PHYS_PAGE='215',
 XY='(4000,1700)',
 ROT='0',
 VER='1',
 VALUE='0.0',
 PACK_TYPE='0402',
 PART_NUMBER='G21497-005',
 LOCATION='R12W25',
 ROOM='CPU0',
 SEC='1',
 CDS_LIB='mstr_discrete',
 CDS_PART_NAME='RES_0402-0.0,5%,1/16W,CHIP,G21A',
 PRIM_FILE='./archive_libs/mstr_discrete/res/chips/chips.prt';

PART_NAME
 R12W26 'RES_0402-0.0,5%,1/16W,EMPTY,G2A':
 ROOM='NV_DIMM';

SECTION_NUMBER 1
 '@BASEBOARD_FAB2_LIB.BASEBOARD_FAB2(SCH_1):PAGE215_I45@MSTR_DISCRETE.RES(CHIPS)':
 C_PATH='@baseboard_fab2_lib.baseboard_fab2(sch_1):page215_i45@mstr_discrete.res~
(chips)',
 P_PATH='@baseboard_fab2_lib.baseboard_fab2(sch_1):page215_i45@mstr_discrete.res~
(chips)',
 PATH='I45',
 DRAWING='@BASEBOARD_FAB2_LIB.BASEBOARD_FAB2(SCH_1):PAGE215',
 WATTAGE='1/16W',
 TOLERANCE='5%',
 SEC_TYPE='0402',
 MATERIAL='EMPTY',
 BOM_COST='MEM_NV',
 PHYS_PAGE='215',
 XY='(4000,1650)',
 ROT='0',
 VER='1',
 VALUE='0.0',
 PACK_TYPE='0402',
 PART_NUMBER='G21497-005',
 LOCATION='R12W26',
 ROOM='NV_DIMM',
 SEC='1',
 CDS_LIB='mstr_discrete',
 CDS_PART_NAME='RES_0402-0.0,5%,1/16W,EMPTY,G2A',
 PRIM_FILE='./archive_libs/mstr_discrete/res/chips/chips.prt';

PART_NAME
 R12W27 'RES_0402-0.0,5%,1/16W,EMPTY,G2A':
 ROOM='NV_DIMM';

SECTION_NUMBER 1
 '@BASEBOARD_FAB2_LIB.BASEBOARD_FAB2(SCH_1):PAGE215_I54@MSTR_DISCRETE.RES(CHIPS)':
 C_PATH='@baseboard_fab2_lib.baseboard_fab2(sch_1):page215_i54@mstr_discrete.res~
(chips)',
 P_PATH='@baseboard_fab2_lib.baseboard_fab2(sch_1):page215_i54@mstr_discrete.res~
(chips)',
 PATH='I54',
 DRAWING='@BASEBOARD_FAB2_LIB.BASEBOARD_FAB2(SCH_1):PAGE215',
 WATTAGE='1/16W',
 TOLERANCE='5%',
 SEC_TYPE='0402',
 MATERIAL='EMPTY',
 BOM_COST='MEM_NV',
 PHYS_PAGE='215',
 XY='(4000,2050)',
 ROT='0',
 VER='1',
 VALUE='0.0',
 PACK_TYPE='0402',
 PART_NUMBER='G21497-005',
 LOCATION='R12W27',
 ROOM='NV_DIMM',
 SEC='1',
 CDS_LIB='mstr_discrete',
 CDS_PART_NAME='RES_0402-0.0,5%,1/16W,EMPTY,G2A',
 PRIM_FILE='./archive_libs/mstr_discrete/res/chips/chips.prt';

PART_NAME
 R12W28 'RES_0402-0.0,5%,1/16W,CHIP,G21A':
 ROOM='CPU0';

SECTION_NUMBER 1
 '@BASEBOARD_FAB2_LIB.BASEBOARD_FAB2(SCH_1):PAGE218_I75@MSTR_DISCRETE.RES(CHIPS)':
 C_PATH='@baseboard_fab2_lib.baseboard_fab2(sch_1):page218_i75@mstr_discrete.res~
(chips)',
 P_PATH='@baseboard_fab2_lib.baseboard_fab2(sch_1):page218_i75@mstr_discrete.res~
(chips)',
 PATH='I75',
 DRAWING='@BASEBOARD_FAB2_LIB.BASEBOARD_FAB2(SCH_1):PAGE218',
 WATTAGE='1/16W',
 TOLERANCE='5%',
 SEC_TYPE='0402',
 MATERIAL='CHIP',
 BOM_COST='PROC_SIDEBAND',
 PHYS_PAGE='218',
 XY='(1825,1600)',
 ROT='0',
 VER='1',
 VALUE='0.0',
 PACK_TYPE='0402',
 PART_NUMBER='G21497-005',
 LOCATION='R12W28',
 ROOM='CPU0',
 SEC='1',
 CDS_LIB='mstr_discrete',
 CDS_PART_NAME='RES_0402-0.0,5%,1/16W,CHIP,G21A',
 PRIM_FILE='./archive_libs/mstr_discrete/res/chips/chips.prt';

PART_NAME
 R12W29 'RES_0402-0.0,5%,1/16W,EMPTY,G2A':
 ROOM='NV_DIMM';

SECTION_NUMBER 1
 '@BASEBOARD_FAB2_LIB.BASEBOARD_FAB2(SCH_1):PAGE218_I46@MSTR_DISCRETE.RES(CHIPS)':
 C_PATH='@baseboard_fab2_lib.baseboard_fab2(sch_1):page218_i46@mstr_discrete.res~
(chips)',
 P_PATH='@baseboard_fab2_lib.baseboard_fab2(sch_1):page218_i46@mstr_discrete.res~
(chips)',
 PATH='I46',
 DRAWING='@BASEBOARD_FAB2_LIB.BASEBOARD_FAB2(SCH_1):PAGE218',
 WATTAGE='1/16W',
 TOLERANCE='5%',
 SEC_TYPE='0402',
 MATERIAL='EMPTY',
 BOM_COST='MEM_NV',
 PHYS_PAGE='218',
 XY='(1825,1550)',
 ROT='0',
 VER='1',
 VALUE='0.0',
 PACK_TYPE='0402',
 PART_NUMBER='G21497-005',
 LOCATION='R12W29',
 ROOM='NV_DIMM',
 SEC='1',
 CDS_LIB='mstr_discrete',
 CDS_PART_NAME='RES_0402-0.0,5%,1/16W,EMPTY,G2A',
 PRIM_FILE='./archive_libs/mstr_discrete/res/chips/chips.prt';

PART_NAME
 R12W30 'RES_0402-0.0,5%,1/16W,EMPTY,G2A':
 ROOM='NV_DIMM';

SECTION_NUMBER 1
 '@BASEBOARD_FAB2_LIB.BASEBOARD_FAB2(SCH_1):PAGE218_I55@MSTR_DISCRETE.RES(CHIPS)':
 C_PATH='@baseboard_fab2_lib.baseboard_fab2(sch_1):page218_i55@mstr_discrete.res~
(chips)',
 P_PATH='@baseboard_fab2_lib.baseboard_fab2(sch_1):page218_i55@mstr_discrete.res~
(chips)',
 PATH='I55',
 DRAWING='@BASEBOARD_FAB2_LIB.BASEBOARD_FAB2(SCH_1):PAGE218',
 WATTAGE='1/16W',
 TOLERANCE='5%',
 SEC_TYPE='0402',
 MATERIAL='EMPTY',
 BOM_COST='MEM_NV',
 PHYS_PAGE='218',
 XY='(1825,1950)',
 ROT='0',
 VER='1',
 VALUE='0.0',
 PACK_TYPE='0402',
 PART_NUMBER='G21497-005',
 LOCATION='R12W30',
 ROOM='NV_DIMM',
 SEC='1',
 CDS_LIB='mstr_discrete',
 CDS_PART_NAME='RES_0402-0.0,5%,1/16W,EMPTY,G2A',
 PRIM_FILE='./archive_libs/mstr_discrete/res/chips/chips.prt';

PART_NAME
 R12W31 'RES_0402-0.0,5%,1/16W,CHIP,G21A':
 ROOM='CPU0';

SECTION_NUMBER 1
 '@BASEBOARD_FAB2_LIB.BASEBOARD_FAB2(SCH_1):PAGE223_I75@MSTR_DISCRETE.RES(CHIPS)':
 C_PATH='@baseboard_fab2_lib.baseboard_fab2(sch_1):page223_i75@mstr_discrete.res~
(chips)',
 P_PATH='@baseboard_fab2_lib.baseboard_fab2(sch_1):page223_i75@mstr_discrete.res~
(chips)',
 PATH='I75',
 DRAWING='@BASEBOARD_FAB2_LIB.BASEBOARD_FAB2(SCH_1):PAGE223',
 WATTAGE='1/16W',
 TOLERANCE='5%',
 SEC_TYPE='0402',
 MATERIAL='CHIP',
 BOM_COST='PROC_SIDEBAND',
 PHYS_PAGE='223',
 XY='(3250,1550)',
 ROT='0',
 VER='1',
 VALUE='0.0',
 PACK_TYPE='0402',
 PART_NUMBER='G21497-005',
 LOCATION='R12W31',
 ROOM='CPU0',
 SEC='1',
 CDS_LIB='mstr_discrete',
 CDS_PART_NAME='RES_0402-0.0,5%,1/16W,CHIP,G21A',
 PRIM_FILE='./archive_libs/mstr_discrete/res/chips/chips.prt';

PART_NAME
 R12W32 'RES_0402-0.0,5%,1/16W,EMPTY,G2A':
 ROOM='NV_DIMM';

SECTION_NUMBER 1
 '@BASEBOARD_FAB2_LIB.BASEBOARD_FAB2(SCH_1):PAGE223_I45@MSTR_DISCRETE.RES(CHIPS)':
 C_PATH='@baseboard_fab2_lib.baseboard_fab2(sch_1):page223_i45@mstr_discrete.res~
(chips)',
 P_PATH='@baseboard_fab2_lib.baseboard_fab2(sch_1):page223_i45@mstr_discrete.res~
(chips)',
 PATH='I45',
 DRAWING='@BASEBOARD_FAB2_LIB.BASEBOARD_FAB2(SCH_1):PAGE223',
 WATTAGE='1/16W',
 TOLERANCE='5%',
 SEC_TYPE='0402',
 MATERIAL='EMPTY',
 BOM_COST='MEM_NV',
 PHYS_PAGE='223',
 XY='(3250,1500)',
 ROT='0',
 VER='1',
 VALUE='0.0',
 PACK_TYPE='0402',
 PART_NUMBER='G21497-005',
 LOCATION='R12W32',
 ROOM='NV_DIMM',
 SEC='1',
 CDS_LIB='mstr_discrete',
 CDS_PART_NAME='RES_0402-0.0,5%,1/16W,EMPTY,G2A',
 PRIM_FILE='./archive_libs/mstr_discrete/res/chips/chips.prt';

PART_NAME
 R12W33 'RES_0402-0.0,5%,1/16W,EMPTY,G2A':
 ROOM='NV_DIMM';

SECTION_NUMBER 1
 '@BASEBOARD_FAB2_LIB.BASEBOARD_FAB2(SCH_1):PAGE223_I53@MSTR_DISCRETE.RES(CHIPS)':
 C_PATH='@baseboard_fab2_lib.baseboard_fab2(sch_1):page223_i53@mstr_discrete.res~
(chips)',
 P_PATH='@baseboard_fab2_lib.baseboard_fab2(sch_1):page223_i53@mstr_discrete.res~
(chips)',
 PATH='I53',
 DRAWING='@BASEBOARD_FAB2_LIB.BASEBOARD_FAB2(SCH_1):PAGE223',
 WATTAGE='1/16W',
 TOLERANCE='5%',
 SEC_TYPE='0402',
 MATERIAL='EMPTY',
 BOM_COST='MEM_NV',
 PHYS_PAGE='223',
 XY='(3250,1900)',
 ROT='0',
 VER='1',
 VALUE='0.0',
 PACK_TYPE='0402',
 PART_NUMBER='G21497-005',
 LOCATION='R12W33',
 ROOM='NV_DIMM',
 SEC='1',
 CDS_LIB='mstr_discrete',
 CDS_PART_NAME='RES_0402-0.0,5%,1/16W,EMPTY,G2A',
 PRIM_FILE='./archive_libs/mstr_discrete/res/chips/chips.prt';

PART_NAME
 R12W34 'RES_0402-0.0,5%,1/16W,CHIP,G21A':
 ROOM='CPU0';

SECTION_NUMBER 1
 '@BASEBOARD_FAB2_LIB.BASEBOARD_FAB2(SCH_1):PAGE226_I74@MSTR_DISCRETE.RES(CHIPS)':
 C_PATH='@baseboard_fab2_lib.baseboard_fab2(sch_1):page226_i74@mstr_discrete.res~
(chips)',
 P_PATH='@baseboard_fab2_lib.baseboard_fab2(sch_1):page226_i74@mstr_discrete.res~
(chips)',
 PATH='I74',
 DRAWING='@BASEBOARD_FAB2_LIB.BASEBOARD_FAB2(SCH_1):PAGE226',
 WATTAGE='1/16W',
 TOLERANCE='5%',
 SEC_TYPE='0402',
 MATERIAL='CHIP',
 BOM_COST='PROC_SIDEBAND',
 PHYS_PAGE='226',
 XY='(2950,1175)',
 ROT='0',
 VER='1',
 VALUE='0.0',
 PACK_TYPE='0402',
 PART_NUMBER='G21497-005',
 LOCATION='R12W34',
 ROOM='CPU0',
 SEC='1',
 CDS_LIB='mstr_discrete',
 CDS_PART_NAME='RES_0402-0.0,5%,1/16W,CHIP,G21A',
 PRIM_FILE='./archive_libs/mstr_discrete/res/chips/chips.prt';

PART_NAME
 R12W35 'RES_0402-0.0,5%,1/16W,EMPTY,G2A':
 ROOM='NV_DIMM';

SECTION_NUMBER 1
 '@BASEBOARD_FAB2_LIB.BASEBOARD_FAB2(SCH_1):PAGE226_I46@MSTR_DISCRETE.RES(CHIPS)':
 C_PATH='@baseboard_fab2_lib.baseboard_fab2(sch_1):page226_i46@mstr_discrete.res~
(chips)',
 P_PATH='@baseboard_fab2_lib.baseboard_fab2(sch_1):page226_i46@mstr_discrete.res~
(chips)',
 PATH='I46',
 DRAWING='@BASEBOARD_FAB2_LIB.BASEBOARD_FAB2(SCH_1):PAGE226',
 WATTAGE='1/16W',
 TOLERANCE='5%',
 SEC_TYPE='0402',
 MATERIAL='EMPTY',
 BOM_COST='MEM_NV',
 PHYS_PAGE='226',
 XY='(2950,1125)',
 ROT='0',
 VER='1',
 VALUE='0.0',
 PACK_TYPE='0402',
 PART_NUMBER='G21497-005',
 LOCATION='R12W35',
 ROOM='NV_DIMM',
 SEC='1',
 CDS_LIB='mstr_discrete',
 CDS_PART_NAME='RES_0402-0.0,5%,1/16W,EMPTY,G2A',
 PRIM_FILE='./archive_libs/mstr_discrete/res/chips/chips.prt';

PART_NAME
 R12W36 'RES_0402-0.0,5%,1/16W,EMPTY,G2A':
 ROOM='NV_DIMM';

SECTION_NUMBER 1
 '@BASEBOARD_FAB2_LIB.BASEBOARD_FAB2(SCH_1):PAGE226_I53@MSTR_DISCRETE.RES(CHIPS)':
 C_PATH='@baseboard_fab2_lib.baseboard_fab2(sch_1):page226_i53@mstr_discrete.res~
(chips)',
 P_PATH='@baseboard_fab2_lib.baseboard_fab2(sch_1):page226_i53@mstr_discrete.res~
(chips)',
 PATH='I53',
 DRAWING='@BASEBOARD_FAB2_LIB.BASEBOARD_FAB2(SCH_1):PAGE226',
 WATTAGE='1/16W',
 TOLERANCE='5%',
 SEC_TYPE='0402',
 MATERIAL='EMPTY',
 BOM_COST='MEM_NV',
 PHYS_PAGE='226',
 XY='(2950,1525)',
 ROT='0',
 VER='1',
 VALUE='0.0',
 PACK_TYPE='0402',
 PART_NUMBER='G21497-005',
 LOCATION='R12W36',
 ROOM='NV_DIMM',
 SEC='1',
 CDS_LIB='mstr_discrete',
 CDS_PART_NAME='RES_0402-0.0,5%,1/16W,EMPTY,G2A',
 PRIM_FILE='./archive_libs/mstr_discrete/res/chips/chips.prt';

PART_NAME
 R24W1 'RES_0402-3.3K,5%,1/16W,CHIP,G2A':;

SECTION_NUMBER 1
 '@BASEBOARD_FAB2_LIB.BASEBOARD_FAB2(SCH_1):PAGE138_I198@MSTR_DISCRETE.RES(CHIPS)':
 C_PATH='@baseboard_fab2_lib.baseboard_fab2(sch_1):page138_i198@mstr_discrete.re~
s(chips)',
 P_PATH='@baseboard_fab2_lib.baseboard_fab2(sch_1):page138_i198@mstr_discrete.re~
s(chips)',
 PATH='I198',
 DRAWING='@BASEBOARD_FAB2_LIB.BASEBOARD_FAB2(SCH_1):PAGE138',
 WATTAGE='1/16W',
 TOLERANCE='5%',
 SEC_TYPE='0402',
 MATERIAL='CHIP',
 PHYS_PAGE='138',
 XY='(-600,1650)',
 ROT='5',
 VER='1',
 VALUE='3.3K',
 PACK_TYPE='0402',
 PART_NUMBER='G21497-013',
 LOCATION='R24W1',
 SEC='1',
 CDS_LIB='mstr_discrete',
 CDS_PART_NAME='RES_0402-3.3K,5%,1/16W,CHIP,G2A',
 PRIM_FILE='./archive_libs/mstr_discrete/res/chips/chips.prt';

PART_NAME
 R24W2 'RES_0402-3.3K,5%,1/16W,CHIP,G2A':;

SECTION_NUMBER 1
 '@BASEBOARD_FAB2_LIB.BASEBOARD_FAB2(SCH_1):PAGE138_I199@MSTR_DISCRETE.RES(CHIPS)':
 C_PATH='@baseboard_fab2_lib.baseboard_fab2(sch_1):page138_i199@mstr_discrete.re~
s(chips)',
 P_PATH='@baseboard_fab2_lib.baseboard_fab2(sch_1):page138_i199@mstr_discrete.re~
s(chips)',
 PATH='I199',
 DRAWING='@BASEBOARD_FAB2_LIB.BASEBOARD_FAB2(SCH_1):PAGE138',
 WATTAGE='1/16W',
 TOLERANCE='5%',
 SEC_TYPE='0402',
 MATERIAL='CHIP',
 PHYS_PAGE='138',
 XY='(-200,1650)',
 ROT='5',
 VER='1',
 VALUE='3.3K',
 PACK_TYPE='0402',
 PART_NUMBER='G21497-013',
 LOCATION='R24W2',
 SEC='1',
 CDS_LIB='mstr_discrete',
 CDS_PART_NAME='RES_0402-3.3K,5%,1/16W,CHIP,G2A',
 PRIM_FILE='./archive_libs/mstr_discrete/res/chips/chips.prt';

PART_NAME
 R25W1 '120R2F-GP_RCL_GP-120R2F-GP,64.A':;

SECTION_NUMBER 1
 '@BASEBOARD_FAB2_LIB.BASEBOARD_FAB2(SCH_1):PAGE151_I248@W_HDL.120R2F-GP(CHIPS)':
 C_PATH='@baseboard_fab2_lib.baseboard_fab2(sch_1):page151_i248@w_hdl.\120r2f-gp~
\(chips)',
 P_PATH='@baseboard_fab2_lib.baseboard_fab2(sch_1):page151_i248@w_hdl.\120r2f-gp~
\(chips)',
 PATH='I248',
 DRAWING='@BASEBOARD_FAB2_LIB.BASEBOARD_FAB2(SCH_1):PAGE151',
 PACK_SIZE='0402',
 RATED='1/16W',
 ATTRIBUTE='120OHM',
 TOLERANCE='1%',
 SEC_TYPE='RCL_GP',
 PHYS_PAGE='151',
 XY='(-3025,1675)',
 ROT='1',
 VER='1',
 VALUE='120R2F-GP',
 PACK_TYPE='RCL_GP',
 PART_NUMBER='64.12005.6DL',
 LOCATION='R25W1',
 SEC='1',
 CDS_LIB='w_hdl',
 CDS_PART_NAME='120R2F-GP_RCL_GP-120R2F-GP,64.A',
 PRIM_FILE='C:/<user>/w_hdl/120r2f#2dgp/chips/chips.prt';

PART_NAME
 R25W2 '120R2F-GP_RCL_GP-120R2F-GP,64.A':;

SECTION_NUMBER 1
 '@BASEBOARD_FAB2_LIB.BASEBOARD_FAB2(SCH_1):PAGE151_I249@W_HDL.120R2F-GP(CHIPS)':
 C_PATH='@baseboard_fab2_lib.baseboard_fab2(sch_1):page151_i249@w_hdl.\120r2f-gp~
\(chips)',
 P_PATH='@baseboard_fab2_lib.baseboard_fab2(sch_1):page151_i249@w_hdl.\120r2f-gp~
\(chips)',
 PATH='I249',
 DRAWING='@BASEBOARD_FAB2_LIB.BASEBOARD_FAB2(SCH_1):PAGE151',
 PACK_SIZE='0402',
 RATED='1/16W',
 ATTRIBUTE='120OHM',
 TOLERANCE='1%',
 SEC_TYPE='RCL_GP',
 PHYS_PAGE='151',
 XY='(-3025,1625)',
 ROT='1',
 VER='1',
 VALUE='120R2F-GP',
 PACK_TYPE='RCL_GP',
 PART_NUMBER='64.12005.6DL',
 LOCATION='R25W2',
 SEC='1',
 CDS_LIB='w_hdl',
 CDS_PART_NAME='120R2F-GP_RCL_GP-120R2F-GP,64.A',
 PRIM_FILE='C:/<user>/w_hdl/120r2f#2dgp/chips/chips.prt';

PART_NAME
 R25W3 '120R2F-GP_RCL_GP-120R2F-GP,64.A':;

SECTION_NUMBER 1
 '@BASEBOARD_FAB2_LIB.BASEBOARD_FAB2(SCH_1):PAGE151_I250@W_HDL.120R2F-GP(CHIPS)':
 C_PATH='@baseboard_fab2_lib.baseboard_fab2(sch_1):page151_i250@w_hdl.\120r2f-gp~
\(chips)',
 P_PATH='@baseboard_fab2_lib.baseboard_fab2(sch_1):page151_i250@w_hdl.\120r2f-gp~
\(chips)',
 PATH='I250',
 DRAWING='@BASEBOARD_FAB2_LIB.BASEBOARD_FAB2(SCH_1):PAGE151',
 PACK_SIZE='0402',
 RATED='1/16W',
 ATTRIBUTE='120OHM',
 POP='NOPOP',
 TOLERANCE='1%',
 SEC_TYPE='RCL_GP',
 PHYS_PAGE='151',
 XY='(-3025,1575)',
 ROT='1',
 VER='1',
 VALUE='120R2F-GP',
 PACK_TYPE='RCL_GP',
 PART_NUMBER='64.12005.6DL',
 LOCATION='R25W3',
 SEC='1',
 CDS_LIB='w_hdl',
 CDS_PART_NAME='120R2F-GP_RCL_GP-120R2F-GP,64.A',
 PRIM_FILE='C:/<user>/w_hdl/120r2f#2dgp/chips/chips.prt';

PART_NAME
 R25W4 '120R2F-GP_RCL_GP-120R2F-GP,64.A':;

SECTION_NUMBER 1
 '@BASEBOARD_FAB2_LIB.BASEBOARD_FAB2(SCH_1):PAGE151_I251@W_HDL.120R2F-GP(CHIPS)':
 C_PATH='@baseboard_fab2_lib.baseboard_fab2(sch_1):page151_i251@w_hdl.\120r2f-gp~
\(chips)',
 P_PATH='@baseboard_fab2_lib.baseboard_fab2(sch_1):page151_i251@w_hdl.\120r2f-gp~
\(chips)',
 PATH='I251',
 DRAWING='@BASEBOARD_FAB2_LIB.BASEBOARD_FAB2(SCH_1):PAGE151',
 PACK_SIZE='0402',
 RATED='1/16W',
 ATTRIBUTE='120OHM',
 POP='NOPOP',
 TOLERANCE='1%',
 SEC_TYPE='RCL_GP',
 PHYS_PAGE='151',
 XY='(-3025,1525)',
 ROT='1',
 VER='1',
 VALUE='120R2F-GP',
 PACK_TYPE='RCL_GP',
 PART_NUMBER='64.12005.6DL',
 LOCATION='R25W4',
 SEC='1',
 CDS_LIB='w_hdl',
 CDS_PART_NAME='120R2F-GP_RCL_GP-120R2F-GP,64.A',
 PRIM_FILE='C:/<user>/w_hdl/120r2f#2dgp/chips/chips.prt';

PART_NAME
 R25W5 '120R2F-GP_RCL_GP-120R2F-GP,64.A':;

SECTION_NUMBER 1
 '@BASEBOARD_FAB2_LIB.BASEBOARD_FAB2(SCH_1):PAGE151_I252@W_HDL.120R2F-GP(CHIPS)':
 C_PATH='@baseboard_fab2_lib.baseboard_fab2(sch_1):page151_i252@w_hdl.\120r2f-gp~
\(chips)',
 P_PATH='@baseboard_fab2_lib.baseboard_fab2(sch_1):page151_i252@w_hdl.\120r2f-gp~
\(chips)',
 PATH='I252',
 DRAWING='@BASEBOARD_FAB2_LIB.BASEBOARD_FAB2(SCH_1):PAGE151',
 PACK_SIZE='0402',
 RATED='1/16W',
 ATTRIBUTE='120OHM',
 TOLERANCE='1%',
 SEC_TYPE='RCL_GP',
 PHYS_PAGE='151',
 XY='(-3025,1475)',
 ROT='1',
 VER='1',
 VALUE='120R2F-GP',
 PACK_TYPE='RCL_GP',
 PART_NUMBER='64.12005.6DL',
 LOCATION='R25W5',
 SEC='1',
 CDS_LIB='w_hdl',
 CDS_PART_NAME='120R2F-GP_RCL_GP-120R2F-GP,64.A',
 PRIM_FILE='C:/<user>/w_hdl/120r2f#2dgp/chips/chips.prt';

PART_NAME
 R25W6 '120R2F-GP_RCL_GP-120R2F-GP,64.A':;

SECTION_NUMBER 1
 '@BASEBOARD_FAB2_LIB.BASEBOARD_FAB2(SCH_1):PAGE151_I253@W_HDL.120R2F-GP(CHIPS)':
 C_PATH='@baseboard_fab2_lib.baseboard_fab2(sch_1):page151_i253@w_hdl.\120r2f-gp~
\(chips)',
 P_PATH='@baseboard_fab2_lib.baseboard_fab2(sch_1):page151_i253@w_hdl.\120r2f-gp~
\(chips)',
 PATH='I253',
 DRAWING='@BASEBOARD_FAB2_LIB.BASEBOARD_FAB2(SCH_1):PAGE151',
 PACK_SIZE='0402',
 RATED='1/16W',
 ATTRIBUTE='120OHM',
 TOLERANCE='1%',
 SEC_TYPE='RCL_GP',
 PHYS_PAGE='151',
 XY='(-3025,1425)',
 ROT='1',
 VER='1',
 VALUE='120R2F-GP',
 PACK_TYPE='RCL_GP',
 PART_NUMBER='64.12005.6DL',
 LOCATION='R25W6',
 SEC='1',
 CDS_LIB='w_hdl',
 CDS_PART_NAME='120R2F-GP_RCL_GP-120R2F-GP,64.A',
 PRIM_FILE='C:/<user>/w_hdl/120r2f#2dgp/chips/chips.prt';

PART_NAME
 R25W7 '120R2F-GP_RCL_GP-120R2F-GP,64.A':;

SECTION_NUMBER 1
 '@BASEBOARD_FAB2_LIB.BASEBOARD_FAB2(SCH_1):PAGE151_I254@W_HDL.120R2F-GP(CHIPS)':
 C_PATH='@baseboard_fab2_lib.baseboard_fab2(sch_1):page151_i254@w_hdl.\120r2f-gp~
\(chips)',
 P_PATH='@baseboard_fab2_lib.baseboard_fab2(sch_1):page151_i254@w_hdl.\120r2f-gp~
\(chips)',
 PATH='I254',
 DRAWING='@BASEBOARD_FAB2_LIB.BASEBOARD_FAB2(SCH_1):PAGE151',
 PACK_SIZE='0402',
 RATED='1/16W',
 ATTRIBUTE='120OHM',
 TOLERANCE='1%',
 SEC_TYPE='RCL_GP',
 PHYS_PAGE='151',
 XY='(-3025,1375)',
 ROT='1',
 VER='1',
 VALUE='120R2F-GP',
 PACK_TYPE='RCL_GP',
 PART_NUMBER='64.12005.6DL',
 LOCATION='R25W7',
 SEC='1',
 CDS_LIB='w_hdl',
 CDS_PART_NAME='120R2F-GP_RCL_GP-120R2F-GP,64.A',
 PRIM_FILE='C:/<user>/w_hdl/120r2f#2dgp/chips/chips.prt';

PART_NAME
 R25W8 '120R2F-GP_RCL_GP-120R2F-GP,64.A':;

SECTION_NUMBER 1
 '@BASEBOARD_FAB2_LIB.BASEBOARD_FAB2(SCH_1):PAGE151_I255@W_HDL.120R2F-GP(CHIPS)':
 C_PATH='@baseboard_fab2_lib.baseboard_fab2(sch_1):page151_i255@w_hdl.\120r2f-gp~
\(chips)',
 P_PATH='@baseboard_fab2_lib.baseboard_fab2(sch_1):page151_i255@w_hdl.\120r2f-gp~
\(chips)',
 PATH='I255',
 DRAWING='@BASEBOARD_FAB2_LIB.BASEBOARD_FAB2(SCH_1):PAGE151',
 PACK_SIZE='0402',
 RATED='1/16W',
 ATTRIBUTE='120OHM',
 TOLERANCE='1%',
 SEC_TYPE='RCL_GP',
 PHYS_PAGE='151',
 XY='(-3025,1325)',
 ROT='1',
 VER='1',
 VALUE='120R2F-GP',
 PACK_TYPE='RCL_GP',
 PART_NUMBER='64.12005.6DL',
 LOCATION='R25W8',
 SEC='1',
 CDS_LIB='w_hdl',
 CDS_PART_NAME='120R2F-GP_RCL_GP-120R2F-GP,64.A',
 PRIM_FILE='C:/<user>/w_hdl/120r2f#2dgp/chips/chips.prt';

PART_NAME
 R25W9 '120R2F-GP_RCL_GP-120R2F-GP,64.A':;

SECTION_NUMBER 1
 '@BASEBOARD_FAB2_LIB.BASEBOARD_FAB2(SCH_1):PAGE151_I258@W_HDL.120R2F-GP(CHIPS)':
 C_PATH='@baseboard_fab2_lib.baseboard_fab2(sch_1):page151_i258@w_hdl.\120r2f-gp~
\(chips)',
 P_PATH='@baseboard_fab2_lib.baseboard_fab2(sch_1):page151_i258@w_hdl.\120r2f-gp~
\(chips)',
 PATH='I258',
 DRAWING='@BASEBOARD_FAB2_LIB.BASEBOARD_FAB2(SCH_1):PAGE151',
 PACK_SIZE='0402',
 RATED='1/16W',
 ATTRIBUTE='120OHM',
 TOLERANCE='1%',
 SEC_TYPE='RCL_GP',
 PHYS_PAGE='151',
 XY='(-3025,1275)',
 ROT='1',
 VER='1',
 VALUE='120R2F-GP',
 PACK_TYPE='RCL_GP',
 PART_NUMBER='64.12005.6DL',
 LOCATION='R25W9',
 SEC='1',
 CDS_LIB='w_hdl',
 CDS_PART_NAME='120R2F-GP_RCL_GP-120R2F-GP,64.A',
 PRIM_FILE='C:/<user>/w_hdl/120r2f#2dgp/chips/chips.prt';

PART_NAME
 R25W10 '120R2F-GP_RCL_GP-120R2F-GP,64.A':;

SECTION_NUMBER 1
 '@BASEBOARD_FAB2_LIB.BASEBOARD_FAB2(SCH_1):PAGE151_I259@W_HDL.120R2F-GP(CHIPS)':
 C_PATH='@baseboard_fab2_lib.baseboard_fab2(sch_1):page151_i259@w_hdl.\120r2f-gp~
\(chips)',
 P_PATH='@baseboard_fab2_lib.baseboard_fab2(sch_1):page151_i259@w_hdl.\120r2f-gp~
\(chips)',
 PATH='I259',
 DRAWING='@BASEBOARD_FAB2_LIB.BASEBOARD_FAB2(SCH_1):PAGE151',
 PACK_SIZE='0402',
 RATED='1/16W',
 ATTRIBUTE='120OHM',
 TOLERANCE='1%',
 SEC_TYPE='RCL_GP',
 PHYS_PAGE='151',
 XY='(-3025,1225)',
 ROT='1',
 VER='1',
 VALUE='120R2F-GP',
 PACK_TYPE='RCL_GP',
 PART_NUMBER='64.12005.6DL',
 LOCATION='R25W10',
 SEC='1',
 CDS_LIB='w_hdl',
 CDS_PART_NAME='120R2F-GP_RCL_GP-120R2F-GP,64.A',
 PRIM_FILE='C:/<user>/w_hdl/120r2f#2dgp/chips/chips.prt';

PART_NAME
 R25W11 '120R2F-GP_RCL_GP-120R2F-GP,64.A':;

SECTION_NUMBER 1
 '@BASEBOARD_FAB2_LIB.BASEBOARD_FAB2(SCH_1):PAGE151_I257@W_HDL.120R2F-GP(CHIPS)':
 C_PATH='@baseboard_fab2_lib.baseboard_fab2(sch_1):page151_i257@w_hdl.\120r2f-gp~
\(chips)',
 P_PATH='@baseboard_fab2_lib.baseboard_fab2(sch_1):page151_i257@w_hdl.\120r2f-gp~
\(chips)',
 PATH='I257',
 DRAWING='@BASEBOARD_FAB2_LIB.BASEBOARD_FAB2(SCH_1):PAGE151',
 PACK_SIZE='0402',
 RATED='1/16W',
 ATTRIBUTE='120OHM',
 TOLERANCE='1%',
 SEC_TYPE='RCL_GP',
 PHYS_PAGE='151',
 XY='(-3025,1175)',
 ROT='1',
 VER='1',
 VALUE='120R2F-GP',
 PACK_TYPE='RCL_GP',
 PART_NUMBER='64.12005.6DL',
 LOCATION='R25W11',
 SEC='1',
 CDS_LIB='w_hdl',
 CDS_PART_NAME='120R2F-GP_RCL_GP-120R2F-GP,64.A',
 PRIM_FILE='C:/<user>/w_hdl/120r2f#2dgp/chips/chips.prt';

PART_NAME
 R25W12 '120R2F-GP_RCL_GP-120R2F-GP,64.A':;

SECTION_NUMBER 1
 '@BASEBOARD_FAB2_LIB.BASEBOARD_FAB2(SCH_1):PAGE151_I256@W_HDL.120R2F-GP(CHIPS)':
 C_PATH='@baseboard_fab2_lib.baseboard_fab2(sch_1):page151_i256@w_hdl.\120r2f-gp~
\(chips)',
 P_PATH='@baseboard_fab2_lib.baseboard_fab2(sch_1):page151_i256@w_hdl.\120r2f-gp~
\(chips)',
 PATH='I256',
 DRAWING='@BASEBOARD_FAB2_LIB.BASEBOARD_FAB2(SCH_1):PAGE151',
 PACK_SIZE='0402',
 RATED='1/16W',
 ATTRIBUTE='120OHM',
 TOLERANCE='1%',
 SEC_TYPE='RCL_GP',
 PHYS_PAGE='151',
 XY='(-3025,1125)',
 ROT='1',
 VER='1',
 VALUE='120R2F-GP',
 PACK_TYPE='RCL_GP',
 PART_NUMBER='64.12005.6DL',
 LOCATION='R25W12',
 SEC='1',
 CDS_LIB='w_hdl',
 CDS_PART_NAME='120R2F-GP_RCL_GP-120R2F-GP,64.A',
 PRIM_FILE='C:/<user>/w_hdl/120r2f#2dgp/chips/chips.prt';

PART_NAME
 R25W13 '120R2F-GP_RCL_GP-120R2F-GP,64.A':;

SECTION_NUMBER 1
 '@BASEBOARD_FAB2_LIB.BASEBOARD_FAB2(SCH_1):PAGE151_I260@W_HDL.120R2F-GP(CHIPS)':
 C_PATH='@baseboard_fab2_lib.baseboard_fab2(sch_1):page151_i260@w_hdl.\120r2f-gp~
\(chips)',
 P_PATH='@baseboard_fab2_lib.baseboard_fab2(sch_1):page151_i260@w_hdl.\120r2f-gp~
\(chips)',
 PATH='I260',
 DRAWING='@BASEBOARD_FAB2_LIB.BASEBOARD_FAB2(SCH_1):PAGE151',
 PACK_SIZE='0402',
 RATED='1/16W',
 ATTRIBUTE='120OHM',
 TOLERANCE='1%',
 SEC_TYPE='RCL_GP',
 PHYS_PAGE='151',
 XY='(-3025,1075)',
 ROT='1',
 VER='1',
 VALUE='120R2F-GP',
 PACK_TYPE='RCL_GP',
 PART_NUMBER='64.12005.6DL',
 LOCATION='R25W13',
 SEC='1',
 CDS_LIB='w_hdl',
 CDS_PART_NAME='120R2F-GP_RCL_GP-120R2F-GP,64.A',
 PRIM_FILE='C:/<user>/w_hdl/120r2f#2dgp/chips/chips.prt';

PART_NAME
 R25W14 '120R2F-GP_RCL_GP-120R2F-GP,64.A':;

SECTION_NUMBER 1
 '@BASEBOARD_FAB2_LIB.BASEBOARD_FAB2(SCH_1):PAGE151_I263@W_HDL.120R2F-GP(CHIPS)':
 C_PATH='@baseboard_fab2_lib.baseboard_fab2(sch_1):page151_i263@w_hdl.\120r2f-gp~
\(chips)',
 P_PATH='@baseboard_fab2_lib.baseboard_fab2(sch_1):page151_i263@w_hdl.\120r2f-gp~
\(chips)',
 PATH='I263',
 DRAWING='@BASEBOARD_FAB2_LIB.BASEBOARD_FAB2(SCH_1):PAGE151',
 PACK_SIZE='0402',
 RATED='1/16W',
 ATTRIBUTE='120OHM',
 TOLERANCE='1%',
 SEC_TYPE='RCL_GP',
 PHYS_PAGE='151',
 XY='(-3025,1025)',
 ROT='1',
 VER='1',
 VALUE='120R2F-GP',
 PACK_TYPE='RCL_GP',
 PART_NUMBER='64.12005.6DL',
 LOCATION='R25W14',
 SEC='1',
 CDS_LIB='w_hdl',
 CDS_PART_NAME='120R2F-GP_RCL_GP-120R2F-GP,64.A',
 PRIM_FILE='C:/<user>/w_hdl/120r2f#2dgp/chips/chips.prt';

PART_NAME
 R25W15 '120R2F-GP_RCL_GP-120R2F-GP,64.A':;

SECTION_NUMBER 1
 '@BASEBOARD_FAB2_LIB.BASEBOARD_FAB2(SCH_1):PAGE151_I262@W_HDL.120R2F-GP(CHIPS)':
 C_PATH='@baseboard_fab2_lib.baseboard_fab2(sch_1):page151_i262@w_hdl.\120r2f-gp~
\(chips)',
 P_PATH='@baseboard_fab2_lib.baseboard_fab2(sch_1):page151_i262@w_hdl.\120r2f-gp~
\(chips)',
 PATH='I262',
 DRAWING='@BASEBOARD_FAB2_LIB.BASEBOARD_FAB2(SCH_1):PAGE151',
 PACK_SIZE='0402',
 RATED='1/16W',
 ATTRIBUTE='120OHM',
 TOLERANCE='1%',
 SEC_TYPE='RCL_GP',
 PHYS_PAGE='151',
 XY='(-3025,975)',
 ROT='1',
 VER='1',
 VALUE='120R2F-GP',
 PACK_TYPE='RCL_GP',
 PART_NUMBER='64.12005.6DL',
 LOCATION='R25W15',
 SEC='1',
 CDS_LIB='w_hdl',
 CDS_PART_NAME='120R2F-GP_RCL_GP-120R2F-GP,64.A',
 PRIM_FILE='C:/<user>/w_hdl/120r2f#2dgp/chips/chips.prt';

PART_NAME
 R25W16 '120R2F-GP_RCL_GP-120R2F-GP,64.A':;

SECTION_NUMBER 1
 '@BASEBOARD_FAB2_LIB.BASEBOARD_FAB2(SCH_1):PAGE151_I261@W_HDL.120R2F-GP(CHIPS)':
 C_PATH='@baseboard_fab2_lib.baseboard_fab2(sch_1):page151_i261@w_hdl.\120r2f-gp~
\(chips)',
 P_PATH='@baseboard_fab2_lib.baseboard_fab2(sch_1):page151_i261@w_hdl.\120r2f-gp~
\(chips)',
 PATH='I261',
 DRAWING='@BASEBOARD_FAB2_LIB.BASEBOARD_FAB2(SCH_1):PAGE151',
 PACK_SIZE='0402',
 RATED='1/16W',
 ATTRIBUTE='120OHM',
 TOLERANCE='1%',
 SEC_TYPE='RCL_GP',
 PHYS_PAGE='151',
 XY='(-3025,925)',
 ROT='1',
 VER='1',
 VALUE='120R2F-GP',
 PACK_TYPE='RCL_GP',
 PART_NUMBER='64.12005.6DL',
 LOCATION='R25W16',
 SEC='1',
 CDS_LIB='w_hdl',
 CDS_PART_NAME='120R2F-GP_RCL_GP-120R2F-GP,64.A',
 PRIM_FILE='C:/<user>/w_hdl/120r2f#2dgp/chips/chips.prt';

PART_NAME
 R25W17 '120R2F-GP_RCL_GP-120R2F-GP,64.A':;

SECTION_NUMBER 1
 '@BASEBOARD_FAB2_LIB.BASEBOARD_FAB2(SCH_1):PAGE151_I264@W_HDL.120R2F-GP(CHIPS)':
 C_PATH='@baseboard_fab2_lib.baseboard_fab2(sch_1):page151_i264@w_hdl.\120r2f-gp~
\(chips)',
 P_PATH='@baseboard_fab2_lib.baseboard_fab2(sch_1):page151_i264@w_hdl.\120r2f-gp~
\(chips)',
 PATH='I264',
 DRAWING='@BASEBOARD_FAB2_LIB.BASEBOARD_FAB2(SCH_1):PAGE151',
 PACK_SIZE='0402',
 RATED='1/16W',
 ATTRIBUTE='120OHM',
 TOLERANCE='1%',
 SEC_TYPE='RCL_GP',
 PHYS_PAGE='151',
 XY='(-3025,875)',
 ROT='1',
 VER='1',
 VALUE='120R2F-GP',
 PACK_TYPE='RCL_GP',
 PART_NUMBER='64.12005.6DL',
 LOCATION='R25W17',
 SEC='1',
 CDS_LIB='w_hdl',
 CDS_PART_NAME='120R2F-GP_RCL_GP-120R2F-GP,64.A',
 PRIM_FILE='C:/<user>/w_hdl/120r2f#2dgp/chips/chips.prt';

PART_NAME
 R25W18 '120R2F-GP_RCL_GP-120R2F-GP,64.A':;

SECTION_NUMBER 1
 '@BASEBOARD_FAB2_LIB.BASEBOARD_FAB2(SCH_1):PAGE151_I265@W_HDL.120R2F-GP(CHIPS)':
 C_PATH='@baseboard_fab2_lib.baseboard_fab2(sch_1):page151_i265@w_hdl.\120r2f-gp~
\(chips)',
 P_PATH='@baseboard_fab2_lib.baseboard_fab2(sch_1):page151_i265@w_hdl.\120r2f-gp~
\(chips)',
 PATH='I265',
 DRAWING='@BASEBOARD_FAB2_LIB.BASEBOARD_FAB2(SCH_1):PAGE151',
 PACK_SIZE='0402',
 RATED='1/16W',
 ATTRIBUTE='120OHM',
 TOLERANCE='1%',
 SEC_TYPE='RCL_GP',
 PHYS_PAGE='151',
 XY='(-3025,825)',
 ROT='1',
 VER='1',
 VALUE='120R2F-GP',
 PACK_TYPE='RCL_GP',
 PART_NUMBER='64.12005.6DL',
 LOCATION='R25W18',
 SEC='1',
 CDS_LIB='w_hdl',
 CDS_PART_NAME='120R2F-GP_RCL_GP-120R2F-GP,64.A',
 PRIM_FILE='C:/<user>/w_hdl/120r2f#2dgp/chips/chips.prt';

PART_NAME
 R25W19 '120R2F-GP_RCL_GP-120R2F-GP,64.A':;

SECTION_NUMBER 1
 '@BASEBOARD_FAB2_LIB.BASEBOARD_FAB2(SCH_1):PAGE151_I267@W_HDL.120R2F-GP(CHIPS)':
 C_PATH='@baseboard_fab2_lib.baseboard_fab2(sch_1):page151_i267@w_hdl.\120r2f-gp~
\(chips)',
 P_PATH='@baseboard_fab2_lib.baseboard_fab2(sch_1):page151_i267@w_hdl.\120r2f-gp~
\(chips)',
 PATH='I267',
 DRAWING='@BASEBOARD_FAB2_LIB.BASEBOARD_FAB2(SCH_1):PAGE151',
 PACK_SIZE='0402',
 RATED='1/16W',
 ATTRIBUTE='120OHM',
 TOLERANCE='1%',
 SEC_TYPE='RCL_GP',
 PHYS_PAGE='151',
 XY='(-3025,775)',
 ROT='1',
 VER='1',
 VALUE='120R2F-GP',
 PACK_TYPE='RCL_GP',
 PART_NUMBER='64.12005.6DL',
 LOCATION='R25W19',
 SEC='1',
 CDS_LIB='w_hdl',
 CDS_PART_NAME='120R2F-GP_RCL_GP-120R2F-GP,64.A',
 PRIM_FILE='C:/<user>/w_hdl/120r2f#2dgp/chips/chips.prt';

PART_NAME
 R25W20 '120R2F-GP_RCL_GP-120R2F-GP,64.A':;

SECTION_NUMBER 1
 '@BASEBOARD_FAB2_LIB.BASEBOARD_FAB2(SCH_1):PAGE151_I266@W_HDL.120R2F-GP(CHIPS)':
 C_PATH='@baseboard_fab2_lib.baseboard_fab2(sch_1):page151_i266@w_hdl.\120r2f-gp~
\(chips)',
 P_PATH='@baseboard_fab2_lib.baseboard_fab2(sch_1):page151_i266@w_hdl.\120r2f-gp~
\(chips)',
 PATH='I266',
 DRAWING='@BASEBOARD_FAB2_LIB.BASEBOARD_FAB2(SCH_1):PAGE151',
 PACK_SIZE='0402',
 RATED='1/16W',
 ATTRIBUTE='120OHM',
 TOLERANCE='1%',
 SEC_TYPE='RCL_GP',
 PHYS_PAGE='151',
 XY='(-3025,725)',
 ROT='1',
 VER='1',
 VALUE='120R2F-GP',
 PACK_TYPE='RCL_GP',
 PART_NUMBER='64.12005.6DL',
 LOCATION='R25W20',
 SEC='1',
 CDS_LIB='w_hdl',
 CDS_PART_NAME='120R2F-GP_RCL_GP-120R2F-GP,64.A',
 PRIM_FILE='C:/<user>/w_hdl/120r2f#2dgp/chips/chips.prt';

PART_NAME
 R25W21 '120R2F-GP_RCL_GP-120R2F-GP,64.A':;

SECTION_NUMBER 1
 '@BASEBOARD_FAB2_LIB.BASEBOARD_FAB2(SCH_1):PAGE151_I271@W_HDL.120R2F-GP(CHIPS)':
 C_PATH='@baseboard_fab2_lib.baseboard_fab2(sch_1):page151_i271@w_hdl.\120r2f-gp~
\(chips)',
 P_PATH='@baseboard_fab2_lib.baseboard_fab2(sch_1):page151_i271@w_hdl.\120r2f-gp~
\(chips)',
 PATH='I271',
 DRAWING='@BASEBOARD_FAB2_LIB.BASEBOARD_FAB2(SCH_1):PAGE151',
 PACK_SIZE='0402',
 RATED='1/16W',
 ATTRIBUTE='120OHM',
 TOLERANCE='1%',
 SEC_TYPE='RCL_GP',
 PHYS_PAGE='151',
 XY='(-3025,675)',
 ROT='1',
 VER='1',
 VALUE='120R2F-GP',
 PACK_TYPE='RCL_GP',
 PART_NUMBER='64.12005.6DL',
 LOCATION='R25W21',
 SEC='1',
 CDS_LIB='w_hdl',
 CDS_PART_NAME='120R2F-GP_RCL_GP-120R2F-GP,64.A',
 PRIM_FILE='C:/<user>/w_hdl/120r2f#2dgp/chips/chips.prt';

PART_NAME
 R25W22 '120R2F-GP_RCL_GP-120R2F-GP,64.A':;

SECTION_NUMBER 1
 '@BASEBOARD_FAB2_LIB.BASEBOARD_FAB2(SCH_1):PAGE151_I270@W_HDL.120R2F-GP(CHIPS)':
 C_PATH='@baseboard_fab2_lib.baseboard_fab2(sch_1):page151_i270@w_hdl.\120r2f-gp~
\(chips)',
 P_PATH='@baseboard_fab2_lib.baseboard_fab2(sch_1):page151_i270@w_hdl.\120r2f-gp~
\(chips)',
 PATH='I270',
 DRAWING='@BASEBOARD_FAB2_LIB.BASEBOARD_FAB2(SCH_1):PAGE151',
 PACK_SIZE='0402',
 RATED='1/16W',
 ATTRIBUTE='120OHM',
 TOLERANCE='1%',
 SEC_TYPE='RCL_GP',
 PHYS_PAGE='151',
 XY='(-3025,625)',
 ROT='1',
 VER='1',
 VALUE='120R2F-GP',
 PACK_TYPE='RCL_GP',
 PART_NUMBER='64.12005.6DL',
 LOCATION='R25W22',
 SEC='1',
 CDS_LIB='w_hdl',
 CDS_PART_NAME='120R2F-GP_RCL_GP-120R2F-GP,64.A',
 PRIM_FILE='C:/<user>/w_hdl/120r2f#2dgp/chips/chips.prt';

PART_NAME
 R25W23 '120R2F-GP_RCL_GP-120R2F-GP,64.A':;

SECTION_NUMBER 1
 '@BASEBOARD_FAB2_LIB.BASEBOARD_FAB2(SCH_1):PAGE151_I269@W_HDL.120R2F-GP(CHIPS)':
 C_PATH='@baseboard_fab2_lib.baseboard_fab2(sch_1):page151_i269@w_hdl.\120r2f-gp~
\(chips)',
 P_PATH='@baseboard_fab2_lib.baseboard_fab2(sch_1):page151_i269@w_hdl.\120r2f-gp~
\(chips)',
 PATH='I269',
 DRAWING='@BASEBOARD_FAB2_LIB.BASEBOARD_FAB2(SCH_1):PAGE151',
 PACK_SIZE='0402',
 RATED='1/16W',
 ATTRIBUTE='120OHM',
 TOLERANCE='1%',
 SEC_TYPE='RCL_GP',
 PHYS_PAGE='151',
 XY='(-3025,575)',
 ROT='1',
 VER='1',
 VALUE='120R2F-GP',
 PACK_TYPE='RCL_GP',
 PART_NUMBER='64.12005.6DL',
 LOCATION='R25W23',
 SEC='1',
 CDS_LIB='w_hdl',
 CDS_PART_NAME='120R2F-GP_RCL_GP-120R2F-GP,64.A',
 PRIM_FILE='C:/<user>/w_hdl/120r2f#2dgp/chips/chips.prt';

PART_NAME
 R25W24 '120R2F-GP_RCL_GP-120R2F-GP,64.A':;

SECTION_NUMBER 1
 '@BASEBOARD_FAB2_LIB.BASEBOARD_FAB2(SCH_1):PAGE151_I268@W_HDL.120R2F-GP(CHIPS)':
 C_PATH='@baseboard_fab2_lib.baseboard_fab2(sch_1):page151_i268@w_hdl.\120r2f-gp~
\(chips)',
 P_PATH='@baseboard_fab2_lib.baseboard_fab2(sch_1):page151_i268@w_hdl.\120r2f-gp~
\(chips)',
 PATH='I268',
 DRAWING='@BASEBOARD_FAB2_LIB.BASEBOARD_FAB2(SCH_1):PAGE151',
 PACK_SIZE='0402',
 RATED='1/16W',
 ATTRIBUTE='120OHM',
 TOLERANCE='1%',
 SEC_TYPE='RCL_GP',
 PHYS_PAGE='151',
 XY='(-3025,525)',
 ROT='1',
 VER='1',
 VALUE='120R2F-GP',
 PACK_TYPE='RCL_GP',
 PART_NUMBER='64.12005.6DL',
 LOCATION='R25W24',
 SEC='1',
 CDS_LIB='w_hdl',
 CDS_PART_NAME='120R2F-GP_RCL_GP-120R2F-GP,64.A',
 PRIM_FILE='C:/<user>/w_hdl/120r2f#2dgp/chips/chips.prt';

PART_NAME
 R25W25 '120R2F-GP_RCL_GP-120R2F-GP,64.A':;

SECTION_NUMBER 1
 '@BASEBOARD_FAB2_LIB.BASEBOARD_FAB2(SCH_1):PAGE151_I275@W_HDL.120R2F-GP(CHIPS)':
 C_PATH='@baseboard_fab2_lib.baseboard_fab2(sch_1):page151_i275@w_hdl.\120r2f-gp~
\(chips)',
 P_PATH='@baseboard_fab2_lib.baseboard_fab2(sch_1):page151_i275@w_hdl.\120r2f-gp~
\(chips)',
 PATH='I275',
 DRAWING='@BASEBOARD_FAB2_LIB.BASEBOARD_FAB2(SCH_1):PAGE151',
 PACK_SIZE='0402',
 RATED='1/16W',
 ATTRIBUTE='120OHM',
 TOLERANCE='1%',
 SEC_TYPE='RCL_GP',
 PHYS_PAGE='151',
 XY='(-3025,475)',
 ROT='1',
 VER='1',
 VALUE='120R2F-GP',
 PACK_TYPE='RCL_GP',
 PART_NUMBER='64.12005.6DL',
 LOCATION='R25W25',
 SEC='1',
 CDS_LIB='w_hdl',
 CDS_PART_NAME='120R2F-GP_RCL_GP-120R2F-GP,64.A',
 PRIM_FILE='C:/<user>/w_hdl/120r2f#2dgp/chips/chips.prt';

PART_NAME
 R25W26 '120R2F-GP_RCL_GP-120R2F-GP,64.A':;

SECTION_NUMBER 1
 '@BASEBOARD_FAB2_LIB.BASEBOARD_FAB2(SCH_1):PAGE151_I274@W_HDL.120R2F-GP(CHIPS)':
 C_PATH='@baseboard_fab2_lib.baseboard_fab2(sch_1):page151_i274@w_hdl.\120r2f-gp~
\(chips)',
 P_PATH='@baseboard_fab2_lib.baseboard_fab2(sch_1):page151_i274@w_hdl.\120r2f-gp~
\(chips)',
 PATH='I274',
 DRAWING='@BASEBOARD_FAB2_LIB.BASEBOARD_FAB2(SCH_1):PAGE151',
 PACK_SIZE='0402',
 RATED='1/16W',
 ATTRIBUTE='120OHM',
 TOLERANCE='1%',
 SEC_TYPE='RCL_GP',
 PHYS_PAGE='151',
 XY='(-3025,425)',
 ROT='1',
 VER='1',
 VALUE='120R2F-GP',
 PACK_TYPE='RCL_GP',
 PART_NUMBER='64.12005.6DL',
 LOCATION='R25W26',
 SEC='1',
 CDS_LIB='w_hdl',
 CDS_PART_NAME='120R2F-GP_RCL_GP-120R2F-GP,64.A',
 PRIM_FILE='C:/<user>/w_hdl/120r2f#2dgp/chips/chips.prt';

PART_NAME
 R25W27 '120R2F-GP_RCL_GP-120R2F-GP,64.A':;

SECTION_NUMBER 1
 '@BASEBOARD_FAB2_LIB.BASEBOARD_FAB2(SCH_1):PAGE151_I223@W_HDL.120R2F-GP(CHIPS)':
 C_PATH='@baseboard_fab2_lib.baseboard_fab2(sch_1):page151_i223@w_hdl.\120r2f-gp~
\(chips)',
 P_PATH='@baseboard_fab2_lib.baseboard_fab2(sch_1):page151_i223@w_hdl.\120r2f-gp~
\(chips)',
 PATH='I223',
 DRAWING='@BASEBOARD_FAB2_LIB.BASEBOARD_FAB2(SCH_1):PAGE151',
 PACK_SIZE='0402',
 RATED='1/16W',
 ATTRIBUTE='120OHM',
 TOLERANCE='1%',
 SEC_TYPE='RCL_GP',
 PHYS_PAGE='151',
 XY='(-950,1675)',
 ROT='1',
 VER='1',
 VALUE='120R2F-GP',
 PACK_TYPE='RCL_GP',
 PART_NUMBER='64.12005.6DL',
 LOCATION='R25W27',
 SEC='1',
 CDS_LIB='w_hdl',
 CDS_PART_NAME='120R2F-GP_RCL_GP-120R2F-GP,64.A',
 PRIM_FILE='C:/<user>/w_hdl/120r2f#2dgp/chips/chips.prt';

PART_NAME
 R25W28 '120R2F-GP_RCL_GP-120R2F-GP,64.A':;

SECTION_NUMBER 1
 '@BASEBOARD_FAB2_LIB.BASEBOARD_FAB2(SCH_1):PAGE151_I224@W_HDL.120R2F-GP(CHIPS)':
 C_PATH='@baseboard_fab2_lib.baseboard_fab2(sch_1):page151_i224@w_hdl.\120r2f-gp~
\(chips)',
 P_PATH='@baseboard_fab2_lib.baseboard_fab2(sch_1):page151_i224@w_hdl.\120r2f-gp~
\(chips)',
 PATH='I224',
 DRAWING='@BASEBOARD_FAB2_LIB.BASEBOARD_FAB2(SCH_1):PAGE151',
 PACK_SIZE='0402',
 RATED='1/16W',
 ATTRIBUTE='120OHM',
 TOLERANCE='1%',
 SEC_TYPE='RCL_GP',
 PHYS_PAGE='151',
 XY='(-950,1625)',
 ROT='1',
 VER='1',
 VALUE='120R2F-GP',
 PACK_TYPE='RCL_GP',
 PART_NUMBER='64.12005.6DL',
 LOCATION='R25W28',
 SEC='1',
 CDS_LIB='w_hdl',
 CDS_PART_NAME='120R2F-GP_RCL_GP-120R2F-GP,64.A',
 PRIM_FILE='C:/<user>/w_hdl/120r2f#2dgp/chips/chips.prt';

PART_NAME
 R25W29 '120R2F-GP_RCL_GP-120R2F-GP,64.A':;

SECTION_NUMBER 1
 '@BASEBOARD_FAB2_LIB.BASEBOARD_FAB2(SCH_1):PAGE151_I225@W_HDL.120R2F-GP(CHIPS)':
 C_PATH='@baseboard_fab2_lib.baseboard_fab2(sch_1):page151_i225@w_hdl.\120r2f-gp~
\(chips)',
 P_PATH='@baseboard_fab2_lib.baseboard_fab2(sch_1):page151_i225@w_hdl.\120r2f-gp~
\(chips)',
 PATH='I225',
 DRAWING='@BASEBOARD_FAB2_LIB.BASEBOARD_FAB2(SCH_1):PAGE151',
 PACK_SIZE='0402',
 RATED='1/16W',
 ATTRIBUTE='120OHM',
 POP='NOPOP',
 TOLERANCE='1%',
 SEC_TYPE='RCL_GP',
 PHYS_PAGE='151',
 XY='(-950,1575)',
 ROT='1',
 VER='1',
 VALUE='120R2F-GP',
 PACK_TYPE='RCL_GP',
 PART_NUMBER='64.12005.6DL',
 LOCATION='R25W29',
 SEC='1',
 CDS_LIB='w_hdl',
 CDS_PART_NAME='120R2F-GP_RCL_GP-120R2F-GP,64.A',
 PRIM_FILE='C:/<user>/w_hdl/120r2f#2dgp/chips/chips.prt';

PART_NAME
 R25W30 'RES_0402-2.7K,1%,1/16W,CHIP,G2A':;

SECTION_NUMBER 1
 '@BASEBOARD_FAB2_LIB.BASEBOARD_FAB2(SCH_1):PAGE151_I222@MSTR_DISCRETE.RES(CHIPS)':
 C_PATH='@baseboard_fab2_lib.baseboard_fab2(sch_1):page151_i222@mstr_discrete.re~
s(chips)',
 P_PATH='@baseboard_fab2_lib.baseboard_fab2(sch_1):page151_i222@mstr_discrete.re~
s(chips)',
 PATH='I222',
 DRAWING='@BASEBOARD_FAB2_LIB.BASEBOARD_FAB2(SCH_1):PAGE151',
 WATTAGE='1/16W',
 TOLERANCE='1%',
 SEC_TYPE='0402',
 MATERIAL='CHIP',
 PHYS_PAGE='151',
 XY='(-975,1525)',
 ROT='1',
 VER='2',
 VALUE='2.7K',
 PACK_TYPE='0402',
 PART_NUMBER='G21796-344',
 LOCATION='R25W30',
 SEC='1',
 CDS_LIB='mstr_discrete',
 CDS_PART_NAME='RES_0402-2.7K,1%,1/16W,CHIP,G2A',
 PRIM_FILE='./archive_libs/mstr_discrete/res/chips/chips.prt';

PART_NAME
 R25W31 '120R2F-GP_RCL_GP-120R2F-GP,64.A':;

SECTION_NUMBER 1
 '@BASEBOARD_FAB2_LIB.BASEBOARD_FAB2(SCH_1):PAGE151_I226@W_HDL.120R2F-GP(CHIPS)':
 C_PATH='@baseboard_fab2_lib.baseboard_fab2(sch_1):page151_i226@w_hdl.\120r2f-gp~
\(chips)',
 P_PATH='@baseboard_fab2_lib.baseboard_fab2(sch_1):page151_i226@w_hdl.\120r2f-gp~
\(chips)',
 PATH='I226',
 DRAWING='@BASEBOARD_FAB2_LIB.BASEBOARD_FAB2(SCH_1):PAGE151',
 PACK_SIZE='0402',
 RATED='1/16W',
 ATTRIBUTE='120OHM',
 TOLERANCE='1%',
 SEC_TYPE='RCL_GP',
 PHYS_PAGE='151',
 XY='(-950,1475)',
 ROT='1',
 VER='1',
 VALUE='120R2F-GP',
 PACK_TYPE='RCL_GP',
 PART_NUMBER='64.12005.6DL',
 LOCATION='R25W31',
 SEC='1',
 CDS_LIB='w_hdl',
 CDS_PART_NAME='120R2F-GP_RCL_GP-120R2F-GP,64.A',
 PRIM_FILE='C:/<user>/w_hdl/120r2f#2dgp/chips/chips.prt';

PART_NAME
 R25W32 '120R2F-GP_RCL_GP-120R2F-GP,64.A':;

SECTION_NUMBER 1
 '@BASEBOARD_FAB2_LIB.BASEBOARD_FAB2(SCH_1):PAGE151_I227@W_HDL.120R2F-GP(CHIPS)':
 C_PATH='@baseboard_fab2_lib.baseboard_fab2(sch_1):page151_i227@w_hdl.\120r2f-gp~
\(chips)',
 P_PATH='@baseboard_fab2_lib.baseboard_fab2(sch_1):page151_i227@w_hdl.\120r2f-gp~
\(chips)',
 PATH='I227',
 DRAWING='@BASEBOARD_FAB2_LIB.BASEBOARD_FAB2(SCH_1):PAGE151',
 PACK_SIZE='0402',
 RATED='1/16W',
 ATTRIBUTE='120OHM',
 TOLERANCE='1%',
 SEC_TYPE='RCL_GP',
 PHYS_PAGE='151',
 XY='(-950,1425)',
 ROT='1',
 VER='1',
 VALUE='120R2F-GP',
 PACK_TYPE='RCL_GP',
 PART_NUMBER='64.12005.6DL',
 LOCATION='R25W32',
 SEC='1',
 CDS_LIB='w_hdl',
 CDS_PART_NAME='120R2F-GP_RCL_GP-120R2F-GP,64.A',
 PRIM_FILE='C:/<user>/w_hdl/120r2f#2dgp/chips/chips.prt';

PART_NAME
 R25W33 '120R2F-GP_RCL_GP-120R2F-GP,64.A':;

SECTION_NUMBER 1
 '@BASEBOARD_FAB2_LIB.BASEBOARD_FAB2(SCH_1):PAGE151_I228@W_HDL.120R2F-GP(CHIPS)':
 C_PATH='@baseboard_fab2_lib.baseboard_fab2(sch_1):page151_i228@w_hdl.\120r2f-gp~
\(chips)',
 P_PATH='@baseboard_fab2_lib.baseboard_fab2(sch_1):page151_i228@w_hdl.\120r2f-gp~
\(chips)',
 PATH='I228',
 DRAWING='@BASEBOARD_FAB2_LIB.BASEBOARD_FAB2(SCH_1):PAGE151',
 PACK_SIZE='0402',
 RATED='1/16W',
 ATTRIBUTE='120OHM',
 TOLERANCE='1%',
 SEC_TYPE='RCL_GP',
 PHYS_PAGE='151',
 XY='(-950,1375)',
 ROT='1',
 VER='1',
 VALUE='120R2F-GP',
 PACK_TYPE='RCL_GP',
 PART_NUMBER='64.12005.6DL',
 LOCATION='R25W33',
 SEC='1',
 CDS_LIB='w_hdl',
 CDS_PART_NAME='120R2F-GP_RCL_GP-120R2F-GP,64.A',
 PRIM_FILE='C:/<user>/w_hdl/120r2f#2dgp/chips/chips.prt';

PART_NAME
 R25W34 '120R2F-GP_RCL_GP-120R2F-GP,64.A':;

SECTION_NUMBER 1
 '@BASEBOARD_FAB2_LIB.BASEBOARD_FAB2(SCH_1):PAGE151_I229@W_HDL.120R2F-GP(CHIPS)':
 C_PATH='@baseboard_fab2_lib.baseboard_fab2(sch_1):page151_i229@w_hdl.\120r2f-gp~
\(chips)',
 P_PATH='@baseboard_fab2_lib.baseboard_fab2(sch_1):page151_i229@w_hdl.\120r2f-gp~
\(chips)',
 PATH='I229',
 DRAWING='@BASEBOARD_FAB2_LIB.BASEBOARD_FAB2(SCH_1):PAGE151',
 PACK_SIZE='0402',
 RATED='1/16W',
 ATTRIBUTE='120OHM',
 TOLERANCE='1%',
 SEC_TYPE='RCL_GP',
 PHYS_PAGE='151',
 XY='(-950,1325)',
 ROT='1',
 VER='1',
 VALUE='120R2F-GP',
 PACK_TYPE='RCL_GP',
 PART_NUMBER='64.12005.6DL',
 LOCATION='R25W34',
 SEC='1',
 CDS_LIB='w_hdl',
 CDS_PART_NAME='120R2F-GP_RCL_GP-120R2F-GP,64.A',
 PRIM_FILE='C:/<user>/w_hdl/120r2f#2dgp/chips/chips.prt';

PART_NAME
 R25W35 '120R2F-GP_RCL_GP-120R2F-GP,64.A':;

SECTION_NUMBER 1
 '@BASEBOARD_FAB2_LIB.BASEBOARD_FAB2(SCH_1):PAGE151_I230@W_HDL.120R2F-GP(CHIPS)':
 C_PATH='@baseboard_fab2_lib.baseboard_fab2(sch_1):page151_i230@w_hdl.\120r2f-gp~
\(chips)',
 P_PATH='@baseboard_fab2_lib.baseboard_fab2(sch_1):page151_i230@w_hdl.\120r2f-gp~
\(chips)',
 PATH='I230',
 DRAWING='@BASEBOARD_FAB2_LIB.BASEBOARD_FAB2(SCH_1):PAGE151',
 PACK_SIZE='0402',
 RATED='1/16W',
 ATTRIBUTE='120OHM',
 TOLERANCE='1%',
 SEC_TYPE='RCL_GP',
 PHYS_PAGE='151',
 XY='(-950,1275)',
 ROT='1',
 VER='1',
 VALUE='120R2F-GP',
 PACK_TYPE='RCL_GP',
 PART_NUMBER='64.12005.6DL',
 LOCATION='R25W35',
 SEC='1',
 CDS_LIB='w_hdl',
 CDS_PART_NAME='120R2F-GP_RCL_GP-120R2F-GP,64.A',
 PRIM_FILE='C:/<user>/w_hdl/120r2f#2dgp/chips/chips.prt';

PART_NAME
 R25W36 '120R2F-GP_RCL_GP-120R2F-GP,64.A':;

SECTION_NUMBER 1
 '@BASEBOARD_FAB2_LIB.BASEBOARD_FAB2(SCH_1):PAGE151_I231@W_HDL.120R2F-GP(CHIPS)':
 C_PATH='@baseboard_fab2_lib.baseboard_fab2(sch_1):page151_i231@w_hdl.\120r2f-gp~
\(chips)',
 P_PATH='@baseboard_fab2_lib.baseboard_fab2(sch_1):page151_i231@w_hdl.\120r2f-gp~
\(chips)',
 PATH='I231',
 DRAWING='@BASEBOARD_FAB2_LIB.BASEBOARD_FAB2(SCH_1):PAGE151',
 PACK_SIZE='0402',
 RATED='1/16W',
 ATTRIBUTE='120OHM',
 TOLERANCE='1%',
 SEC_TYPE='RCL_GP',
 PHYS_PAGE='151',
 XY='(-950,1225)',
 ROT='1',
 VER='1',
 VALUE='120R2F-GP',
 PACK_TYPE='RCL_GP',
 PART_NUMBER='64.12005.6DL',
 LOCATION='R25W36',
 SEC='1',
 CDS_LIB='w_hdl',
 CDS_PART_NAME='120R2F-GP_RCL_GP-120R2F-GP,64.A',
 PRIM_FILE='C:/<user>/w_hdl/120r2f#2dgp/chips/chips.prt';

PART_NAME
 R25W37 '120R2F-GP_RCL_GP-120R2F-GP,64.A':;

SECTION_NUMBER 1
 '@BASEBOARD_FAB2_LIB.BASEBOARD_FAB2(SCH_1):PAGE151_I232@W_HDL.120R2F-GP(CHIPS)':
 C_PATH='@baseboard_fab2_lib.baseboard_fab2(sch_1):page151_i232@w_hdl.\120r2f-gp~
\(chips)',
 P_PATH='@baseboard_fab2_lib.baseboard_fab2(sch_1):page151_i232@w_hdl.\120r2f-gp~
\(chips)',
 PATH='I232',
 DRAWING='@BASEBOARD_FAB2_LIB.BASEBOARD_FAB2(SCH_1):PAGE151',
 PACK_SIZE='0402',
 RATED='1/16W',
 ATTRIBUTE='120OHM',
 TOLERANCE='1%',
 SEC_TYPE='RCL_GP',
 PHYS_PAGE='151',
 XY='(-950,1175)',
 ROT='1',
 VER='1',
 VALUE='120R2F-GP',
 PACK_TYPE='RCL_GP',
 PART_NUMBER='64.12005.6DL',
 LOCATION='R25W37',
 SEC='1',
 CDS_LIB='w_hdl',
 CDS_PART_NAME='120R2F-GP_RCL_GP-120R2F-GP,64.A',
 PRIM_FILE='C:/<user>/w_hdl/120r2f#2dgp/chips/chips.prt';

PART_NAME
 R25W38 '120R2F-GP_RCL_GP-120R2F-GP,64.A':;

SECTION_NUMBER 1
 '@BASEBOARD_FAB2_LIB.BASEBOARD_FAB2(SCH_1):PAGE151_I233@W_HDL.120R2F-GP(CHIPS)':
 C_PATH='@baseboard_fab2_lib.baseboard_fab2(sch_1):page151_i233@w_hdl.\120r2f-gp~
\(chips)',
 P_PATH='@baseboard_fab2_lib.baseboard_fab2(sch_1):page151_i233@w_hdl.\120r2f-gp~
\(chips)',
 PATH='I233',
 DRAWING='@BASEBOARD_FAB2_LIB.BASEBOARD_FAB2(SCH_1):PAGE151',
 PACK_SIZE='0402',
 RATED='1/16W',
 ATTRIBUTE='120OHM',
 TOLERANCE='1%',
 SEC_TYPE='RCL_GP',
 PHYS_PAGE='151',
 XY='(-950,1125)',
 ROT='1',
 VER='1',
 VALUE='120R2F-GP',
 PACK_TYPE='RCL_GP',
 PART_NUMBER='64.12005.6DL',
 LOCATION='R25W38',
 SEC='1',
 CDS_LIB='w_hdl',
 CDS_PART_NAME='120R2F-GP_RCL_GP-120R2F-GP,64.A',
 PRIM_FILE='C:/<user>/w_hdl/120r2f#2dgp/chips/chips.prt';

PART_NAME
 R25W39 '120R2F-GP_RCL_GP-120R2F-GP,64.A':;

SECTION_NUMBER 1
 '@BASEBOARD_FAB2_LIB.BASEBOARD_FAB2(SCH_1):PAGE151_I234@W_HDL.120R2F-GP(CHIPS)':
 C_PATH='@baseboard_fab2_lib.baseboard_fab2(sch_1):page151_i234@w_hdl.\120r2f-gp~
\(chips)',
 P_PATH='@baseboard_fab2_lib.baseboard_fab2(sch_1):page151_i234@w_hdl.\120r2f-gp~
\(chips)',
 PATH='I234',
 DRAWING='@BASEBOARD_FAB2_LIB.BASEBOARD_FAB2(SCH_1):PAGE151',
 PACK_SIZE='0402',
 RATED='1/16W',
 ATTRIBUTE='120OHM',
 TOLERANCE='1%',
 SEC_TYPE='RCL_GP',
 PHYS_PAGE='151',
 XY='(-950,1075)',
 ROT='1',
 VER='1',
 VALUE='120R2F-GP',
 PACK_TYPE='RCL_GP',
 PART_NUMBER='64.12005.6DL',
 LOCATION='R25W39',
 SEC='1',
 CDS_LIB='w_hdl',
 CDS_PART_NAME='120R2F-GP_RCL_GP-120R2F-GP,64.A',
 PRIM_FILE='C:/<user>/w_hdl/120r2f#2dgp/chips/chips.prt';

PART_NAME
 R25W40 '120R2F-GP_RCL_GP-120R2F-GP,64.A':;

SECTION_NUMBER 1
 '@BASEBOARD_FAB2_LIB.BASEBOARD_FAB2(SCH_1):PAGE151_I247@W_HDL.120R2F-GP(CHIPS)':
 C_PATH='@baseboard_fab2_lib.baseboard_fab2(sch_1):page151_i247@w_hdl.\120r2f-gp~
\(chips)',
 P_PATH='@baseboard_fab2_lib.baseboard_fab2(sch_1):page151_i247@w_hdl.\120r2f-gp~
\(chips)',
 PATH='I247',
 DRAWING='@BASEBOARD_FAB2_LIB.BASEBOARD_FAB2(SCH_1):PAGE151',
 PACK_SIZE='0402',
 RATED='1/16W',
 ATTRIBUTE='120OHM',
 TOLERANCE='1%',
 SEC_TYPE='RCL_GP',
 PHYS_PAGE='151',
 XY='(-950,1025)',
 ROT='1',
 VER='1',
 VALUE='120R2F-GP',
 PACK_TYPE='RCL_GP',
 PART_NUMBER='64.12005.6DL',
 LOCATION='R25W40',
 SEC='1',
 CDS_LIB='w_hdl',
 CDS_PART_NAME='120R2F-GP_RCL_GP-120R2F-GP,64.A',
 PRIM_FILE='C:/<user>/w_hdl/120r2f#2dgp/chips/chips.prt';

PART_NAME
 R25W41 '120R2F-GP_RCL_GP-120R2F-GP,64.A':;

SECTION_NUMBER 1
 '@BASEBOARD_FAB2_LIB.BASEBOARD_FAB2(SCH_1):PAGE151_I235@W_HDL.120R2F-GP(CHIPS)':
 C_PATH='@baseboard_fab2_lib.baseboard_fab2(sch_1):page151_i235@w_hdl.\120r2f-gp~
\(chips)',
 P_PATH='@baseboard_fab2_lib.baseboard_fab2(sch_1):page151_i235@w_hdl.\120r2f-gp~
\(chips)',
 PATH='I235',
 DRAWING='@BASEBOARD_FAB2_LIB.BASEBOARD_FAB2(SCH_1):PAGE151',
 PACK_SIZE='0402',
 RATED='1/16W',
 ATTRIBUTE='120OHM',
 TOLERANCE='1%',
 SEC_TYPE='RCL_GP',
 PHYS_PAGE='151',
 XY='(-950,975)',
 ROT='1',
 VER='1',
 VALUE='120R2F-GP',
 PACK_TYPE='RCL_GP',
 PART_NUMBER='64.12005.6DL',
 LOCATION='R25W41',
 SEC='1',
 CDS_LIB='w_hdl',
 CDS_PART_NAME='120R2F-GP_RCL_GP-120R2F-GP,64.A',
 PRIM_FILE='C:/<user>/w_hdl/120r2f#2dgp/chips/chips.prt';

PART_NAME
 R25W42 '120R2F-GP_RCL_GP-120R2F-GP,64.A':;

SECTION_NUMBER 1
 '@BASEBOARD_FAB2_LIB.BASEBOARD_FAB2(SCH_1):PAGE151_I236@W_HDL.120R2F-GP(CHIPS)':
 C_PATH='@baseboard_fab2_lib.baseboard_fab2(sch_1):page151_i236@w_hdl.\120r2f-gp~
\(chips)',
 P_PATH='@baseboard_fab2_lib.baseboard_fab2(sch_1):page151_i236@w_hdl.\120r2f-gp~
\(chips)',
 PATH='I236',
 DRAWING='@BASEBOARD_FAB2_LIB.BASEBOARD_FAB2(SCH_1):PAGE151',
 PACK_SIZE='0402',
 RATED='1/16W',
 ATTRIBUTE='120OHM',
 TOLERANCE='1%',
 SEC_TYPE='RCL_GP',
 PHYS_PAGE='151',
 XY='(-950,925)',
 ROT='1',
 VER='1',
 VALUE='120R2F-GP',
 PACK_TYPE='RCL_GP',
 PART_NUMBER='64.12005.6DL',
 LOCATION='R25W42',
 SEC='1',
 CDS_LIB='w_hdl',
 CDS_PART_NAME='120R2F-GP_RCL_GP-120R2F-GP,64.A',
 PRIM_FILE='C:/<user>/w_hdl/120r2f#2dgp/chips/chips.prt';

PART_NAME
 R25W43 '120R2F-GP_RCL_GP-120R2F-GP,64.A':;

SECTION_NUMBER 1
 '@BASEBOARD_FAB2_LIB.BASEBOARD_FAB2(SCH_1):PAGE151_I238@W_HDL.120R2F-GP(CHIPS)':
 C_PATH='@baseboard_fab2_lib.baseboard_fab2(sch_1):page151_i238@w_hdl.\120r2f-gp~
\(chips)',
 P_PATH='@baseboard_fab2_lib.baseboard_fab2(sch_1):page151_i238@w_hdl.\120r2f-gp~
\(chips)',
 PATH='I238',
 DRAWING='@BASEBOARD_FAB2_LIB.BASEBOARD_FAB2(SCH_1):PAGE151',
 PACK_SIZE='0402',
 RATED='1/16W',
 ATTRIBUTE='120OHM',
 TOLERANCE='1%',
 SEC_TYPE='RCL_GP',
 PHYS_PAGE='151',
 XY='(-950,875)',
 ROT='1',
 VER='1',
 VALUE='120R2F-GP',
 PACK_TYPE='RCL_GP',
 PART_NUMBER='64.12005.6DL',
 LOCATION='R25W43',
 SEC='1',
 CDS_LIB='w_hdl',
 CDS_PART_NAME='120R2F-GP_RCL_GP-120R2F-GP,64.A',
 PRIM_FILE='C:/<user>/w_hdl/120r2f#2dgp/chips/chips.prt';

PART_NAME
 R25W44 '120R2F-GP_RCL_GP-120R2F-GP,64.A':;

SECTION_NUMBER 1
 '@BASEBOARD_FAB2_LIB.BASEBOARD_FAB2(SCH_1):PAGE151_I237@W_HDL.120R2F-GP(CHIPS)':
 C_PATH='@baseboard_fab2_lib.baseboard_fab2(sch_1):page151_i237@w_hdl.\120r2f-gp~
\(chips)',
 P_PATH='@baseboard_fab2_lib.baseboard_fab2(sch_1):page151_i237@w_hdl.\120r2f-gp~
\(chips)',
 PATH='I237',
 DRAWING='@BASEBOARD_FAB2_LIB.BASEBOARD_FAB2(SCH_1):PAGE151',
 PACK_SIZE='0402',
 RATED='1/16W',
 ATTRIBUTE='120OHM',
 TOLERANCE='1%',
 SEC_TYPE='RCL_GP',
 PHYS_PAGE='151',
 XY='(-950,825)',
 ROT='1',
 VER='1',
 VALUE='120R2F-GP',
 PACK_TYPE='RCL_GP',
 PART_NUMBER='64.12005.6DL',
 LOCATION='R25W44',
 SEC='1',
 CDS_LIB='w_hdl',
 CDS_PART_NAME='120R2F-GP_RCL_GP-120R2F-GP,64.A',
 PRIM_FILE='C:/<user>/w_hdl/120r2f#2dgp/chips/chips.prt';

PART_NAME
 R25W45 '120R2F-GP_RCL_GP-120R2F-GP,64.A':;

SECTION_NUMBER 1
 '@BASEBOARD_FAB2_LIB.BASEBOARD_FAB2(SCH_1):PAGE151_I242@W_HDL.120R2F-GP(CHIPS)':
 C_PATH='@baseboard_fab2_lib.baseboard_fab2(sch_1):page151_i242@w_hdl.\120r2f-gp~
\(chips)',
 P_PATH='@baseboard_fab2_lib.baseboard_fab2(sch_1):page151_i242@w_hdl.\120r2f-gp~
\(chips)',
 PATH='I242',
 DRAWING='@BASEBOARD_FAB2_LIB.BASEBOARD_FAB2(SCH_1):PAGE151',
 PACK_SIZE='0402',
 RATED='1/16W',
 ATTRIBUTE='120OHM',
 TOLERANCE='1%',
 SEC_TYPE='RCL_GP',
 PHYS_PAGE='151',
 XY='(-950,775)',
 ROT='1',
 VER='1',
 VALUE='120R2F-GP',
 PACK_TYPE='RCL_GP',
 PART_NUMBER='64.12005.6DL',
 LOCATION='R25W45',
 SEC='1',
 CDS_LIB='w_hdl',
 CDS_PART_NAME='120R2F-GP_RCL_GP-120R2F-GP,64.A',
 PRIM_FILE='C:/<user>/w_hdl/120r2f#2dgp/chips/chips.prt';

PART_NAME
 R25W46 '120R2F-GP_RCL_GP-120R2F-GP,64.A':;

SECTION_NUMBER 1
 '@BASEBOARD_FAB2_LIB.BASEBOARD_FAB2(SCH_1):PAGE151_I241@W_HDL.120R2F-GP(CHIPS)':
 C_PATH='@baseboard_fab2_lib.baseboard_fab2(sch_1):page151_i241@w_hdl.\120r2f-gp~
\(chips)',
 P_PATH='@baseboard_fab2_lib.baseboard_fab2(sch_1):page151_i241@w_hdl.\120r2f-gp~
\(chips)',
 PATH='I241',
 DRAWING='@BASEBOARD_FAB2_LIB.BASEBOARD_FAB2(SCH_1):PAGE151',
 PACK_SIZE='0402',
 RATED='1/16W',
 ATTRIBUTE='120OHM',
 TOLERANCE='1%',
 SEC_TYPE='RCL_GP',
 PHYS_PAGE='151',
 XY='(-950,725)',
 ROT='1',
 VER='1',
 VALUE='120R2F-GP',
 PACK_TYPE='RCL_GP',
 PART_NUMBER='64.12005.6DL',
 LOCATION='R25W46',
 SEC='1',
 CDS_LIB='w_hdl',
 CDS_PART_NAME='120R2F-GP_RCL_GP-120R2F-GP,64.A',
 PRIM_FILE='C:/<user>/w_hdl/120r2f#2dgp/chips/chips.prt';

PART_NAME
 R25W47 '120R2F-GP_RCL_GP-120R2F-GP,64.A':;

SECTION_NUMBER 1
 '@BASEBOARD_FAB2_LIB.BASEBOARD_FAB2(SCH_1):PAGE151_I239@W_HDL.120R2F-GP(CHIPS)':
 C_PATH='@baseboard_fab2_lib.baseboard_fab2(sch_1):page151_i239@w_hdl.\120r2f-gp~
\(chips)',
 P_PATH='@baseboard_fab2_lib.baseboard_fab2(sch_1):page151_i239@w_hdl.\120r2f-gp~
\(chips)',
 PATH='I239',
 DRAWING='@BASEBOARD_FAB2_LIB.BASEBOARD_FAB2(SCH_1):PAGE151',
 PACK_SIZE='0402',
 RATED='1/16W',
 ATTRIBUTE='120OHM',
 TOLERANCE='1%',
 SEC_TYPE='RCL_GP',
 PHYS_PAGE='151',
 XY='(-950,675)',
 ROT='1',
 VER='1',
 VALUE='120R2F-GP',
 PACK_TYPE='RCL_GP',
 PART_NUMBER='64.12005.6DL',
 LOCATION='R25W47',
 SEC='1',
 CDS_LIB='w_hdl',
 CDS_PART_NAME='120R2F-GP_RCL_GP-120R2F-GP,64.A',
 PRIM_FILE='C:/<user>/w_hdl/120r2f#2dgp/chips/chips.prt';

PART_NAME
 R25W48 '120R2F-GP_RCL_GP-120R2F-GP,64.A':;

SECTION_NUMBER 1
 '@BASEBOARD_FAB2_LIB.BASEBOARD_FAB2(SCH_1):PAGE151_I240@W_HDL.120R2F-GP(CHIPS)':
 C_PATH='@baseboard_fab2_lib.baseboard_fab2(sch_1):page151_i240@w_hdl.\120r2f-gp~
\(chips)',
 P_PATH='@baseboard_fab2_lib.baseboard_fab2(sch_1):page151_i240@w_hdl.\120r2f-gp~
\(chips)',
 PATH='I240',
 DRAWING='@BASEBOARD_FAB2_LIB.BASEBOARD_FAB2(SCH_1):PAGE151',
 PACK_SIZE='0402',
 RATED='1/16W',
 ATTRIBUTE='120OHM',
 TOLERANCE='1%',
 SEC_TYPE='RCL_GP',
 PHYS_PAGE='151',
 XY='(-950,625)',
 ROT='1',
 VER='1',
 VALUE='120R2F-GP',
 PACK_TYPE='RCL_GP',
 PART_NUMBER='64.12005.6DL',
 LOCATION='R25W48',
 SEC='1',
 CDS_LIB='w_hdl',
 CDS_PART_NAME='120R2F-GP_RCL_GP-120R2F-GP,64.A',
 PRIM_FILE='C:/<user>/w_hdl/120r2f#2dgp/chips/chips.prt';

PART_NAME
 R25W49 '120R2F-GP_RCL_GP-120R2F-GP,64.A':;

SECTION_NUMBER 1
 '@BASEBOARD_FAB2_LIB.BASEBOARD_FAB2(SCH_1):PAGE151_I243@W_HDL.120R2F-GP(CHIPS)':
 C_PATH='@baseboard_fab2_lib.baseboard_fab2(sch_1):page151_i243@w_hdl.\120r2f-gp~
\(chips)',
 P_PATH='@baseboard_fab2_lib.baseboard_fab2(sch_1):page151_i243@w_hdl.\120r2f-gp~
\(chips)',
 PATH='I243',
 DRAWING='@BASEBOARD_FAB2_LIB.BASEBOARD_FAB2(SCH_1):PAGE151',
 PACK_SIZE='0402',
 RATED='1/16W',
 ATTRIBUTE='120OHM',
 TOLERANCE='1%',
 SEC_TYPE='RCL_GP',
 PHYS_PAGE='151',
 XY='(-950,575)',
 ROT='1',
 VER='1',
 VALUE='120R2F-GP',
 PACK_TYPE='RCL_GP',
 PART_NUMBER='64.12005.6DL',
 LOCATION='R25W49',
 SEC='1',
 CDS_LIB='w_hdl',
 CDS_PART_NAME='120R2F-GP_RCL_GP-120R2F-GP,64.A',
 PRIM_FILE='C:/<user>/w_hdl/120r2f#2dgp/chips/chips.prt';

PART_NAME
 R25W50 '120R2F-GP_RCL_GP-120R2F-GP,64.A':;

SECTION_NUMBER 1
 '@BASEBOARD_FAB2_LIB.BASEBOARD_FAB2(SCH_1):PAGE151_I244@W_HDL.120R2F-GP(CHIPS)':
 C_PATH='@baseboard_fab2_lib.baseboard_fab2(sch_1):page151_i244@w_hdl.\120r2f-gp~
\(chips)',
 P_PATH='@baseboard_fab2_lib.baseboard_fab2(sch_1):page151_i244@w_hdl.\120r2f-gp~
\(chips)',
 PATH='I244',
 DRAWING='@BASEBOARD_FAB2_LIB.BASEBOARD_FAB2(SCH_1):PAGE151',
 PACK_SIZE='0402',
 RATED='1/16W',
 ATTRIBUTE='120OHM',
 TOLERANCE='1%',
 SEC_TYPE='RCL_GP',
 PHYS_PAGE='151',
 XY='(-950,525)',
 ROT='1',
 VER='1',
 VALUE='120R2F-GP',
 PACK_TYPE='RCL_GP',
 PART_NUMBER='64.12005.6DL',
 LOCATION='R25W50',
 SEC='1',
 CDS_LIB='w_hdl',
 CDS_PART_NAME='120R2F-GP_RCL_GP-120R2F-GP,64.A',
 PRIM_FILE='C:/<user>/w_hdl/120r2f#2dgp/chips/chips.prt';

PART_NAME
 R25W51 '120R2F-GP_RCL_GP-120R2F-GP,64.A':;

SECTION_NUMBER 1
 '@BASEBOARD_FAB2_LIB.BASEBOARD_FAB2(SCH_1):PAGE151_I245@W_HDL.120R2F-GP(CHIPS)':
 C_PATH='@baseboard_fab2_lib.baseboard_fab2(sch_1):page151_i245@w_hdl.\120r2f-gp~
\(chips)',
 P_PATH='@baseboard_fab2_lib.baseboard_fab2(sch_1):page151_i245@w_hdl.\120r2f-gp~
\(chips)',
 PATH='I245',
 DRAWING='@BASEBOARD_FAB2_LIB.BASEBOARD_FAB2(SCH_1):PAGE151',
 PACK_SIZE='0402',
 RATED='1/16W',
 ATTRIBUTE='120OHM',
 TOLERANCE='1%',
 SEC_TYPE='RCL_GP',
 PHYS_PAGE='151',
 XY='(-950,475)',
 ROT='1',
 VER='1',
 VALUE='120R2F-GP',
 PACK_TYPE='RCL_GP',
 PART_NUMBER='64.12005.6DL',
 LOCATION='R25W51',
 SEC='1',
 CDS_LIB='w_hdl',
 CDS_PART_NAME='120R2F-GP_RCL_GP-120R2F-GP,64.A',
 PRIM_FILE='C:/<user>/w_hdl/120r2f#2dgp/chips/chips.prt';

PART_NAME
 R25W52 '120R2F-GP_RCL_GP-120R2F-GP,64.A':;

SECTION_NUMBER 1
 '@BASEBOARD_FAB2_LIB.BASEBOARD_FAB2(SCH_1):PAGE151_I246@W_HDL.120R2F-GP(CHIPS)':
 C_PATH='@baseboard_fab2_lib.baseboard_fab2(sch_1):page151_i246@w_hdl.\120r2f-gp~
\(chips)',
 P_PATH='@baseboard_fab2_lib.baseboard_fab2(sch_1):page151_i246@w_hdl.\120r2f-gp~
\(chips)',
 PATH='I246',
 DRAWING='@BASEBOARD_FAB2_LIB.BASEBOARD_FAB2(SCH_1):PAGE151',
 PACK_SIZE='0402',
 RATED='1/16W',
 ATTRIBUTE='120OHM',
 TOLERANCE='1%',
 SEC_TYPE='RCL_GP',
 PHYS_PAGE='151',
 XY='(-950,425)',
 ROT='1',
 VER='1',
 VALUE='120R2F-GP',
 PACK_TYPE='RCL_GP',
 PART_NUMBER='64.12005.6DL',
 LOCATION='R25W52',
 SEC='1',
 CDS_LIB='w_hdl',
 CDS_PART_NAME='120R2F-GP_RCL_GP-120R2F-GP,64.A',
 PRIM_FILE='C:/<user>/w_hdl/120r2f#2dgp/chips/chips.prt';

PART_NAME
 R25W57 'RES_0402-49.9K,1%,1/16W,CHIP,GA':
 ROOM='V_SUPER';

SECTION_NUMBER 1
 '@BASEBOARD_FAB2_LIB.BASEBOARD_FAB2(SCH_1):PAGE147_I151@MSTR_DISCRETE.RES(CHIPS)':
 C_PATH='@baseboard_fab2_lib.baseboard_fab2(sch_1):page147_i151@mstr_discrete.re~
s(chips)',
 P_PATH='@baseboard_fab2_lib.baseboard_fab2(sch_1):page147_i151@mstr_discrete.re~
s(chips)',
 PATH='I151',
 DRAWING='@BASEBOARD_FAB2_LIB.BASEBOARD_FAB2(SCH_1):PAGE147',
 WATTAGE='1/16W',
 TOLERANCE='1%',
 SEC_TYPE='0402',
 MATERIAL='CHIP',
 PHYS_PAGE='147',
 XY='(900,1950)',
 ROT='0',
 VER='2',
 VALUE='49.9K',
 PACK_TYPE='0402',
 PART_NUMBER='G21796-048',
 LOCATION='R25W57',
 ROOM='V_SUPER',
 SEC='1',
 CDS_LIB='mstr_discrete',
 CDS_PART_NAME='RES_0402-49.9K,1%,1/16W,CHIP,GA',
 PRIM_FILE='./archive_libs/mstr_discrete/res/chips/chips.prt';

PART_NAME
 R25W58 '18KR2F-GP_RCL_GP-18KR2F-GP,64.A':;

SECTION_NUMBER 1
 '@BASEBOARD_FAB2_LIB.BASEBOARD_FAB2(SCH_1):PAGE144_I150@W_HDL.18KR2F-GP(CHIPS)':
 C_PATH='@baseboard_fab2_lib.baseboard_fab2(sch_1):page144_i150@w_hdl.\18kr2f-gp~
\(chips)',
 P_PATH='@baseboard_fab2_lib.baseboard_fab2(sch_1):page144_i150@w_hdl.\18kr2f-gp~
\(chips)',
 PATH='I150',
 DRAWING='@BASEBOARD_FAB2_LIB.BASEBOARD_FAB2(SCH_1):PAGE144',
 PACK_SIZE='0402',
 RATED='1/16W',
 ATTRIBUTE='18KOHM',
 TOLERANCE='1%',
 SEC_TYPE='RCL_GP',
 PHYS_PAGE='144',
 XY='(-2400,-3525)',
 ROT='0',
 VER='1',
 VALUE='18KR2F-GP',
 PACK_TYPE='RCL_GP',
 PART_NUMBER='64.18025.6DL',
 LOCATION='R25W58',
 SEC='1',
 CDS_LIB='w_hdl',
 CDS_PART_NAME='18KR2F-GP_RCL_GP-18KR2F-GP,64.A',
 PRIM_FILE='C:/<user>/w_hdl/18kr2f#2dgp/chips/chips.prt';

PART_NAME
 R25W59 'RES_0402-0.0,5%,1/16W,CHIP,G21A':
 ROOM='USB';

SECTION_NUMBER 1
 '@BASEBOARD_FAB2_LIB.BASEBOARD_FAB2(SCH_1):PAGE148_I16@MSTR_DISCRETE.RES(CHIPS)':
 C_PATH='@baseboard_fab2_lib.baseboard_fab2(sch_1):page148_i16@mstr_discrete.res~
(chips)',
 P_PATH='@baseboard_fab2_lib.baseboard_fab2(sch_1):page148_i16@mstr_discrete.res~
(chips)',
 PATH='I16',
 DRAWING='@BASEBOARD_FAB2_LIB.BASEBOARD_FAB2(SCH_1):PAGE148',
 WATTAGE='1/16W',
 TOLERANCE='5%',
 SEC_TYPE='0402',
 MATERIAL='CHIP',
 BOM_COST='MIO_USB',
 PHYS_PAGE='148',
 XY='(-6550,3850)',
 ROT='0',
 VER='1',
 VALUE='0.0',
 PACK_TYPE='0402',
 PART_NUMBER='G21497-005',
 LOCATION='R25W59',
 ROOM='USB',
 SEC='1',
 CDS_LIB='mstr_discrete',
 CDS_PART_NAME='RES_0402-0.0,5%,1/16W,CHIP,G21A',
 PRIM_FILE='./archive_libs/mstr_discrete/res/chips/chips.prt';

PART_NAME
 R25W60 'RES_0402-100.0K,1%,1/16W,CHIP,A':
 GROUP='AST2520',
 ROOM='BMC';

SECTION_NUMBER 1
 '@BASEBOARD_FAB2_LIB.BASEBOARD_FAB2(SCH_1):PAGE145_I34@MSTR_DISCRETE.RES(CHIPS)':
 C_PATH='@baseboard_fab2_lib.baseboard_fab2(sch_1):page145_i34@mstr_discrete.res~
(chips)',
 P_PATH='@baseboard_fab2_lib.baseboard_fab2(sch_1):page145_i34@mstr_discrete.res~
(chips)',
 PATH='I34',
 DRAWING='@BASEBOARD_FAB2_LIB.BASEBOARD_FAB2(SCH_1):PAGE145',
 WATTAGE='1/16W',
 TOLERANCE='1%',
 SEC_TYPE='0402',
 MATERIAL='CHIP',
 BOM_COST='SM_CONTROLLER',
 PHYS_PAGE='145',
 XY='(-5700,-4150)',
 ROT='0',
 VER='2',
 VALUE='100.0K',
 PACK_TYPE='0402',
 PART_NUMBER='G21796-010',
 LOCATION='R25W60',
 ROOM='BMC',
 GROUP='AST2520',
 SEC='1',
 CDS_LIB='mstr_discrete',
 CDS_PART_NAME='RES_0402-100.0K,1%,1/16W,CHIP,A',
 PRIM_FILE='./archive_libs/mstr_discrete/res/chips/chips.prt';

PART_NAME
 R25W61 'RES_0402-100.0K,1%,1/16W,CHIP,A':
 GROUP='AST2520',
 ROOM='BMC';

SECTION_NUMBER 1
 '@BASEBOARD_FAB2_LIB.BASEBOARD_FAB2(SCH_1):PAGE145_I30@MSTR_DISCRETE.RES(CHIPS)':
 C_PATH='@baseboard_fab2_lib.baseboard_fab2(sch_1):page145_i30@mstr_discrete.res~
(chips)',
 P_PATH='@baseboard_fab2_lib.baseboard_fab2(sch_1):page145_i30@mstr_discrete.res~
(chips)',
 PATH='I30',
 DRAWING='@BASEBOARD_FAB2_LIB.BASEBOARD_FAB2(SCH_1):PAGE145',
 WATTAGE='1/16W',
 TOLERANCE='1%',
 SEC_TYPE='0402',
 MATERIAL='CHIP',
 BOM_COST='SM_CONTROLLER',
 PHYS_PAGE='145',
 XY='(-5450,-4150)',
 ROT='0',
 VER='2',
 VALUE='100.0K',
 PACK_TYPE='0402',
 PART_NUMBER='G21796-010',
 LOCATION='R25W61',
 ROOM='BMC',
 GROUP='AST2520',
 SEC='1',
 CDS_LIB='mstr_discrete',
 CDS_PART_NAME='RES_0402-100.0K,1%,1/16W,CHIP,A',
 PRIM_FILE='./archive_libs/mstr_discrete/res/chips/chips.prt';

PART_NAME
 R25W62 'RES_0402-100.0K,1%,1/16W,CHIP,A':
 GROUP='AST2520',
 ROOM='BMC';

SECTION_NUMBER 1
 '@BASEBOARD_FAB2_LIB.BASEBOARD_FAB2(SCH_1):PAGE145_I31@MSTR_DISCRETE.RES(CHIPS)':
 C_PATH='@baseboard_fab2_lib.baseboard_fab2(sch_1):page145_i31@mstr_discrete.res~
(chips)',
 P_PATH='@baseboard_fab2_lib.baseboard_fab2(sch_1):page145_i31@mstr_discrete.res~
(chips)',
 PATH='I31',
 DRAWING='@BASEBOARD_FAB2_LIB.BASEBOARD_FAB2(SCH_1):PAGE145',
 WATTAGE='1/16W',
 TOLERANCE='1%',
 SEC_TYPE='0402',
 MATERIAL='CHIP',
 BOM_COST='SM_CONTROLLER',
 PHYS_PAGE='145',
 XY='(-5200,-4150)',
 ROT='0',
 VER='2',
 VALUE='100.0K',
 PACK_TYPE='0402',
 PART_NUMBER='G21796-010',
 LOCATION='R25W62',
 ROOM='BMC',
 GROUP='AST2520',
 SEC='1',
 CDS_LIB='mstr_discrete',
 CDS_PART_NAME='RES_0402-100.0K,1%,1/16W,CHIP,A',
 PRIM_FILE='./archive_libs/mstr_discrete/res/chips/chips.prt';

PART_NAME
 R25W63 'RES_0402-100.0K,1%,1/16W,CHIP,A':
 ROOM='BMC';

SECTION_NUMBER 1
 '@BASEBOARD_FAB2_LIB.BASEBOARD_FAB2(SCH_1):PAGE146_I65@MSTR_DISCRETE.RES(CHIPS)':
 C_PATH='@baseboard_fab2_lib.baseboard_fab2(sch_1):page146_i65@mstr_discrete.res~
(chips)',
 P_PATH='@baseboard_fab2_lib.baseboard_fab2(sch_1):page146_i65@mstr_discrete.res~
(chips)',
 PATH='I65',
 DRAWING='@BASEBOARD_FAB2_LIB.BASEBOARD_FAB2(SCH_1):PAGE146',
 WATTAGE='1/16W',
 TOLERANCE='1%',
 SEC_TYPE='0402',
 MATERIAL='CHIP',
 BOM_COST='SM_CONTROLLER',
 PHYS_PAGE='146',
 XY='(-1550,1400)',
 ROT='0',
 VER='2',
 VALUE='100.0K',
 PACK_TYPE='0402',
 PART_NUMBER='G21796-010',
 LOCATION='R25W63',
 ROOM='BMC',
 SEC='1',
 CDS_LIB='mstr_discrete',
 CDS_PART_NAME='RES_0402-100.0K,1%,1/16W,CHIP,A',
 PRIM_FILE='./archive_libs/mstr_discrete/res/chips/chips.prt';

PART_NAME
 R25W64 'RES_0402-100.0K,1%,1/16W,CHIP,A':
 GROUP='AST2520',
 ROOM='BMC';

SECTION_NUMBER 1
 '@BASEBOARD_FAB2_LIB.BASEBOARD_FAB2(SCH_1):PAGE145_I36@MSTR_DISCRETE.RES(CHIPS)':
 C_PATH='@baseboard_fab2_lib.baseboard_fab2(sch_1):page145_i36@mstr_discrete.res~
(chips)',
 P_PATH='@baseboard_fab2_lib.baseboard_fab2(sch_1):page145_i36@mstr_discrete.res~
(chips)',
 PATH='I36',
 DRAWING='@BASEBOARD_FAB2_LIB.BASEBOARD_FAB2(SCH_1):PAGE145',
 WATTAGE='1/16W',
 TOLERANCE='1%',
 SEC_TYPE='0402',
 MATERIAL='CHIP',
 BOM_COST='SM_CONTROLLER',
 PHYS_PAGE='145',
 XY='(-5950,-4150)',
 ROT='0',
 VER='2',
 VALUE='100.0K',
 PACK_TYPE='0402',
 PART_NUMBER='G21796-010',
 LOCATION='R25W64',
 ROOM='BMC',
 GROUP='AST2520',
 SEC='1',
 CDS_LIB='mstr_discrete',
 CDS_PART_NAME='RES_0402-100.0K,1%,1/16W,CHIP,A',
 PRIM_FILE='./archive_libs/mstr_discrete/res/chips/chips.prt';

PART_NAME
 R25W65 'RES_0402-100.0K,1%,1/16W,CHIP,A':
 GROUP='AST2520',
 ROOM='BMC';

SECTION_NUMBER 1
 '@BASEBOARD_FAB2_LIB.BASEBOARD_FAB2(SCH_1):PAGE145_I38@MSTR_DISCRETE.RES(CHIPS)':
 C_PATH='@baseboard_fab2_lib.baseboard_fab2(sch_1):page145_i38@mstr_discrete.res~
(chips)',
 P_PATH='@baseboard_fab2_lib.baseboard_fab2(sch_1):page145_i38@mstr_discrete.res~
(chips)',
 PATH='I38',
 DRAWING='@BASEBOARD_FAB2_LIB.BASEBOARD_FAB2(SCH_1):PAGE145',
 WATTAGE='1/16W',
 TOLERANCE='1%',
 SEC_TYPE='0402',
 MATERIAL='CHIP',
 BOM_COST='SM_CONTROLLER',
 PHYS_PAGE='145',
 XY='(-6200,-4150)',
 ROT='0',
 VER='2',
 VALUE='100.0K',
 PACK_TYPE='0402',
 PART_NUMBER='G21796-010',
 LOCATION='R25W65',
 ROOM='BMC',
 GROUP='AST2520',
 SEC='1',
 CDS_LIB='mstr_discrete',
 CDS_PART_NAME='RES_0402-100.0K,1%,1/16W,CHIP,A',
 PRIM_FILE='./archive_libs/mstr_discrete/res/chips/chips.prt';

PART_NAME
 R25W66 'RES_0402-100.0K,1%,1/16W,CHIP,A':
 ROOM='BMC';

SECTION_NUMBER 1
 '@BASEBOARD_FAB2_LIB.BASEBOARD_FAB2(SCH_1):PAGE146_I76@MSTR_DISCRETE.RES(CHIPS)':
 C_PATH='@baseboard_fab2_lib.baseboard_fab2(sch_1):page146_i76@mstr_discrete.res~
(chips)',
 P_PATH='@baseboard_fab2_lib.baseboard_fab2(sch_1):page146_i76@mstr_discrete.res~
(chips)',
 PATH='I76',
 DRAWING='@BASEBOARD_FAB2_LIB.BASEBOARD_FAB2(SCH_1):PAGE146',
 POP='NOPOP',
 WATTAGE='1/16W',
 TOLERANCE='1%',
 MATERIAL='CHIP',
 PHYS_PAGE='146',
 XY='(-6250,850)',
 ROT='0',
 VER='2',
 VALUE='100.0K',
 PACK_TYPE='0402',
 PART_NUMBER='G21796-010',
 LOCATION='R25W66',
 ROOM='BMC',
 CDS_LIB='mstr_discrete',
 CDS_PART_NAME='RES_0402-100.0K,1%,1/16W,CHIP,A',
 PRIM_FILE='./archive_libs/mstr_discrete/res/chips/chips.prt';

PART_NAME
 R25W67 '200R2F-L1-GP_SMD-RG4-200R2F-L1A':
 GROUP='AST2500';

SECTION_NUMBER 1
 '@BASEBOARD_FAB2_LIB.BASEBOARD_FAB2(SCH_1):PAGE145_I118@W_HDL.200R2F-L1-GP(CHIPS)':
 C_PATH='@baseboard_fab2_lib.baseboard_fab2(sch_1):page145_i118@w_hdl.\200r2f-l1~
-gp\(chips)',
 P_PATH='@baseboard_fab2_lib.baseboard_fab2(sch_1):page145_i118@w_hdl.\200r2f-l1~
-gp\(chips)',
 PATH='I118',
 DRAWING='@BASEBOARD_FAB2_LIB.BASEBOARD_FAB2(SCH_1):PAGE145',
 PACK_SIZE='0402',
 RATED='1/16W',
 ATTRIBUTE='200 OHM',
 TOLERANCE='1%',
 PHYS_PAGE='145',
 XY='(-1625,-3200)',
 ROT='1',
 VER='1',
 VALUE='200R2F-L1-GP',
 PACK_TYPE='SMD-RG4',
 PART_NUMBER='64.20005.L0L',
 LOCATION='R25W67',
 GROUP='AST2500',
 CDS_LIB='w_hdl',
 CDS_PART_NAME='200R2F-L1-GP_SMD-RG4-200R2F-L1A',
 PRIM_FILE='C:/<user>/w_hdl/200r2f#2dl1#2dgp/chips/chips.prt';

PART_NAME
 R25W68 'RES_0402-33.2,1%,1/16W,CHIP,G2A':
 ROOM='BMC';

SECTION_NUMBER 1
 '@BASEBOARD_FAB2_LIB.BASEBOARD_FAB2(SCH_1):PAGE146_I84@MSTR_DISCRETE.RES(CHIPS)':
 C_PATH='@baseboard_fab2_lib.baseboard_fab2(sch_1):page146_i84@mstr_discrete.res~
(chips)',
 P_PATH='@baseboard_fab2_lib.baseboard_fab2(sch_1):page146_i84@mstr_discrete.res~
(chips)',
 PATH='I84',
 DRAWING='@BASEBOARD_FAB2_LIB.BASEBOARD_FAB2(SCH_1):PAGE146',
 WATTAGE='1/16W',
 TOLERANCE='1%',
 SEC_TYPE='0402',
 MATERIAL='CHIP',
 BOM_COST='SB',
 PHYS_PAGE='146',
 XY='(-6850,1400)',
 ROT='0',
 VER='1',
 VALUE='33.2',
 PACK_TYPE='0402',
 PART_NUMBER='G21796-074',
 LOCATION='R25W68',
 ROOM='BMC',
 SEC='1',
 CDS_LIB='mstr_discrete',
 CDS_PART_NAME='RES_0402-33.2,1%,1/16W,CHIP,G2A',
 PRIM_FILE='./archive_libs/mstr_discrete/res/chips/chips.prt';

PART_NAME
 R25W69 'RES_0402-33.2,1%,1/16W,CHIP,G2A':
 ROOM='BMC';

SECTION_NUMBER 1
 '@BASEBOARD_FAB2_LIB.BASEBOARD_FAB2(SCH_1):PAGE146_I85@MSTR_DISCRETE.RES(CHIPS)':
 C_PATH='@baseboard_fab2_lib.baseboard_fab2(sch_1):page146_i85@mstr_discrete.res~
(chips)',
 P_PATH='@baseboard_fab2_lib.baseboard_fab2(sch_1):page146_i85@mstr_discrete.res~
(chips)',
 PATH='I85',
 DRAWING='@BASEBOARD_FAB2_LIB.BASEBOARD_FAB2(SCH_1):PAGE146',
 WATTAGE='1/16W',
 TOLERANCE='1%',
 SEC_TYPE='0402',
 MATERIAL='CHIP',
 BOM_COST='SB',
 PHYS_PAGE='146',
 XY='(-6850,1300)',
 ROT='0',
 VER='1',
 VALUE='33.2',
 PACK_TYPE='0402',
 PART_NUMBER='G21796-074',
 LOCATION='R25W69',
 ROOM='BMC',
 SEC='1',
 CDS_LIB='mstr_discrete',
 CDS_PART_NAME='RES_0402-33.2,1%,1/16W,CHIP,G2A',
 PRIM_FILE='./archive_libs/mstr_discrete/res/chips/chips.prt';

PART_NAME
 R25W70 'RES_0402-33.2,1%,1/16W,CHIP,G2A':
 ROOM='BMC';

SECTION_NUMBER 1
 '@BASEBOARD_FAB2_LIB.BASEBOARD_FAB2(SCH_1):PAGE144_I114@MSTR_DISCRETE.RES(CHIPS)':
 C_PATH='@baseboard_fab2_lib.baseboard_fab2(sch_1):page144_i114@mstr_discrete.re~
s(chips)',
 P_PATH='@baseboard_fab2_lib.baseboard_fab2(sch_1):page144_i114@mstr_discrete.re~
s(chips)',
 PATH='I114',
 DRAWING='@BASEBOARD_FAB2_LIB.BASEBOARD_FAB2(SCH_1):PAGE144',
 WATTAGE='1/16W',
 TOLERANCE='1%',
 SEC_TYPE='0402',
 MATERIAL='CHIP',
 BOM_COST='SM_CONTROLLER',
 PHYS_PAGE='144',
 XY='(-1750,-2800)',
 ROT='0',
 VER='1',
 VALUE='33.2',
 PACK_TYPE='0402',
 PART_NUMBER='G21796-074',
 LOCATION='R25W70',
 ROOM='BMC',
 SEC='1',
 CDS_LIB='mstr_discrete',
 CDS_PART_NAME='RES_0402-33.2,1%,1/16W,CHIP,G2A',
 PRIM_FILE='./archive_libs/mstr_discrete/res/chips/chips.prt';

PART_NAME
 R25W72 'RES_0402-33.2,1%,1/16W,CHIP,G2A':
 ROOM='BMC';

SECTION_NUMBER 1
 '@BASEBOARD_FAB2_LIB.BASEBOARD_FAB2(SCH_1):PAGE146_I71@MSTR_DISCRETE.RES(CHIPS)':
 C_PATH='@baseboard_fab2_lib.baseboard_fab2(sch_1):page146_i71@mstr_discrete.res~
(chips)',
 P_PATH='@baseboard_fab2_lib.baseboard_fab2(sch_1):page146_i71@mstr_discrete.res~
(chips)',
 PATH='I71',
 DRAWING='@BASEBOARD_FAB2_LIB.BASEBOARD_FAB2(SCH_1):PAGE146',
 WATTAGE='1/16W',
 TOLERANCE='1%',
 SEC_TYPE='0402',
 MATERIAL='CHIP',
 BOM_COST='SM_CONTROLLER',
 PHYS_PAGE='146',
 XY='(-6350,1550)',
 ROT='0',
 VER='1',
 VALUE='33.2',
 PACK_TYPE='0402',
 PART_NUMBER='G21796-074',
 LOCATION='R25W72',
 ROOM='BMC',
 SEC='1',
 CDS_LIB='mstr_discrete',
 CDS_PART_NAME='RES_0402-33.2,1%,1/16W,CHIP,G2A',
 PRIM_FILE='./archive_libs/mstr_discrete/res/chips/chips.prt';

PART_NAME
 R25W73 'RES_0402-33.2,1%,1/16W,CHIP,G2A':
 ROOM='BMC';

SECTION_NUMBER 1
 '@BASEBOARD_FAB2_LIB.BASEBOARD_FAB2(SCH_1):PAGE146_I73@MSTR_DISCRETE.RES(CHIPS)':
 C_PATH='@baseboard_fab2_lib.baseboard_fab2(sch_1):page146_i73@mstr_discrete.res~
(chips)',
 P_PATH='@baseboard_fab2_lib.baseboard_fab2(sch_1):page146_i73@mstr_discrete.res~
(chips)',
 PATH='I73',
 DRAWING='@BASEBOARD_FAB2_LIB.BASEBOARD_FAB2(SCH_1):PAGE146',
 WATTAGE='1/16W',
 TOLERANCE='1%',
 SEC_TYPE='0402',
 MATERIAL='CHIP',
 BOM_COST='SM_CONTROLLER',
 PHYS_PAGE='146',
 XY='(-6350,1650)',
 ROT='0',
 VER='1',
 VALUE='33.2',
 PACK_TYPE='0402',
 PART_NUMBER='G21796-074',
 LOCATION='R25W73',
 ROOM='BMC',
 SEC='1',
 CDS_LIB='mstr_discrete',
 CDS_PART_NAME='RES_0402-33.2,1%,1/16W,CHIP,G2A',
 PRIM_FILE='./archive_libs/mstr_discrete/res/chips/chips.prt';

PART_NAME
 R25W74 'RES_0402-0.0,5%,1/16W,CHIP,G21A':
 ROOM='BMC';

SECTION_NUMBER 1
 '@BASEBOARD_FAB2_LIB.BASEBOARD_FAB2(SCH_1):PAGE146_I70@MSTR_DISCRETE.RES(CHIPS)':
 C_PATH='@baseboard_fab2_lib.baseboard_fab2(sch_1):page146_i70@mstr_discrete.res~
(chips)',
 P_PATH='@baseboard_fab2_lib.baseboard_fab2(sch_1):page146_i70@mstr_discrete.res~
(chips)',
 PATH='I70',
 DRAWING='@BASEBOARD_FAB2_LIB.BASEBOARD_FAB2(SCH_1):PAGE146',
 WATTAGE='1/16W',
 TOLERANCE='5%',
 SEC_TYPE='0402',
 MATERIAL='CHIP',
 BOM_COST='SM_CONTROLLER',
 PHYS_PAGE='146',
 XY='(-6350,1750)',
 ROT='0',
 VER='1',
 VALUE='0.0',
 PACK_TYPE='0402',
 PART_NUMBER='G21497-005',
 LOCATION='R25W74',
 ROOM='BMC',
 SEC='1',
 CDS_LIB='mstr_discrete',
 CDS_PART_NAME='RES_0402-0.0,5%,1/16W,CHIP,G21A',
 PRIM_FILE='./archive_libs/mstr_discrete/res/chips/chips.prt';

PART_NAME
 R25W75 'RES_0402-33.2,1%,1/16W,CHIP,G2A':
 ROOM='BMC';

SECTION_NUMBER 1
 '@BASEBOARD_FAB2_LIB.BASEBOARD_FAB2(SCH_1):PAGE144_I118@MSTR_DISCRETE.RES(CHIPS)':
 C_PATH='@baseboard_fab2_lib.baseboard_fab2(sch_1):page144_i118@mstr_discrete.re~
s(chips)',
 P_PATH='@baseboard_fab2_lib.baseboard_fab2(sch_1):page144_i118@mstr_discrete.re~
s(chips)',
 PATH='I118',
 DRAWING='@BASEBOARD_FAB2_LIB.BASEBOARD_FAB2(SCH_1):PAGE144',
 WATTAGE='1/16W',
 TOLERANCE='1%',
 SEC_TYPE='0402',
 MATERIAL='CHIP',
 BOM_COST='SM_CONTROLLER',
 PHYS_PAGE='144',
 XY='(-1750,-2750)',
 ROT='0',
 VER='1',
 VALUE='33.2',
 PACK_TYPE='0402',
 PART_NUMBER='G21796-074',
 LOCATION='R25W75',
 ROOM='BMC',
 SEC='1',
 CDS_LIB='mstr_discrete',
 CDS_PART_NAME='RES_0402-33.2,1%,1/16W,CHIP,G2A',
 PRIM_FILE='./archive_libs/mstr_discrete/res/chips/chips.prt';

PART_NAME
 R25W78 'RES_0402-22.1,1.0%,1/16W,CHIP,A':
 ROOM='BMC';

SECTION_NUMBER 1
 '@BASEBOARD_FAB2_LIB.BASEBOARD_FAB2(SCH_1):PAGE146_I123@MSTR_DISCRETE.RES(CHIPS)':
 C_PATH='@baseboard_fab2_lib.baseboard_fab2(sch_1):page146_i123@mstr_discrete.re~
s(chips)',
 P_PATH='@baseboard_fab2_lib.baseboard_fab2(sch_1):page146_i123@mstr_discrete.re~
s(chips)',
 PATH='I123',
 DRAWING='@BASEBOARD_FAB2_LIB.BASEBOARD_FAB2(SCH_1):PAGE146',
 WATTAGE='1/16W',
 TOLERANCE='1.0%',
 SEC_TYPE='0402',
 MATERIAL='CHIP',
 BOM_COST='SM_CONTROLLER',
 PHYS_PAGE='146',
 XY='(-1450,2050)',
 ROT='0',
 VER='1',
 VALUE='22.1',
 PACK_TYPE='0402',
 PART_NUMBER='G21796-250',
 LOCATION='R25W78',
 ROOM='BMC',
 SEC='1',
 CDS_LIB='mstr_discrete',
 CDS_PART_NAME='RES_0402-22.1,1.0%,1/16W,CHIP,A',
 PRIM_FILE='./archive_libs/mstr_discrete/res/chips/chips.prt';

PART_NAME
 R25W79 'RES_0402-10.0K,1%,1/16W,CHIP,GA':
 ROOM='BMC';

SECTION_NUMBER 1
 '@BASEBOARD_FAB2_LIB.BASEBOARD_FAB2(SCH_1):PAGE147_I42@MSTR_DISCRETE.RES(CHIPS)':
 C_PATH='@baseboard_fab2_lib.baseboard_fab2(sch_1):page147_i42@mstr_discrete.res~
(chips)',
 P_PATH='@baseboard_fab2_lib.baseboard_fab2(sch_1):page147_i42@mstr_discrete.res~
(chips)',
 PATH='I42',
 DRAWING='@BASEBOARD_FAB2_LIB.BASEBOARD_FAB2(SCH_1):PAGE147',
 WATTAGE='1/16W',
 TOLERANCE='1%',
 SEC_TYPE='0402',
 MATERIAL='CHIP',
 BOM_COST='SM_CONTROLLER',
 PHYS_PAGE='147',
 XY='(-3600,4950)',
 ROT='0',
 VER='2',
 VALUE='10.0K',
 PACK_TYPE='0402',
 PART_NUMBER='G21796-016',
 LOCATION='R25W79',
 ROOM='BMC',
 SEC='1',
 CDS_LIB='mstr_discrete',
 CDS_PART_NAME='RES_0402-10.0K,1%,1/16W,CHIP,GA',
 PRIM_FILE='./archive_libs/mstr_discrete/res/chips/chips.prt';

PART_NAME
 R25W80 'RES_0402-10.0K,1%,1/16W,CHIP,GA':
 ROOM='BMC';

SECTION_NUMBER 1
 '@BASEBOARD_FAB2_LIB.BASEBOARD_FAB2(SCH_1):PAGE147_I43@MSTR_DISCRETE.RES(CHIPS)':
 C_PATH='@baseboard_fab2_lib.baseboard_fab2(sch_1):page147_i43@mstr_discrete.res~
(chips)',
 P_PATH='@baseboard_fab2_lib.baseboard_fab2(sch_1):page147_i43@mstr_discrete.res~
(chips)',
 PATH='I43',
 DRAWING='@BASEBOARD_FAB2_LIB.BASEBOARD_FAB2(SCH_1):PAGE147',
 WATTAGE='1/16W',
 TOLERANCE='1%',
 SEC_TYPE='0402',
 MATERIAL='CHIP',
 BOM_COST='SM_CONTROLLER',
 PHYS_PAGE='147',
 XY='(-3900,4950)',
 ROT='0',
 VER='2',
 VALUE='10.0K',
 PACK_TYPE='0402',
 PART_NUMBER='G21796-016',
 LOCATION='R25W80',
 ROOM='BMC',
 SEC='1',
 CDS_LIB='mstr_discrete',
 CDS_PART_NAME='RES_0402-10.0K,1%,1/16W,CHIP,GA',
 PRIM_FILE='./archive_libs/mstr_discrete/res/chips/chips.prt';

PART_NAME
 R25W81 'RES_0402-33.2,1%,1/16W,CHIP,G2A':
 ROOM='BMC';

SECTION_NUMBER 1
 '@BASEBOARD_FAB2_LIB.BASEBOARD_FAB2(SCH_1):PAGE146_I67@MSTR_DISCRETE.RES(CHIPS)':
 C_PATH='@baseboard_fab2_lib.baseboard_fab2(sch_1):page146_i67@mstr_discrete.res~
(chips)',
 P_PATH='@baseboard_fab2_lib.baseboard_fab2(sch_1):page146_i67@mstr_discrete.res~
(chips)',
 PATH='I67',
 DRAWING='@BASEBOARD_FAB2_LIB.BASEBOARD_FAB2(SCH_1):PAGE146',
 WATTAGE='1/16W',
 TOLERANCE='1%',
 SEC_TYPE='0402',
 MATERIAL='CHIP',
 BOM_COST='SM_CONTROLLER',
 PHYS_PAGE='146',
 XY='(-6350,2350)',
 ROT='0',
 VER='1',
 VALUE='33.2',
 PACK_TYPE='0402',
 PART_NUMBER='G21796-074',
 LOCATION='R25W81',
 ROOM='BMC',
 SEC='1',
 CDS_LIB='mstr_discrete',
 CDS_PART_NAME='RES_0402-33.2,1%,1/16W,CHIP,G2A',
 PRIM_FILE='./archive_libs/mstr_discrete/res/chips/chips.prt';

PART_NAME
 R25W82 'RES_0402-33.2,1%,1/16W,CHIP,G2A':
 ROOM='BMC';

SECTION_NUMBER 1
 '@BASEBOARD_FAB2_LIB.BASEBOARD_FAB2(SCH_1):PAGE146_I68@MSTR_DISCRETE.RES(CHIPS)':
 C_PATH='@baseboard_fab2_lib.baseboard_fab2(sch_1):page146_i68@mstr_discrete.res~
(chips)',
 P_PATH='@baseboard_fab2_lib.baseboard_fab2(sch_1):page146_i68@mstr_discrete.res~
(chips)',
 PATH='I68',
 DRAWING='@BASEBOARD_FAB2_LIB.BASEBOARD_FAB2(SCH_1):PAGE146',
 WATTAGE='1/16W',
 TOLERANCE='1%',
 SEC_TYPE='0402',
 MATERIAL='CHIP',
 BOM_COST='SM_CONTROLLER',
 PHYS_PAGE='146',
 XY='(-6350,2500)',
 ROT='0',
 VER='1',
 VALUE='33.2',
 PACK_TYPE='0402',
 PART_NUMBER='G21796-074',
 LOCATION='R25W82',
 ROOM='BMC',
 SEC='1',
 CDS_LIB='mstr_discrete',
 CDS_PART_NAME='RES_0402-33.2,1%,1/16W,CHIP,G2A',
 PRIM_FILE='./archive_libs/mstr_discrete/res/chips/chips.prt';

PART_NAME
 R25W83 'RES_0402-0.0,5%,1/16W,CHIP,G21A':
 ROOM='USB';

SECTION_NUMBER 1
 '@BASEBOARD_FAB2_LIB.BASEBOARD_FAB2(SCH_1):PAGE146_I26@MSTR_DISCRETE.RES(CHIPS)':
 C_PATH='@baseboard_fab2_lib.baseboard_fab2(sch_1):page146_i26@mstr_discrete.res~
(chips)',
 P_PATH='@baseboard_fab2_lib.baseboard_fab2(sch_1):page146_i26@mstr_discrete.res~
(chips)',
 PATH='I26',
 DRAWING='@BASEBOARD_FAB2_LIB.BASEBOARD_FAB2(SCH_1):PAGE146',
 WATTAGE='1/16W',
 TOLERANCE='5%',
 SEC_TYPE='0402',
 MATERIAL='CHIP',
 BOM_COST='MIO_USB',
 PHYS_PAGE='146',
 XY='(-6900,3900)',
 ROT='0',
 VER='1',
 VALUE='0.0',
 PACK_TYPE='0402',
 PART_NUMBER='G21497-005',
 LOCATION='R25W83',
 ROOM='USB',
 SEC='1',
 CDS_LIB='mstr_discrete',
 CDS_PART_NAME='RES_0402-0.0,5%,1/16W,CHIP,G21A',
 PRIM_FILE='./archive_libs/mstr_discrete/res/chips/chips.prt';

PART_NAME
 R25W85 'RES_0402-22.1,1.0%,1/16W,CHIP,A':
 ROOM='BMC';

SECTION_NUMBER 1
 '@BASEBOARD_FAB2_LIB.BASEBOARD_FAB2(SCH_1):PAGE147_I23@MSTR_DISCRETE.RES(CHIPS)':
 C_PATH='@baseboard_fab2_lib.baseboard_fab2(sch_1):page147_i23@mstr_discrete.res~
(chips)',
 P_PATH='@baseboard_fab2_lib.baseboard_fab2(sch_1):page147_i23@mstr_discrete.res~
(chips)',
 PATH='I23',
 DRAWING='@BASEBOARD_FAB2_LIB.BASEBOARD_FAB2(SCH_1):PAGE147',
 WATTAGE='1/16W',
 TOLERANCE='1.0%',
 SEC_TYPE='0402',
 MATERIAL='CHIP',
 BOM_COST='SM_CONTROLLER',
 PHYS_PAGE='147',
 XY='(800,4000)',
 ROT='0',
 VER='1',
 VALUE='22.1',
 PACK_TYPE='0402',
 PART_NUMBER='G21796-250',
 LOCATION='R25W85',
 ROOM='BMC',
 SEC='1',
 CDS_LIB='mstr_discrete',
 CDS_PART_NAME='RES_0402-22.1,1.0%,1/16W,CHIP,A',
 PRIM_FILE='./archive_libs/mstr_discrete/res/chips/chips.prt';

PART_NAME
 R25W86 'RES_0402-22.1,1.0%,1/16W,CHIP,A':
 ROOM='BMC';

SECTION_NUMBER 1
 '@BASEBOARD_FAB2_LIB.BASEBOARD_FAB2(SCH_1):PAGE147_I24@MSTR_DISCRETE.RES(CHIPS)':
 C_PATH='@baseboard_fab2_lib.baseboard_fab2(sch_1):page147_i24@mstr_discrete.res~
(chips)',
 P_PATH='@baseboard_fab2_lib.baseboard_fab2(sch_1):page147_i24@mstr_discrete.res~
(chips)',
 PATH='I24',
 DRAWING='@BASEBOARD_FAB2_LIB.BASEBOARD_FAB2(SCH_1):PAGE147',
 WATTAGE='1/16W',
 TOLERANCE='1.0%',
 SEC_TYPE='0402',
 MATERIAL='CHIP',
 BOM_COST='SM_CONTROLLER',
 PHYS_PAGE='147',
 XY='(800,3750)',
 ROT='0',
 VER='1',
 VALUE='22.1',
 PACK_TYPE='0402',
 PART_NUMBER='G21796-250',
 LOCATION='R25W86',
 ROOM='BMC',
 SEC='1',
 CDS_LIB='mstr_discrete',
 CDS_PART_NAME='RES_0402-22.1,1.0%,1/16W,CHIP,A',
 PRIM_FILE='./archive_libs/mstr_discrete/res/chips/chips.prt';

PART_NAME
 R25W87 'RES_0402-22.1,1.0%,1/16W,CHIP,A':
 ROOM='BMC';

SECTION_NUMBER 1
 '@BASEBOARD_FAB2_LIB.BASEBOARD_FAB2(SCH_1):PAGE147_I25@MSTR_DISCRETE.RES(CHIPS)':
 C_PATH='@baseboard_fab2_lib.baseboard_fab2(sch_1):page147_i25@mstr_discrete.res~
(chips)',
 P_PATH='@baseboard_fab2_lib.baseboard_fab2(sch_1):page147_i25@mstr_discrete.res~
(chips)',
 PATH='I25',
 DRAWING='@BASEBOARD_FAB2_LIB.BASEBOARD_FAB2(SCH_1):PAGE147',
 WATTAGE='1/16W',
 TOLERANCE='1.0%',
 SEC_TYPE='0402',
 MATERIAL='CHIP',
 BOM_COST='SM_CONTROLLER',
 PHYS_PAGE='147',
 XY='(800,3800)',
 ROT='0',
 VER='1',
 VALUE='22.1',
 PACK_TYPE='0402',
 PART_NUMBER='G21796-250',
 LOCATION='R25W87',
 ROOM='BMC',
 SEC='1',
 CDS_LIB='mstr_discrete',
 CDS_PART_NAME='RES_0402-22.1,1.0%,1/16W,CHIP,A',
 PRIM_FILE='./archive_libs/mstr_discrete/res/chips/chips.prt';

PART_NAME
 R25W88 'RES_0402-22.1,1.0%,1/16W,CHIP,A':
 ROOM='BMC';

SECTION_NUMBER 1
 '@BASEBOARD_FAB2_LIB.BASEBOARD_FAB2(SCH_1):PAGE147_I8@MSTR_DISCRETE.RES(CHIPS)':
 C_PATH='@baseboard_fab2_lib.baseboard_fab2(sch_1):page147_i8@mstr_discrete.res(~
chips)',
 P_PATH='@baseboard_fab2_lib.baseboard_fab2(sch_1):page147_i8@mstr_discrete.res(~
chips)',
 PATH='I8',
 DRAWING='@BASEBOARD_FAB2_LIB.BASEBOARD_FAB2(SCH_1):PAGE147',
 WATTAGE='1/16W',
 TOLERANCE='1.0%',
 SEC_TYPE='0402',
 MATERIAL='CHIP',
 BOM_COST='SM_CONTROLLER',
 PHYS_PAGE='147',
 XY='(1000,4400)',
 ROT='0',
 VER='1',
 VALUE='22.1',
 PACK_TYPE='0402',
 PART_NUMBER='G21796-250',
 LOCATION='R25W88',
 ROOM='BMC',
 SEC='1',
 CDS_LIB='mstr_discrete',
 CDS_PART_NAME='RES_0402-22.1,1.0%,1/16W,CHIP,A',
 PRIM_FILE='./archive_libs/mstr_discrete/res/chips/chips.prt';

PART_NAME
 R25W89 'RES_0402-22.1,1.0%,1/16W,CHIP,A':
 ROOM='BMC';

SECTION_NUMBER 1
 '@BASEBOARD_FAB2_LIB.BASEBOARD_FAB2(SCH_1):PAGE147_I22@MSTR_DISCRETE.RES(CHIPS)':
 C_PATH='@baseboard_fab2_lib.baseboard_fab2(sch_1):page147_i22@mstr_discrete.res~
(chips)',
 P_PATH='@baseboard_fab2_lib.baseboard_fab2(sch_1):page147_i22@mstr_discrete.res~
(chips)',
 PATH='I22',
 DRAWING='@BASEBOARD_FAB2_LIB.BASEBOARD_FAB2(SCH_1):PAGE147',
 WATTAGE='1/16W',
 TOLERANCE='1.0%',
 SEC_TYPE='0402',
 MATERIAL='CHIP',
 BOM_COST='SM_CONTROLLER',
 PHYS_PAGE='147',
 XY='(1000,4150)',
 ROT='0',
 VER='1',
 VALUE='22.1',
 PACK_TYPE='0402',
 PART_NUMBER='G21796-250',
 LOCATION='R25W89',
 ROOM='BMC',
 SEC='1',
 CDS_LIB='mstr_discrete',
 CDS_PART_NAME='RES_0402-22.1,1.0%,1/16W,CHIP,A',
 PRIM_FILE='./archive_libs/mstr_discrete/res/chips/chips.prt';

PART_NAME
 R25W90 'RES_0402-22.1,1.0%,1/16W,CHIP,A':
 ROOM='BMC';

SECTION_NUMBER 1
 '@BASEBOARD_FAB2_LIB.BASEBOARD_FAB2(SCH_1):PAGE147_I21@MSTR_DISCRETE.RES(CHIPS)':
 C_PATH='@baseboard_fab2_lib.baseboard_fab2(sch_1):page147_i21@mstr_discrete.res~
(chips)',
 P_PATH='@baseboard_fab2_lib.baseboard_fab2(sch_1):page147_i21@mstr_discrete.res~
(chips)',
 PATH='I21',
 DRAWING='@BASEBOARD_FAB2_LIB.BASEBOARD_FAB2(SCH_1):PAGE147',
 WATTAGE='1/16W',
 TOLERANCE='1.0%',
 SEC_TYPE='0402',
 MATERIAL='CHIP',
 BOM_COST='SM_CONTROLLER',
 PHYS_PAGE='147',
 XY='(1000,4200)',
 ROT='0',
 VER='1',
 VALUE='22.1',
 PACK_TYPE='0402',
 PART_NUMBER='G21796-250',
 LOCATION='R25W90',
 ROOM='BMC',
 SEC='1',
 CDS_LIB='mstr_discrete',
 CDS_PART_NAME='RES_0402-22.1,1.0%,1/16W,CHIP,A',
 PRIM_FILE='./archive_libs/mstr_discrete/res/chips/chips.prt';

PART_NAME
 R25W93 'RES_0603-0,5.0%,1/10W,CHIP,G22A':
 ROOM='NIC_SPRV';

SECTION_NUMBER 1
 '@BASEBOARD_FAB2_LIB.BASEBOARD_FAB2(SCH_1):PAGE149_I90@MSTR_DISCRETE.RES(CHIPS)':
 C_PATH='@baseboard_fab2_lib.baseboard_fab2(sch_1):page149_i90@mstr_discrete.res~
(chips)',
 P_PATH='@baseboard_fab2_lib.baseboard_fab2(sch_1):page149_i90@mstr_discrete.res~
(chips)',
 PATH='I90',
 DRAWING='@BASEBOARD_FAB2_LIB.BASEBOARD_FAB2(SCH_1):PAGE149',
 WATTAGE='1/10W',
 TOLERANCE='5.0%',
 MATERIAL='CHIP',
 BOM_COST='NT_GBE_BASE',
 PHYS_PAGE='149',
 XY='(125,4275)',
 ROT='0',
 VER='1',
 VALUE='0',
 PACK_TYPE='0603',
 PART_NUMBER='G22178-002',
 LOCATION='R25W93',
 ROOM='NIC_SPRV',
 CDS_LIB='mstr_discrete',
 CDS_PART_NAME='RES_0603-0,5.0%,1/10W,CHIP,G22A',
 PRIM_FILE='./archive_libs/mstr_discrete/res/chips/chips.prt';

PART_NAME
 R25W94 'RES_0402-4.75K,1%,1/16W,CHIP,GA':
 ROOM='BMC';

SECTION_NUMBER 1
 '@BASEBOARD_FAB2_LIB.BASEBOARD_FAB2(SCH_1):PAGE137_I140@MSTR_DISCRETE.RES(CHIPS)':
 C_PATH='@baseboard_fab2_lib.baseboard_fab2(sch_1):page137_i140@mstr_discrete.re~
s(chips)',
 P_PATH='@baseboard_fab2_lib.baseboard_fab2(sch_1):page137_i140@mstr_discrete.re~
s(chips)',
 PATH='I140',
 DRAWING='@BASEBOARD_FAB2_LIB.BASEBOARD_FAB2(SCH_1):PAGE137',
 WATTAGE='1/16W',
 TOLERANCE='1%',
 SEC_TYPE='0402',
 MATERIAL='CHIP',
 BOM_COST='SM_CONTROLLER',
 PHYS_PAGE='137',
 XY='(-1250,3300)',
 ROT='1',
 VER='1',
 VALUE='4.75K',
 PACK_TYPE='0402',
 PART_NUMBER='G21796-072',
 LOCATION='R25W94',
 ROOM='BMC',
 SEC='1',
 CDS_LIB='mstr_discrete',
 CDS_PART_NAME='RES_0402-4.75K,1%,1/16W,CHIP,GA',
 PRIM_FILE='./archive_libs/mstr_discrete/res/chips/chips.prt';

PART_NAME
 R25W95 'RES_0402-4.75K,1%,1/16W,CHIP,GA':
 ROOM='BMC';

SECTION_NUMBER 1
 '@BASEBOARD_FAB2_LIB.BASEBOARD_FAB2(SCH_1):PAGE150_I144@MSTR_DISCRETE.RES(CHIPS)':
 C_PATH='@baseboard_fab2_lib.baseboard_fab2(sch_1):page150_i144@mstr_discrete.re~
s(chips)',
 P_PATH='@baseboard_fab2_lib.baseboard_fab2(sch_1):page150_i144@mstr_discrete.re~
s(chips)',
 PATH='I144',
 DRAWING='@BASEBOARD_FAB2_LIB.BASEBOARD_FAB2(SCH_1):PAGE150',
 WATTAGE='1/16W',
 TOLERANCE='1%',
 SEC_TYPE='0402',
 MATERIAL='CHIP',
 BOM_COST='SM_CONTROLLER',
 PHYS_PAGE='150',
 XY='(-600,200)',
 ROT='0',
 VER='1',
 VALUE='4.75K',
 PACK_TYPE='0402',
 PART_NUMBER='G21796-072',
 LOCATION='R25W95',
 ROOM='BMC',
 SEC='1',
 CDS_LIB='mstr_discrete',
 CDS_PART_NAME='RES_0402-4.75K,1%,1/16W,CHIP,GA',
 PRIM_FILE='./archive_libs/mstr_discrete/res/chips/chips.prt';

PART_NAME
 R25W96 'RES_0402-4.75K,1%,1/16W,CHIP,GA':
 ROOM='BMC';

SECTION_NUMBER 1
 '@BASEBOARD_FAB2_LIB.BASEBOARD_FAB2(SCH_1):PAGE150_I145@MSTR_DISCRETE.RES(CHIPS)':
 C_PATH='@baseboard_fab2_lib.baseboard_fab2(sch_1):page150_i145@mstr_discrete.re~
s(chips)',
 P_PATH='@baseboard_fab2_lib.baseboard_fab2(sch_1):page150_i145@mstr_discrete.re~
s(chips)',
 PATH='I145',
 DRAWING='@BASEBOARD_FAB2_LIB.BASEBOARD_FAB2(SCH_1):PAGE150',
 WATTAGE='1/16W',
 TOLERANCE='1%',
 SEC_TYPE='0402',
 MATERIAL='CHIP',
 BOM_COST='SM_CONTROLLER',
 PHYS_PAGE='150',
 XY='(-600,0)',
 ROT='0',
 VER='1',
 VALUE='4.75K',
 PACK_TYPE='0402',
 PART_NUMBER='G21796-072',
 LOCATION='R25W96',
 ROOM='BMC',
 SEC='1',
 CDS_LIB='mstr_discrete',
 CDS_PART_NAME='RES_0402-4.75K,1%,1/16W,CHIP,GA',
 PRIM_FILE='./archive_libs/mstr_discrete/res/chips/chips.prt';

PART_NAME
 R25W97 'RES_0402-4.75K,1%,1/16W,EMPTY,A':
 ROOM='BMC';

SECTION_NUMBER 1
 '@BASEBOARD_FAB2_LIB.BASEBOARD_FAB2(SCH_1):PAGE150_I146@MSTR_DISCRETE.RES(CHIPS)':
 C_PATH='@baseboard_fab2_lib.baseboard_fab2(sch_1):page150_i146@mstr_discrete.re~
s(chips)',
 P_PATH='@baseboard_fab2_lib.baseboard_fab2(sch_1):page150_i146@mstr_discrete.re~
s(chips)',
 PATH='I146',
 DRAWING='@BASEBOARD_FAB2_LIB.BASEBOARD_FAB2(SCH_1):PAGE150',
 WATTAGE='1/16W',
 TOLERANCE='1%',
 SEC_TYPE='0402',
 MATERIAL='EMPTY',
 BOM_COST='SM_CONTROLLER',
 PHYS_PAGE='150',
 XY='(-600,-200)',
 ROT='0',
 VER='1',
 VALUE='4.75K',
 PACK_TYPE='0402',
 PART_NUMBER='G21796-072',
 LOCATION='R25W97',
 ROOM='BMC',
 SEC='1',
 CDS_LIB='mstr_discrete',
 CDS_PART_NAME='RES_0402-4.75K,1%,1/16W,EMPTY,A',
 PRIM_FILE='./archive_libs/mstr_discrete/res/chips/chips.prt';

PART_NAME
 R25W98 'RES_0402-4.75K,1%,1/16W,EMPTY,A':
 ROOM='BMC';

SECTION_NUMBER 1
 '@BASEBOARD_FAB2_LIB.BASEBOARD_FAB2(SCH_1):PAGE150_I209@MSTR_DISCRETE.RES(CHIPS)':
 C_PATH='@baseboard_fab2_lib.baseboard_fab2(sch_1):page150_i209@mstr_discrete.re~
s(chips)',
 P_PATH='@baseboard_fab2_lib.baseboard_fab2(sch_1):page150_i209@mstr_discrete.re~
s(chips)',
 PATH='I209',
 DRAWING='@BASEBOARD_FAB2_LIB.BASEBOARD_FAB2(SCH_1):PAGE150',
 WATTAGE='1/16W',
 TOLERANCE='1%',
 SEC_TYPE='0402',
 MATERIAL='EMPTY',
 BOM_COST='SM_CONTROLLER',
 PHYS_PAGE='150',
 XY='(1850,-200)',
 ROT='0',
 VER='1',
 VALUE='4.75K',
 PACK_TYPE='0402',
 PART_NUMBER='G21796-072',
 LOCATION='R25W98',
 ROOM='BMC',
 SEC='1',
 CDS_LIB='mstr_discrete',
 CDS_PART_NAME='RES_0402-4.75K,1%,1/16W,EMPTY,A',
 PRIM_FILE='./archive_libs/mstr_discrete/res/chips/chips.prt';

PART_NAME
 R25W99 'RES_0402-4.75K,1%,1/16W,EMPTY,A':
 ROOM='BMC';

SECTION_NUMBER 1
 '@BASEBOARD_FAB2_LIB.BASEBOARD_FAB2(SCH_1):PAGE150_I210@MSTR_DISCRETE.RES(CHIPS)':
 C_PATH='@baseboard_fab2_lib.baseboard_fab2(sch_1):page150_i210@mstr_discrete.re~
s(chips)',
 P_PATH='@baseboard_fab2_lib.baseboard_fab2(sch_1):page150_i210@mstr_discrete.re~
s(chips)',
 PATH='I210',
 DRAWING='@BASEBOARD_FAB2_LIB.BASEBOARD_FAB2(SCH_1):PAGE150',
 WATTAGE='1/16W',
 TOLERANCE='1%',
 SEC_TYPE='0402',
 MATERIAL='EMPTY',
 BOM_COST='SM_CONTROLLER',
 PHYS_PAGE='150',
 XY='(1850,-400)',
 ROT='0',
 VER='1',
 VALUE='4.75K',
 PACK_TYPE='0402',
 PART_NUMBER='G21796-072',
 LOCATION='R25W99',
 ROOM='BMC',
 SEC='1',
 CDS_LIB='mstr_discrete',
 CDS_PART_NAME='RES_0402-4.75K,1%,1/16W,EMPTY,A',
 PRIM_FILE='./archive_libs/mstr_discrete/res/chips/chips.prt';

PART_NAME
 R25W100 'RES_0402-4.75K,1%,1/16W,CHIP,GA':
 ROOM='BMC';

SECTION_NUMBER 1
 '@BASEBOARD_FAB2_LIB.BASEBOARD_FAB2(SCH_1):PAGE150_I211@MSTR_DISCRETE.RES(CHIPS)':
 C_PATH='@baseboard_fab2_lib.baseboard_fab2(sch_1):page150_i211@mstr_discrete.re~
s(chips)',
 P_PATH='@baseboard_fab2_lib.baseboard_fab2(sch_1):page150_i211@mstr_discrete.re~
s(chips)',
 PATH='I211',
 DRAWING='@BASEBOARD_FAB2_LIB.BASEBOARD_FAB2(SCH_1):PAGE150',
 WATTAGE='1/16W',
 TOLERANCE='1%',
 SEC_TYPE='0402',
 MATERIAL='CHIP',
 BOM_COST='SM_CONTROLLER',
 PHYS_PAGE='150',
 XY='(1850,-600)',
 ROT='0',
 VER='1',
 VALUE='4.75K',
 PACK_TYPE='0402',
 PART_NUMBER='G21796-072',
 LOCATION='R25W100',
 ROOM='BMC',
 SEC='1',
 CDS_LIB='mstr_discrete',
 CDS_PART_NAME='RES_0402-4.75K,1%,1/16W,CHIP,GA',
 PRIM_FILE='./archive_libs/mstr_discrete/res/chips/chips.prt';

PART_NAME
 R25W101 'RES_0402-4.75K,1%,1/16W,EMPTY,A':
 ROOM='BMC';

SECTION_NUMBER 1
 '@BASEBOARD_FAB2_LIB.BASEBOARD_FAB2(SCH_1):PAGE150_I241@MSTR_DISCRETE.RES(CHIPS)':
 C_PATH='@baseboard_fab2_lib.baseboard_fab2(sch_1):page150_i241@mstr_discrete.re~
s(chips)',
 P_PATH='@baseboard_fab2_lib.baseboard_fab2(sch_1):page150_i241@mstr_discrete.re~
s(chips)',
 PATH='I241',
 DRAWING='@BASEBOARD_FAB2_LIB.BASEBOARD_FAB2(SCH_1):PAGE150',
 WATTAGE='1/16W',
 TOLERANCE='1%',
 SEC_TYPE='0402',
 MATERIAL='EMPTY',
 BOM_COST='SM_CONTROLLER',
 PHYS_PAGE='150',
 XY='(1850,-800)',
 ROT='0',
 VER='1',
 VALUE='4.75K',
 PACK_TYPE='0402',
 PART_NUMBER='G21796-072',
 LOCATION='R25W101',
 ROOM='BMC',
 SEC='1',
 CDS_LIB='mstr_discrete',
 CDS_PART_NAME='RES_0402-4.75K,1%,1/16W,EMPTY,A',
 PRIM_FILE='./archive_libs/mstr_discrete/res/chips/chips.prt';

PART_NAME
 R25W102 'RES_0402-4.75K,1%,1/16W,EMPTY,A':
 ROOM='BMC';

SECTION_NUMBER 1
 '@BASEBOARD_FAB2_LIB.BASEBOARD_FAB2(SCH_1):PAGE150_I239@MSTR_DISCRETE.RES(CHIPS)':
 C_PATH='@baseboard_fab2_lib.baseboard_fab2(sch_1):page150_i239@mstr_discrete.re~
s(chips)',
 P_PATH='@baseboard_fab2_lib.baseboard_fab2(sch_1):page150_i239@mstr_discrete.re~
s(chips)',
 PATH='I239',
 DRAWING='@BASEBOARD_FAB2_LIB.BASEBOARD_FAB2(SCH_1):PAGE150',
 WATTAGE='1/16W',
 TOLERANCE='1%',
 SEC_TYPE='0402',
 MATERIAL='EMPTY',
 BOM_COST='SM_CONTROLLER',
 PHYS_PAGE='150',
 XY='(1850,-1000)',
 ROT='0',
 VER='1',
 VALUE='4.75K',
 PACK_TYPE='0402',
 PART_NUMBER='G21796-072',
 LOCATION='R25W102',
 ROOM='BMC',
 SEC='1',
 CDS_LIB='mstr_discrete',
 CDS_PART_NAME='RES_0402-4.75K,1%,1/16W,EMPTY,A',
 PRIM_FILE='./archive_libs/mstr_discrete/res/chips/chips.prt';

PART_NAME
 R25W103 'RES_0402-4.75K,1%,1/16W,EMPTY,A':
 ROOM='BMC';

SECTION_NUMBER 1
 '@BASEBOARD_FAB2_LIB.BASEBOARD_FAB2(SCH_1):PAGE150_I214@MSTR_DISCRETE.RES(CHIPS)':
 C_PATH='@baseboard_fab2_lib.baseboard_fab2(sch_1):page150_i214@mstr_discrete.re~
s(chips)',
 P_PATH='@baseboard_fab2_lib.baseboard_fab2(sch_1):page150_i214@mstr_discrete.re~
s(chips)',
 PATH='I214',
 DRAWING='@BASEBOARD_FAB2_LIB.BASEBOARD_FAB2(SCH_1):PAGE150',
 WATTAGE='1/16W',
 TOLERANCE='1%',
 SEC_TYPE='0402',
 MATERIAL='EMPTY',
 BOM_COST='SM_CONTROLLER',
 PHYS_PAGE='150',
 XY='(1850,-1200)',
 ROT='0',
 VER='1',
 VALUE='4.75K',
 PACK_TYPE='0402',
 PART_NUMBER='G21796-072',
 LOCATION='R25W103',
 ROOM='BMC',
 SEC='1',
 CDS_LIB='mstr_discrete',
 CDS_PART_NAME='RES_0402-4.75K,1%,1/16W,EMPTY,A',
 PRIM_FILE='./archive_libs/mstr_discrete/res/chips/chips.prt';

PART_NAME
 R25W104 'RES_0402-4.75K,1%,1/16W,CHIP,GA':
 ROOM='BMC';

SECTION_NUMBER 1
 '@BASEBOARD_FAB2_LIB.BASEBOARD_FAB2(SCH_1):PAGE150_I215@MSTR_DISCRETE.RES(CHIPS)':
 C_PATH='@baseboard_fab2_lib.baseboard_fab2(sch_1):page150_i215@mstr_discrete.re~
s(chips)',
 P_PATH='@baseboard_fab2_lib.baseboard_fab2(sch_1):page150_i215@mstr_discrete.re~
s(chips)',
 PATH='I215',
 DRAWING='@BASEBOARD_FAB2_LIB.BASEBOARD_FAB2(SCH_1):PAGE150',
 WATTAGE='1/16W',
 TOLERANCE='1%',
 SEC_TYPE='0402',
 MATERIAL='CHIP',
 BOM_COST='SM_CONTROLLER',
 PHYS_PAGE='150',
 XY='(1850,-1400)',
 ROT='0',
 VER='1',
 VALUE='4.75K',
 PACK_TYPE='0402',
 PART_NUMBER='G21796-072',
 LOCATION='R25W104',
 ROOM='BMC',
 SEC='1',
 CDS_LIB='mstr_discrete',
 CDS_PART_NAME='RES_0402-4.75K,1%,1/16W,CHIP,GA',
 PRIM_FILE='./archive_libs/mstr_discrete/res/chips/chips.prt';

PART_NAME
 R25W105 'RES_0402-4.75K,1%,1/16W,EMPTY,A':
 ROOM='BMC';

SECTION_NUMBER 1
 '@BASEBOARD_FAB2_LIB.BASEBOARD_FAB2(SCH_1):PAGE150_I196@MSTR_DISCRETE.RES(CHIPS)':
 C_PATH='@baseboard_fab2_lib.baseboard_fab2(sch_1):page150_i196@mstr_discrete.re~
s(chips)',
 P_PATH='@baseboard_fab2_lib.baseboard_fab2(sch_1):page150_i196@mstr_discrete.re~
s(chips)',
 PATH='I196',
 DRAWING='@BASEBOARD_FAB2_LIB.BASEBOARD_FAB2(SCH_1):PAGE150',
 WATTAGE='1/16W',
 TOLERANCE='1%',
 SEC_TYPE='0402',
 MATERIAL='EMPTY',
 BOM_COST='SM_CONTROLLER',
 PHYS_PAGE='150',
 XY='(-600,-400)',
 ROT='0',
 VER='1',
 VALUE='4.75K',
 PACK_TYPE='0402',
 PART_NUMBER='G21796-072',
 LOCATION='R25W105',
 ROOM='BMC',
 SEC='1',
 CDS_LIB='mstr_discrete',
 CDS_PART_NAME='RES_0402-4.75K,1%,1/16W,EMPTY,A',
 PRIM_FILE='./archive_libs/mstr_discrete/res/chips/chips.prt';

PART_NAME
 R25W106 'RES_0402-4.75K,1%,1/16W,EMPTY,A':
 ROOM='BMC';

SECTION_NUMBER 1
 '@BASEBOARD_FAB2_LIB.BASEBOARD_FAB2(SCH_1):PAGE150_I175@MSTR_DISCRETE.RES(CHIPS)':
 C_PATH='@baseboard_fab2_lib.baseboard_fab2(sch_1):page150_i175@mstr_discrete.re~
s(chips)',
 P_PATH='@baseboard_fab2_lib.baseboard_fab2(sch_1):page150_i175@mstr_discrete.re~
s(chips)',
 PATH='I175',
 DRAWING='@BASEBOARD_FAB2_LIB.BASEBOARD_FAB2(SCH_1):PAGE150',
 WATTAGE='1/16W',
 TOLERANCE='1%',
 SEC_TYPE='0402',
 MATERIAL='EMPTY',
 BOM_COST='SM_CONTROLLER',
 PHYS_PAGE='150',
 XY='(-600,-1100)',
 ROT='0',
 VER='1',
 VALUE='4.75K',
 PACK_TYPE='0402',
 PART_NUMBER='G21796-072',
 LOCATION='R25W106',
 ROOM='BMC',
 SEC='1',
 CDS_LIB='mstr_discrete',
 CDS_PART_NAME='RES_0402-4.75K,1%,1/16W,EMPTY,A',
 PRIM_FILE='./archive_libs/mstr_discrete/res/chips/chips.prt';

PART_NAME
 R25W107 'RES_0402-4.75K,1%,1/16W,CHIP,GA':
 ROOM='BMC';

SECTION_NUMBER 1
 '@BASEBOARD_FAB2_LIB.BASEBOARD_FAB2(SCH_1):PAGE150_I190@MSTR_DISCRETE.RES(CHIPS)':
 C_PATH='@baseboard_fab2_lib.baseboard_fab2(sch_1):page150_i190@mstr_discrete.re~
s(chips)',
 P_PATH='@baseboard_fab2_lib.baseboard_fab2(sch_1):page150_i190@mstr_discrete.re~
s(chips)',
 PATH='I190',
 DRAWING='@BASEBOARD_FAB2_LIB.BASEBOARD_FAB2(SCH_1):PAGE150',
 WATTAGE='1/16W',
 TOLERANCE='1%',
 SEC_TYPE='0402',
 MATERIAL='CHIP',
 BOM_COST='SM_CONTROLLER',
 PHYS_PAGE='150',
 XY='(-600,-1900)',
 ROT='0',
 VER='1',
 VALUE='4.75K',
 PACK_TYPE='0402',
 PART_NUMBER='G21796-072',
 LOCATION='R25W107',
 ROOM='BMC',
 SEC='1',
 CDS_LIB='mstr_discrete',
 CDS_PART_NAME='RES_0402-4.75K,1%,1/16W,CHIP,GA',
 PRIM_FILE='./archive_libs/mstr_discrete/res/chips/chips.prt';

PART_NAME
 R25W108 'RES_0402-4.75K,1%,1/16W,EMPTY,A':
 ROOM='BMC';

SECTION_NUMBER 1
 '@BASEBOARD_FAB2_LIB.BASEBOARD_FAB2(SCH_1):PAGE150_I191@MSTR_DISCRETE.RES(CHIPS)':
 C_PATH='@baseboard_fab2_lib.baseboard_fab2(sch_1):page150_i191@mstr_discrete.re~
s(chips)',
 P_PATH='@baseboard_fab2_lib.baseboard_fab2(sch_1):page150_i191@mstr_discrete.re~
s(chips)',
 PATH='I191',
 DRAWING='@BASEBOARD_FAB2_LIB.BASEBOARD_FAB2(SCH_1):PAGE150',
 WATTAGE='1/16W',
 TOLERANCE='1%',
 SEC_TYPE='0402',
 MATERIAL='EMPTY',
 BOM_COST='SM_CONTROLLER',
 PHYS_PAGE='150',
 XY='(-600,-2100)',
 ROT='0',
 VER='1',
 VALUE='4.75K',
 PACK_TYPE='0402',
 PART_NUMBER='G21796-072',
 LOCATION='R25W108',
 ROOM='BMC',
 SEC='1',
 CDS_LIB='mstr_discrete',
 CDS_PART_NAME='RES_0402-4.75K,1%,1/16W,EMPTY,A',
 PRIM_FILE='./archive_libs/mstr_discrete/res/chips/chips.prt';

PART_NAME
 R25W109 'RES_0402-4.75K,1%,1/16W,CHIP,GA':
 ROOM='BMC';

SECTION_NUMBER 1
 '@BASEBOARD_FAB2_LIB.BASEBOARD_FAB2(SCH_1):PAGE150_I236@MSTR_DISCRETE.RES(CHIPS)':
 C_PATH='@baseboard_fab2_lib.baseboard_fab2(sch_1):page150_i236@mstr_discrete.re~
s(chips)',
 P_PATH='@baseboard_fab2_lib.baseboard_fab2(sch_1):page150_i236@mstr_discrete.re~
s(chips)',
 PATH='I236',
 DRAWING='@BASEBOARD_FAB2_LIB.BASEBOARD_FAB2(SCH_1):PAGE150',
 WATTAGE='1/16W',
 TOLERANCE='1%',
 SEC_TYPE='0402',
 MATERIAL='CHIP',
 BOM_COST='SM_CONTROLLER',
 PHYS_PAGE='150',
 XY='(1850,0)',
 ROT='0',
 VER='1',
 VALUE='4.75K',
 PACK_TYPE='0402',
 PART_NUMBER='G21796-072',
 LOCATION='R25W109',
 ROOM='BMC',
 SEC='1',
 CDS_LIB='mstr_discrete',
 CDS_PART_NAME='RES_0402-4.75K,1%,1/16W,CHIP,GA',
 PRIM_FILE='./archive_libs/mstr_discrete/res/chips/chips.prt';

PART_NAME
 R25W110 'RES_0402-4.75K,1%,1/16W,EMPTY,A':
 ROOM='BMC';

SECTION_NUMBER 1
 '@BASEBOARD_FAB2_LIB.BASEBOARD_FAB2(SCH_1):PAGE150_I233@MSTR_DISCRETE.RES(CHIPS)':
 C_PATH='@baseboard_fab2_lib.baseboard_fab2(sch_1):page150_i233@mstr_discrete.re~
s(chips)',
 P_PATH='@baseboard_fab2_lib.baseboard_fab2(sch_1):page150_i233@mstr_discrete.re~
s(chips)',
 PATH='I233',
 DRAWING='@BASEBOARD_FAB2_LIB.BASEBOARD_FAB2(SCH_1):PAGE150',
 WATTAGE='1/16W',
 TOLERANCE='1%',
 SEC_TYPE='0402',
 MATERIAL='EMPTY',
 BOM_COST='SM_CONTROLLER',
 PHYS_PAGE='150',
 XY='(1850,400)',
 ROT='0',
 VER='1',
 VALUE='4.75K',
 PACK_TYPE='0402',
 PART_NUMBER='G21796-072',
 LOCATION='R25W110',
 ROOM='BMC',
 SEC='1',
 CDS_LIB='mstr_discrete',
 CDS_PART_NAME='RES_0402-4.75K,1%,1/16W,EMPTY,A',
 PRIM_FILE='./archive_libs/mstr_discrete/res/chips/chips.prt';

PART_NAME
 R25W111 'RES_0402-4.75K,1%,1/16W,EMPTY,A':
 ROOM='BMC';

SECTION_NUMBER 1
 '@BASEBOARD_FAB2_LIB.BASEBOARD_FAB2(SCH_1):PAGE150_I180@MSTR_DISCRETE.RES(CHIPS)':
 C_PATH='@baseboard_fab2_lib.baseboard_fab2(sch_1):page150_i180@mstr_discrete.re~
s(chips)',
 P_PATH='@baseboard_fab2_lib.baseboard_fab2(sch_1):page150_i180@mstr_discrete.re~
s(chips)',
 PATH='I180',
 DRAWING='@BASEBOARD_FAB2_LIB.BASEBOARD_FAB2(SCH_1):PAGE150',
 WATTAGE='1/16W',
 TOLERANCE='1%',
 SEC_TYPE='0402',
 MATERIAL='EMPTY',
 BOM_COST='SM_CONTROLLER',
 PHYS_PAGE='150',
 XY='(-600,-1500)',
 ROT='0',
 VER='1',
 VALUE='4.75K',
 PACK_TYPE='0402',
 PART_NUMBER='G21796-072',
 LOCATION='R25W111',
 ROOM='BMC',
 SEC='1',
 CDS_LIB='mstr_discrete',
 CDS_PART_NAME='RES_0402-4.75K,1%,1/16W,EMPTY,A',
 PRIM_FILE='./archive_libs/mstr_discrete/res/chips/chips.prt';

PART_NAME
 R25W112 'RES_0402-4.75K,1%,1/16W,EMPTY,A':
 ROOM='BMC';

SECTION_NUMBER 1
 '@BASEBOARD_FAB2_LIB.BASEBOARD_FAB2(SCH_1):PAGE150_I228@MSTR_DISCRETE.RES(CHIPS)':
 C_PATH='@baseboard_fab2_lib.baseboard_fab2(sch_1):page150_i228@mstr_discrete.re~
s(chips)',
 P_PATH='@baseboard_fab2_lib.baseboard_fab2(sch_1):page150_i228@mstr_discrete.re~
s(chips)',
 PATH='I228',
 DRAWING='@BASEBOARD_FAB2_LIB.BASEBOARD_FAB2(SCH_1):PAGE150',
 WATTAGE='1/16W',
 TOLERANCE='1%',
 SEC_TYPE='0402',
 MATERIAL='EMPTY',
 BOM_COST='SM_CONTROLLER',
 PHYS_PAGE='150',
 XY='(-600,-3100)',
 ROT='0',
 VER='1',
 VALUE='4.75K',
 PACK_TYPE='0402',
 PART_NUMBER='G21796-072',
 LOCATION='R25W112',
 ROOM='BMC',
 SEC='1',
 CDS_LIB='mstr_discrete',
 CDS_PART_NAME='RES_0402-4.75K,1%,1/16W,EMPTY,A',
 PRIM_FILE='./archive_libs/mstr_discrete/res/chips/chips.prt';

PART_NAME
 R25W113 'RES_0402-4.75K,1%,1/16W,EMPTY,A':
 ROOM='BMC';

SECTION_NUMBER 1
 '@BASEBOARD_FAB2_LIB.BASEBOARD_FAB2(SCH_1):PAGE150_I230@MSTR_DISCRETE.RES(CHIPS)':
 C_PATH='@baseboard_fab2_lib.baseboard_fab2(sch_1):page150_i230@mstr_discrete.re~
s(chips)',
 P_PATH='@baseboard_fab2_lib.baseboard_fab2(sch_1):page150_i230@mstr_discrete.re~
s(chips)',
 PATH='I230',
 DRAWING='@BASEBOARD_FAB2_LIB.BASEBOARD_FAB2(SCH_1):PAGE150',
 WATTAGE='1/16W',
 TOLERANCE='1%',
 SEC_TYPE='0402',
 MATERIAL='EMPTY',
 BOM_COST='SM_CONTROLLER',
 PHYS_PAGE='150',
 XY='(-600,-3500)',
 ROT='0',
 VER='1',
 VALUE='4.75K',
 PACK_TYPE='0402',
 PART_NUMBER='G21796-072',
 LOCATION='R25W113',
 ROOM='BMC',
 SEC='1',
 CDS_LIB='mstr_discrete',
 CDS_PART_NAME='RES_0402-4.75K,1%,1/16W,EMPTY,A',
 PRIM_FILE='./archive_libs/mstr_discrete/res/chips/chips.prt';

PART_NAME
 R25W114 'RES_0402-4.75K,1%,1/16W,EMPTY,A':
 ROOM='BMC';

SECTION_NUMBER 1
 '@BASEBOARD_FAB2_LIB.BASEBOARD_FAB2(SCH_1):PAGE150_I218@MSTR_DISCRETE.RES(CHIPS)':
 C_PATH='@baseboard_fab2_lib.baseboard_fab2(sch_1):page150_i218@mstr_discrete.re~
s(chips)',
 P_PATH='@baseboard_fab2_lib.baseboard_fab2(sch_1):page150_i218@mstr_discrete.re~
s(chips)',
 PATH='I218',
 DRAWING='@BASEBOARD_FAB2_LIB.BASEBOARD_FAB2(SCH_1):PAGE150',
 WATTAGE='1/16W',
 TOLERANCE='1%',
 SEC_TYPE='0402',
 MATERIAL='EMPTY',
 BOM_COST='SM_CONTROLLER',
 PHYS_PAGE='150',
 XY='(-600,-2500)',
 ROT='0',
 VER='1',
 VALUE='4.75K',
 PACK_TYPE='0402',
 PART_NUMBER='G21796-072',
 LOCATION='R25W114',
 ROOM='BMC',
 SEC='1',
 CDS_LIB='mstr_discrete',
 CDS_PART_NAME='RES_0402-4.75K,1%,1/16W,EMPTY,A',
 PRIM_FILE='./archive_libs/mstr_discrete/res/chips/chips.prt';

PART_NAME
 R25W115 'RES_0402-4.75K,1%,1/16W,EMPTY,A':
 ROOM='BMC';

SECTION_NUMBER 1
 '@BASEBOARD_FAB2_LIB.BASEBOARD_FAB2(SCH_1):PAGE150_I242@MSTR_DISCRETE.RES(CHIPS)':
 C_PATH='@baseboard_fab2_lib.baseboard_fab2(sch_1):page150_i242@mstr_discrete.re~
s(chips)',
 P_PATH='@baseboard_fab2_lib.baseboard_fab2(sch_1):page150_i242@mstr_discrete.re~
s(chips)',
 PATH='I242',
 DRAWING='@BASEBOARD_FAB2_LIB.BASEBOARD_FAB2(SCH_1):PAGE150',
 WATTAGE='1/16W',
 TOLERANCE='1%',
 SEC_TYPE='0402',
 MATERIAL='EMPTY',
 BOM_COST='SM_CONTROLLER',
 PHYS_PAGE='150',
 XY='(-600,-2900)',
 ROT='0',
 VER='1',
 VALUE='4.75K',
 PACK_TYPE='0402',
 PART_NUMBER='G21796-072',
 LOCATION='R25W115',
 ROOM='BMC',
 SEC='1',
 CDS_LIB='mstr_discrete',
 CDS_PART_NAME='RES_0402-4.75K,1%,1/16W,EMPTY,A',
 PRIM_FILE='./archive_libs/mstr_discrete/res/chips/chips.prt';

PART_NAME
 R25W116 'RES_0402-3.32K,1%,1/16W,EMPTY,A':
 ROOM='NIC_SPRV';

SECTION_NUMBER 1
 '@BASEBOARD_FAB2_LIB.BASEBOARD_FAB2(SCH_1):PAGE150_I189@MSTR_DISCRETE.RES(CHIPS)':
 C_PATH='@baseboard_fab2_lib.baseboard_fab2(sch_1):page150_i189@mstr_discrete.re~
s(chips)',
 P_PATH='@baseboard_fab2_lib.baseboard_fab2(sch_1):page150_i189@mstr_discrete.re~
s(chips)',
 PATH='I189',
 DRAWING='@BASEBOARD_FAB2_LIB.BASEBOARD_FAB2(SCH_1):PAGE150',
 WATTAGE='1/16W',
 TOLERANCE='1%',
 SEC_TYPE='0402',
 MATERIAL='EMPTY',
 BOM_COST='NT_GBE_BASE',
 PHYS_PAGE='150',
 XY='(-600,-850)',
 ROT='1',
 VER='2',
 VALUE='3.32K',
 PACK_TYPE='0402',
 PART_NUMBER='G21796-027',
 LOCATION='R25W116',
 ROOM='NIC_SPRV',
 SEC='1',
 CDS_LIB='mstr_discrete',
 CDS_PART_NAME='RES_0402-3.32K,1%,1/16W,EMPTY,A',
 PRIM_FILE='./archive_libs/mstr_discrete/res/chips/chips.prt';

PART_NAME
 R25W117 'RES_0402-240,1.0%,1/16W,CHIP,GA':
 ROOM='BMC_MEMORY';

SECTION_NUMBER 1
 '@BASEBOARD_FAB2_LIB.BASEBOARD_FAB2(SCH_1):PAGE151_I101@MSTR_DISCRETE.RES(CHIPS)':
 C_PATH='@baseboard_fab2_lib.baseboard_fab2(sch_1):page151_i101@mstr_discrete.re~
s(chips)',
 P_PATH='@baseboard_fab2_lib.baseboard_fab2(sch_1):page151_i101@mstr_discrete.re~
s(chips)',
 PATH='I101',
 DRAWING='@BASEBOARD_FAB2_LIB.BASEBOARD_FAB2(SCH_1):PAGE151',
 WATTAGE='1/16W',
 TOLERANCE='1.0%',
 SEC_TYPE='0402',
 MATERIAL='CHIP',
 BOM_COST='SM_MEM',
 PHYS_PAGE='151',
 XY='(950,-100)',
 ROT='0',
 VER='2',
 VALUE='240',
 PACK_TYPE='0402',
 PART_NUMBER='G21796-294',
 LOCATION='R25W117',
 ROOM='BMC_MEMORY',
 SEC='1',
 CDS_LIB='mstr_discrete',
 CDS_PART_NAME='RES_0402-240,1.0%,1/16W,CHIP,GA',
 PRIM_FILE='./archive_libs/mstr_discrete/res/chips/chips.prt';

PART_NAME
 R25W118 'RES_0402-0.0,5%,1/16W,CHIP,G21A':
 ROOM='HOT_SWAP';

SECTION_NUMBER 1
 '@BASEBOARD_FAB2_LIB.BASEBOARD_FAB2(SCH_1):PAGE151_I211@MSTR_DISCRETE.RES(CHIPS)':
 C_PATH='@baseboard_fab2_lib.baseboard_fab2(sch_1):page151_i211@mstr_discrete.re~
s(chips)',
 P_PATH='@baseboard_fab2_lib.baseboard_fab2(sch_1):page151_i211@mstr_discrete.re~
s(chips)',
 PATH='I211',
 DRAWING='@BASEBOARD_FAB2_LIB.BASEBOARD_FAB2(SCH_1):PAGE151',
 WATTAGE='1/16W',
 TOLERANCE='5%',
 SEC_TYPE='0402',
 MATERIAL='CHIP',
 PHYS_PAGE='151',
 XY='(-150,-1950)',
 ROT='5',
 VER='1',
 VALUE='0.0',
 PACK_TYPE='0402',
 PART_NUMBER='G21497-005',
 LOCATION='R25W118',
 ROOM='HOT_SWAP',
 SEC='1',
 CDS_LIB='mstr_discrete',
 CDS_PART_NAME='RES_0402-0.0,5%,1/16W,CHIP,G21A',
 PRIM_FILE='./archive_libs/mstr_discrete/res/chips/chips.prt';

PART_NAME
 R25W119 'RES_0402-4.75K,1%,1/16W,EMPTY,A':
 ROOM='SB_SPI',
 NO_XNET_CONNECTION='1';

SECTION_NUMBER 1
 '@BASEBOARD_FAB2_LIB.BASEBOARD_FAB2(SCH_1):PAGE151_I210@MSTR_DISCRETE.RES(CHIPS)':
 C_PATH='@baseboard_fab2_lib.baseboard_fab2(sch_1):page151_i210@mstr_discrete.re~
s(chips)',
 P_PATH='@baseboard_fab2_lib.baseboard_fab2(sch_1):page151_i210@mstr_discrete.re~
s(chips)',
 PATH='I210',
 DRAWING='@BASEBOARD_FAB2_LIB.BASEBOARD_FAB2(SCH_1):PAGE151',
 WATTAGE='1/16W',
 TOLERANCE='1%',
 SEC_TYPE='0402',
 MATERIAL='EMPTY',
 BOM_COST='MIO_BIOS_MEM',
 NO_XNET_CONNECTION='1',
 PHYS_PAGE='151',
 XY='(-150,-1500)',
 ROT='2',
 VER='2',
 VALUE='4.75K',
 PACK_TYPE='0402',
 PART_NUMBER='G21796-072',
 LOCATION='R25W119',
 ROOM='SB_SPI',
 SEC='1',
 CDS_LIB='mstr_discrete',
 CDS_PART_NAME='RES_0402-4.75K,1%,1/16W,EMPTY,A',
 PRIM_FILE='./archive_libs/mstr_discrete/res/chips/chips.prt';

PART_NAME
 R25W120 'RES_0603-0,5.0%,1/10W,CHIP,G22A':
 ROOM='NIC_SPRV';

SECTION_NUMBER 1
 '@BASEBOARD_FAB2_LIB.BASEBOARD_FAB2(SCH_1):PAGE149_I91@MSTR_DISCRETE.RES(CHIPS)':
 C_PATH='@baseboard_fab2_lib.baseboard_fab2(sch_1):page149_i91@mstr_discrete.res~
(chips)',
 P_PATH='@baseboard_fab2_lib.baseboard_fab2(sch_1):page149_i91@mstr_discrete.res~
(chips)',
 PATH='I91',
 DRAWING='@BASEBOARD_FAB2_LIB.BASEBOARD_FAB2(SCH_1):PAGE149',
 WATTAGE='1/10W',
 TOLERANCE='5.0%',
 MATERIAL='CHIP',
 BOM_COST='NT_GBE_BASE',
 PHYS_PAGE='149',
 XY='(4100,5500)',
 ROT='0',
 VER='1',
 VALUE='0',
 PACK_TYPE='0603',
 PART_NUMBER='G22178-002',
 LOCATION='R25W120',
 ROOM='NIC_SPRV',
 CDS_LIB='mstr_discrete',
 CDS_PART_NAME='RES_0603-0,5.0%,1/10W,CHIP,G22A',
 PRIM_FILE='./archive_libs/mstr_discrete/res/chips/chips.prt';

PART_NAME
 R25W121 'RES_0402-20.0,1%,1/16W,CHIP,G2A':
 ROOM='SMB_PE_HP_CPU1';

SECTION_NUMBER 1
 '@BASEBOARD_FAB2_LIB.BASEBOARD_FAB2(SCH_1):PAGE145_I163@MSTR_DISCRETE.RES(CHIPS)':
 C_PATH='@baseboard_fab2_lib.baseboard_fab2(sch_1):page145_i163@mstr_discrete.re~
s(chips)',
 P_PATH='@baseboard_fab2_lib.baseboard_fab2(sch_1):page145_i163@mstr_discrete.re~
s(chips)',
 PATH='I163',
 DRAWING='@BASEBOARD_FAB2_LIB.BASEBOARD_FAB2(SCH_1):PAGE145',
 WATTAGE='1/16W',
 TOLERANCE='1%',
 SEC_TYPE='0402',
 MATERIAL='CHIP',
 PHYS_PAGE='145',
 XY='(-6450,-1850)',
 ROT='0',
 VER='1',
 VALUE='20.0',
 PACK_TYPE='0402',
 PART_NUMBER='G21796-173',
 LOCATION='R25W121',
 ROOM='SMB_PE_HP_CPU1',
 SEC='1',
 CDS_LIB='mstr_discrete',
 CDS_PART_NAME='RES_0402-20.0,1%,1/16W,CHIP,G2A',
 PRIM_FILE='./archive_libs/mstr_discrete/res/chips/chips.prt';

PART_NAME
 R25W122 'RES_0402-20.0,1%,1/16W,CHIP,G2A':
 ROOM='SMB_PE_HP_CPU1';

SECTION_NUMBER 1
 '@BASEBOARD_FAB2_LIB.BASEBOARD_FAB2(SCH_1):PAGE145_I164@MSTR_DISCRETE.RES(CHIPS)':
 C_PATH='@baseboard_fab2_lib.baseboard_fab2(sch_1):page145_i164@mstr_discrete.re~
s(chips)',
 P_PATH='@baseboard_fab2_lib.baseboard_fab2(sch_1):page145_i164@mstr_discrete.re~
s(chips)',
 PATH='I164',
 DRAWING='@BASEBOARD_FAB2_LIB.BASEBOARD_FAB2(SCH_1):PAGE145',
 WATTAGE='1/16W',
 TOLERANCE='1%',
 SEC_TYPE='0402',
 MATERIAL='CHIP',
 PHYS_PAGE='145',
 XY='(-6450,-1900)',
 ROT='0',
 VER='1',
 VALUE='20.0',
 PACK_TYPE='0402',
 PART_NUMBER='G21796-173',
 LOCATION='R25W122',
 ROOM='SMB_PE_HP_CPU1',
 SEC='1',
 CDS_LIB='mstr_discrete',
 CDS_PART_NAME='RES_0402-20.0,1%,1/16W,CHIP,G2A',
 PRIM_FILE='./archive_libs/mstr_discrete/res/chips/chips.prt';

PART_NAME
 R25W123 'RES_0402-150.0,1%,1/16W,CHIP,GA':
 GROUP='AST2500',
 ROOM='PROC_SIDEBAND';

SECTION_NUMBER 1
 '@BASEBOARD_FAB2_LIB.BASEBOARD_FAB2(SCH_1):PAGE144_I139@MSTR_DISCRETE.RES(CHIPS)':
 C_PATH='@baseboard_fab2_lib.baseboard_fab2(sch_1):page144_i139@mstr_discrete.re~
s(chips)',
 P_PATH='@baseboard_fab2_lib.baseboard_fab2(sch_1):page144_i139@mstr_discrete.re~
s(chips)',
 PATH='I139',
 DRAWING='@BASEBOARD_FAB2_LIB.BASEBOARD_FAB2(SCH_1):PAGE144',
 WATTAGE='1/16W',
 TOLERANCE='1%',
 SEC_TYPE='0402',
 MATERIAL='CHIP',
 BOM_COST='PROC_SIDEBAND',
 PHYS_PAGE='144',
 XY='(-2800,-4550)',
 ROT='2',
 VER='2',
 VALUE='150.0',
 PACK_TYPE='0402',
 PART_NUMBER='G21796-009',
 LOCATION='R25W123',
 ROOM='PROC_SIDEBAND',
 GROUP='AST2500',
 SEC='1',
 CDS_LIB='mstr_discrete',
 CDS_PART_NAME='RES_0402-150.0,1%,1/16W,CHIP,GA',
 PRIM_FILE='./archive_libs/mstr_discrete/res/chips/chips.prt';

PART_NAME
 R25W124 'RES_0402-150.0,1%,1/16W,CHIP,GA':
 GROUP='AST2500',
 ROOM='PROC_SIDEBAND';

SECTION_NUMBER 1
 '@BASEBOARD_FAB2_LIB.BASEBOARD_FAB2(SCH_1):PAGE144_I140@MSTR_DISCRETE.RES(CHIPS)':
 C_PATH='@baseboard_fab2_lib.baseboard_fab2(sch_1):page144_i140@mstr_discrete.re~
s(chips)',
 P_PATH='@baseboard_fab2_lib.baseboard_fab2(sch_1):page144_i140@mstr_discrete.re~
s(chips)',
 PATH='I140',
 DRAWING='@BASEBOARD_FAB2_LIB.BASEBOARD_FAB2(SCH_1):PAGE144',
 WATTAGE='1/16W',
 TOLERANCE='1%',
 SEC_TYPE='0402',
 MATERIAL='CHIP',
 BOM_COST='PROC_SIDEBAND',
 PHYS_PAGE='144',
 XY='(-2450,-4550)',
 ROT='2',
 VER='2',
 VALUE='150.0',
 PACK_TYPE='0402',
 PART_NUMBER='G21796-009',
 LOCATION='R25W124',
 ROOM='PROC_SIDEBAND',
 GROUP='AST2500',
 SEC='1',
 CDS_LIB='mstr_discrete',
 CDS_PART_NAME='RES_0402-150.0,1%,1/16W,CHIP,GA',
 PRIM_FILE='./archive_libs/mstr_discrete/res/chips/chips.prt';

PART_NAME
 R25W125 'RES_0402-150.0,1%,1/16W,CHIP,GA':
 GROUP='AST2500',
 ROOM='PROC_SIDEBAND';

SECTION_NUMBER 1
 '@BASEBOARD_FAB2_LIB.BASEBOARD_FAB2(SCH_1):PAGE144_I141@MSTR_DISCRETE.RES(CHIPS)':
 C_PATH='@baseboard_fab2_lib.baseboard_fab2(sch_1):page144_i141@mstr_discrete.re~
s(chips)',
 P_PATH='@baseboard_fab2_lib.baseboard_fab2(sch_1):page144_i141@mstr_discrete.re~
s(chips)',
 PATH='I141',
 DRAWING='@BASEBOARD_FAB2_LIB.BASEBOARD_FAB2(SCH_1):PAGE144',
 WATTAGE='1/16W',
 TOLERANCE='1%',
 SEC_TYPE='0402',
 MATERIAL='CHIP',
 BOM_COST='PROC_SIDEBAND',
 PHYS_PAGE='144',
 XY='(-2100,-4550)',
 ROT='2',
 VER='2',
 VALUE='150.0',
 PACK_TYPE='0402',
 PART_NUMBER='G21796-009',
 LOCATION='R25W125',
 ROOM='PROC_SIDEBAND',
 GROUP='AST2500',
 SEC='1',
 CDS_LIB='mstr_discrete',
 CDS_PART_NAME='RES_0402-150.0,1%,1/16W,CHIP,GA',
 PRIM_FILE='./archive_libs/mstr_discrete/res/chips/chips.prt';

PART_NAME
 R25W126 'RES_0402-150.0,1%,1/16W,CHIP,GA':
 GROUP='AST2500',
 ROOM='PROC_SIDEBAND';

SECTION_NUMBER 1
 '@BASEBOARD_FAB2_LIB.BASEBOARD_FAB2(SCH_1):PAGE255_I26@MSTR_DISCRETE.RES(CHIPS)':
 C_PATH='@baseboard_fab2_lib.baseboard_fab2(sch_1):page255_i26@mstr_discrete.res~
(chips)',
 P_PATH='@baseboard_fab2_lib.baseboard_fab2(sch_1):page252_i26@mstr_discrete.res~
(chips)',
 PATH='I26',
 DRAWING='@BASEBOARD_FAB2_LIB.BASEBOARD_FAB2(SCH_1):PAGE255',
 WATTAGE='1/16W',
 TOLERANCE='1%',
 MATERIAL='CHIP',
 BOM_COST='PROC_SIDEBAND',
 PHYS_PAGE='252',
 XY='(-7050,2550)',
 ROT='2',
 VER='2',
 VALUE='150.0',
 PACK_TYPE='0402',
 PART_NUMBER='G21796-009',
 LOCATION='R25W126',
 ROOM='PROC_SIDEBAND',
 GROUP='AST2500',
 CDS_LIB='mstr_discrete',
 CDS_PART_NAME='RES_0402-150.0,1%,1/16W,CHIP,GA',
 PRIM_FILE='./archive_libs/mstr_discrete/res/chips/chips.prt';

PART_NAME
 R25W127 'RES_0402-150.0,1%,1/16W,CHIP,GA':
 GROUP='AST2500',
 ROOM='PROC_SIDEBAND';

SECTION_NUMBER 1
 '@BASEBOARD_FAB2_LIB.BASEBOARD_FAB2(SCH_1):PAGE255_I24@MSTR_DISCRETE.RES(CHIPS)':
 C_PATH='@baseboard_fab2_lib.baseboard_fab2(sch_1):page255_i24@mstr_discrete.res~
(chips)',
 P_PATH='@baseboard_fab2_lib.baseboard_fab2(sch_1):page252_i24@mstr_discrete.res~
(chips)',
 PATH='I24',
 DRAWING='@BASEBOARD_FAB2_LIB.BASEBOARD_FAB2(SCH_1):PAGE255',
 WATTAGE='1/16W',
 TOLERANCE='1%',
 MATERIAL='CHIP',
 BOM_COST='PROC_SIDEBAND',
 PHYS_PAGE='252',
 XY='(-6700,2550)',
 ROT='2',
 VER='2',
 VALUE='150.0',
 PACK_TYPE='0402',
 PART_NUMBER='G21796-009',
 LOCATION='R25W127',
 ROOM='PROC_SIDEBAND',
 GROUP='AST2500',
 CDS_LIB='mstr_discrete',
 CDS_PART_NAME='RES_0402-150.0,1%,1/16W,CHIP,GA',
 PRIM_FILE='./archive_libs/mstr_discrete/res/chips/chips.prt';

PART_NAME
 R25W128 'RES_0402-150.0,1%,1/16W,CHIP,GA':
 GROUP='AST2500',
 ROOM='PROC_SIDEBAND';

SECTION_NUMBER 1
 '@BASEBOARD_FAB2_LIB.BASEBOARD_FAB2(SCH_1):PAGE255_I22@MSTR_DISCRETE.RES(CHIPS)':
 C_PATH='@baseboard_fab2_lib.baseboard_fab2(sch_1):page255_i22@mstr_discrete.res~
(chips)',
 P_PATH='@baseboard_fab2_lib.baseboard_fab2(sch_1):page252_i22@mstr_discrete.res~
(chips)',
 PATH='I22',
 DRAWING='@BASEBOARD_FAB2_LIB.BASEBOARD_FAB2(SCH_1):PAGE255',
 WATTAGE='1/16W',
 TOLERANCE='1%',
 MATERIAL='CHIP',
 BOM_COST='PROC_SIDEBAND',
 PHYS_PAGE='252',
 XY='(-6350,2550)',
 ROT='2',
 VER='2',
 VALUE='150.0',
 PACK_TYPE='0402',
 PART_NUMBER='G21796-009',
 LOCATION='R25W128',
 ROOM='PROC_SIDEBAND',
 GROUP='AST2500',
 CDS_LIB='mstr_discrete',
 CDS_PART_NAME='RES_0402-150.0,1%,1/16W,CHIP,GA',
 PRIM_FILE='./archive_libs/mstr_discrete/res/chips/chips.prt';

PART_NAME
 R25W129 'RES_0402-4.75K,1%,1/16W,CHIP,GA':
 ROOM='CPU_FANS';

SECTION_NUMBER 1
 '@BASEBOARD_FAB2_LIB.BASEBOARD_FAB2(SCH_1):PAGE146_I152@MSTR_DISCRETE.RES(CHIPS)':
 C_PATH='@baseboard_fab2_lib.baseboard_fab2(sch_1):page146_i152@mstr_discrete.re~
s(chips)',
 P_PATH='@baseboard_fab2_lib.baseboard_fab2(sch_1):page146_i152@mstr_discrete.re~
s(chips)',
 PATH='I152',
 DRAWING='@BASEBOARD_FAB2_LIB.BASEBOARD_FAB2(SCH_1):PAGE146',
 WATTAGE='1/16W',
 TOLERANCE='1%',
 SEC_TYPE='0402',
 MATERIAL='CHIP',
 BOM_COST='SM_THERM',
 PHYS_PAGE='146',
 XY='(-7300,400)',
 ROT='1',
 VER='2',
 VALUE='4.75K',
 PACK_TYPE='0402',
 PART_NUMBER='G21796-072',
 LOCATION='R25W129',
 ROOM='CPU_FANS',
 SEC='1',
 CDS_LIB='mstr_discrete',
 CDS_PART_NAME='RES_0402-4.75K,1%,1/16W,CHIP,GA',
 PRIM_FILE='./archive_libs/mstr_discrete/res/chips/chips.prt';

PART_NAME
 R25W130 'RES_0402-4.75K,1%,1/16W,CHIP,GA':
 ROOM='CPU_FANS';

SECTION_NUMBER 1
 '@BASEBOARD_FAB2_LIB.BASEBOARD_FAB2(SCH_1):PAGE146_I153@MSTR_DISCRETE.RES(CHIPS)':
 C_PATH='@baseboard_fab2_lib.baseboard_fab2(sch_1):page146_i153@mstr_discrete.re~
s(chips)',
 P_PATH='@baseboard_fab2_lib.baseboard_fab2(sch_1):page146_i153@mstr_discrete.re~
s(chips)',
 PATH='I153',
 DRAWING='@BASEBOARD_FAB2_LIB.BASEBOARD_FAB2(SCH_1):PAGE146',
 WATTAGE='1/16W',
 TOLERANCE='1%',
 SEC_TYPE='0402',
 MATERIAL='CHIP',
 BOM_COST='SM_THERM',
 PHYS_PAGE='146',
 XY='(-7300,250)',
 ROT='1',
 VER='2',
 VALUE='4.75K',
 PACK_TYPE='0402',
 PART_NUMBER='G21796-072',
 LOCATION='R25W130',
 ROOM='CPU_FANS',
 SEC='1',
 CDS_LIB='mstr_discrete',
 CDS_PART_NAME='RES_0402-4.75K,1%,1/16W,CHIP,GA',
 PRIM_FILE='./archive_libs/mstr_discrete/res/chips/chips.prt';

PART_NAME
 R25W131 'RES_0402-4.75K,1%,1/16W,CHIP,GA':
 GROUP='AST2500',
 ROOM='CPU_FANS';

SECTION_NUMBER 1
 '@BASEBOARD_FAB2_LIB.BASEBOARD_FAB2(SCH_1):PAGE255_I30@MSTR_DISCRETE.RES(CHIPS)':
 C_PATH='@baseboard_fab2_lib.baseboard_fab2(sch_1):page255_i30@mstr_discrete.res~
(chips)',
 P_PATH='@baseboard_fab2_lib.baseboard_fab2(sch_1):page252_i30@mstr_discrete.res~
(chips)',
 PATH='I30',
 DRAWING='@BASEBOARD_FAB2_LIB.BASEBOARD_FAB2(SCH_1):PAGE255',
 WATTAGE='1/16W',
 TOLERANCE='1%',
 SEC_TYPE='0402',
 MATERIAL='CHIP',
 BOM_COST='SM_THERM',
 PHYS_PAGE='252',
 XY='(-8200,5300)',
 ROT='0',
 VER='2',
 VALUE='4.75K',
 PACK_TYPE='0402',
 PART_NUMBER='G21796-072',
 LOCATION='R25W131',
 ROOM='CPU_FANS',
 GROUP='AST2500',
 SEC='1',
 CDS_LIB='mstr_discrete',
 CDS_PART_NAME='RES_0402-4.75K,1%,1/16W,CHIP,GA',
 PRIM_FILE='./archive_libs/mstr_discrete/res/chips/chips.prt';

PART_NAME
 R25W132 'RES_0402-4.75K,1%,1/16W,CHIP,GA':
 GROUP='AST2500',
 ROOM='CPU_FANS';

SECTION_NUMBER 1
 '@BASEBOARD_FAB2_LIB.BASEBOARD_FAB2(SCH_1):PAGE255_I31@MSTR_DISCRETE.RES(CHIPS)':
 C_PATH='@baseboard_fab2_lib.baseboard_fab2(sch_1):page255_i31@mstr_discrete.res~
(chips)',
 P_PATH='@baseboard_fab2_lib.baseboard_fab2(sch_1):page252_i31@mstr_discrete.res~
(chips)',
 PATH='I31',
 DRAWING='@BASEBOARD_FAB2_LIB.BASEBOARD_FAB2(SCH_1):PAGE255',
 WATTAGE='1/16W',
 TOLERANCE='1%',
 SEC_TYPE='0402',
 MATERIAL='CHIP',
 BOM_COST='SM_THERM',
 PHYS_PAGE='252',
 XY='(-7750,4950)',
 ROT='0',
 VER='2',
 VALUE='4.75K',
 PACK_TYPE='0402',
 PART_NUMBER='G21796-072',
 LOCATION='R25W132',
 ROOM='CPU_FANS',
 GROUP='AST2500',
 SEC='1',
 CDS_LIB='mstr_discrete',
 CDS_PART_NAME='RES_0402-4.75K,1%,1/16W,CHIP,GA',
 PRIM_FILE='./archive_libs/mstr_discrete/res/chips/chips.prt';

PART_NAME
 R25W133 'RES_0402-33.2,1%,1/16W,CHIP,G2A':
 GROUP='AST2500';

SECTION_NUMBER 1
 '@BASEBOARD_FAB2_LIB.BASEBOARD_FAB2(SCH_1):PAGE255_I34@MSTR_DISCRETE.RES(CHIPS)':
 C_PATH='@baseboard_fab2_lib.baseboard_fab2(sch_1):page255_i34@mstr_discrete.res~
(chips)',
 P_PATH='@baseboard_fab2_lib.baseboard_fab2(sch_1):page252_i34@mstr_discrete.res~
(chips)',
 PATH='I34',
 DRAWING='@BASEBOARD_FAB2_LIB.BASEBOARD_FAB2(SCH_1):PAGE255',
 WATTAGE='1/16W',
 TOLERANCE='1%',
 SEC_TYPE='0402',
 MATERIAL='CHIP',
 PHYS_PAGE='252',
 XY='(-6800,4750)',
 ROT='0',
 VER='1',
 VALUE='33.2',
 PACK_TYPE='0402',
 PART_NUMBER='G21796-074',
 LOCATION='R25W133',
 GROUP='AST2500',
 SEC='1',
 CDS_LIB='mstr_discrete',
 CDS_PART_NAME='RES_0402-33.2,1%,1/16W,CHIP,G2A',
 PRIM_FILE='./archive_libs/mstr_discrete/res/chips/chips.prt';

PART_NAME
 R25W134 'RES_0402-4.75K,1%,1/16W,CHIP,GA':
 GROUP='AST2500',
 ROOM='CPU_FANS';

SECTION_NUMBER 1
 '@BASEBOARD_FAB2_LIB.BASEBOARD_FAB2(SCH_1):PAGE255_I43@MSTR_DISCRETE.RES(CHIPS)':
 C_PATH='@baseboard_fab2_lib.baseboard_fab2(sch_1):page255_i43@mstr_discrete.res~
(chips)',
 P_PATH='@baseboard_fab2_lib.baseboard_fab2(sch_1):page252_i43@mstr_discrete.res~
(chips)',
 PATH='I43',
 DRAWING='@BASEBOARD_FAB2_LIB.BASEBOARD_FAB2(SCH_1):PAGE255',
 WATTAGE='1/16W',
 TOLERANCE='1%',
 SEC_TYPE='0402',
 MATERIAL='CHIP',
 BOM_COST='SM_THERM',
 PHYS_PAGE='252',
 XY='(-8200,4050)',
 ROT='0',
 VER='2',
 VALUE='4.75K',
 PACK_TYPE='0402',
 PART_NUMBER='G21796-072',
 LOCATION='R25W134',
 ROOM='CPU_FANS',
 GROUP='AST2500',
 SEC='1',
 CDS_LIB='mstr_discrete',
 CDS_PART_NAME='RES_0402-4.75K,1%,1/16W,CHIP,GA',
 PRIM_FILE='./archive_libs/mstr_discrete/res/chips/chips.prt';

PART_NAME
 R25W135 'RES_0402-4.75K,1%,1/16W,CHIP,GA':
 GROUP='AST2500',
 ROOM='CPU_FANS';

SECTION_NUMBER 1
 '@BASEBOARD_FAB2_LIB.BASEBOARD_FAB2(SCH_1):PAGE255_I44@MSTR_DISCRETE.RES(CHIPS)':
 C_PATH='@baseboard_fab2_lib.baseboard_fab2(sch_1):page255_i44@mstr_discrete.res~
(chips)',
 P_PATH='@baseboard_fab2_lib.baseboard_fab2(sch_1):page252_i44@mstr_discrete.res~
(chips)',
 PATH='I44',
 DRAWING='@BASEBOARD_FAB2_LIB.BASEBOARD_FAB2(SCH_1):PAGE255',
 WATTAGE='1/16W',
 TOLERANCE='1%',
 MATERIAL='CHIP',
 BOM_COST='SM_THERM',
 PHYS_PAGE='252',
 XY='(-7750,3700)',
 ROT='0',
 VER='2',
 VALUE='4.75K',
 PACK_TYPE='0402',
 PART_NUMBER='G21796-072',
 LOCATION='R25W135',
 ROOM='CPU_FANS',
 GROUP='AST2500',
 CDS_LIB='mstr_discrete',
 CDS_PART_NAME='RES_0402-4.75K,1%,1/16W,CHIP,GA',
 PRIM_FILE='./archive_libs/mstr_discrete/res/chips/chips.prt';

PART_NAME
 R25W136 'RES_0402-33.2,1%,1/16W,CHIP,G2A':
 GROUP='AST2500';

SECTION_NUMBER 1
 '@BASEBOARD_FAB2_LIB.BASEBOARD_FAB2(SCH_1):PAGE255_I38@MSTR_DISCRETE.RES(CHIPS)':
 C_PATH='@baseboard_fab2_lib.baseboard_fab2(sch_1):page255_i38@mstr_discrete.res~
(chips)',
 P_PATH='@baseboard_fab2_lib.baseboard_fab2(sch_1):page252_i38@mstr_discrete.res~
(chips)',
 PATH='I38',
 DRAWING='@BASEBOARD_FAB2_LIB.BASEBOARD_FAB2(SCH_1):PAGE255',
 WATTAGE='1/16W',
 TOLERANCE='1%',
 SEC_TYPE='0402',
 MATERIAL='CHIP',
 PHYS_PAGE='252',
 XY='(-6800,3500)',
 ROT='0',
 VER='1',
 VALUE='33.2',
 PACK_TYPE='0402',
 PART_NUMBER='G21796-074',
 LOCATION='R25W136',
 GROUP='AST2500',
 SEC='1',
 CDS_LIB='mstr_discrete',
 CDS_PART_NAME='RES_0402-33.2,1%,1/16W,CHIP,G2A',
 PRIM_FILE='./archive_libs/mstr_discrete/res/chips/chips.prt';

PART_NAME
 R25W138 'RES_0402-33.2,1%,1/16W,CHIP,G2A':
 GROUP='AST2500',
 ROOM='PROC_TRANSLATORS';

SECTION_NUMBER 1
 '@BASEBOARD_FAB2_LIB.BASEBOARD_FAB2(SCH_1):PAGE255_I49@MSTR_DISCRETE.RES(CHIPS)':
 C_PATH='@baseboard_fab2_lib.baseboard_fab2(sch_1):page255_i49@mstr_discrete.res~
(chips)',
 P_PATH='@baseboard_fab2_lib.baseboard_fab2(sch_1):page252_i49@mstr_discrete.res~
(chips)',
 PATH='I49',
 DRAWING='@BASEBOARD_FAB2_LIB.BASEBOARD_FAB2(SCH_1):PAGE255',
 WATTAGE='1/16W',
 TOLERANCE='1%',
 SEC_TYPE='0402',
 MATERIAL='CHIP',
 BOM_COST='PROC_SIDEBAND',
 PHYS_PAGE='252',
 XY='(-3250,5000)',
 ROT='0',
 VER='1',
 VALUE='33.2',
 PACK_TYPE='0402',
 PART_NUMBER='G21796-074',
 LOCATION='R25W138',
 ROOM='PROC_TRANSLATORS',
 GROUP='AST2500',
 SEC='1',
 CDS_LIB='mstr_discrete',
 CDS_PART_NAME='RES_0402-33.2,1%,1/16W,CHIP,G2A',
 PRIM_FILE='./archive_libs/mstr_discrete/res/chips/chips.prt';

PART_NAME
 R25W139 'RES_0402-33.2,1%,1/16W,CHIP,G2A':
 GROUP='AST2500',
 ROOM='PROC_TRANSLATORS';

SECTION_NUMBER 1
 '@BASEBOARD_FAB2_LIB.BASEBOARD_FAB2(SCH_1):PAGE255_I59@MSTR_DISCRETE.RES(CHIPS)':
 C_PATH='@baseboard_fab2_lib.baseboard_fab2(sch_1):page255_i59@mstr_discrete.res~
(chips)',
 P_PATH='@baseboard_fab2_lib.baseboard_fab2(sch_1):page252_i59@mstr_discrete.res~
(chips)',
 PATH='I59',
 DRAWING='@BASEBOARD_FAB2_LIB.BASEBOARD_FAB2(SCH_1):PAGE255',
 WATTAGE='1/16W',
 TOLERANCE='1%',
 SEC_TYPE='0402',
 MATERIAL='CHIP',
 BOM_COST='PROC_SIDEBAND',
 PHYS_PAGE='252',
 XY='(-3250,4450)',
 ROT='0',
 VER='1',
 VALUE='33.2',
 PACK_TYPE='0402',
 PART_NUMBER='G21796-074',
 LOCATION='R25W139',
 ROOM='PROC_TRANSLATORS',
 GROUP='AST2500',
 SEC='1',
 CDS_LIB='mstr_discrete',
 CDS_PART_NAME='RES_0402-33.2,1%,1/16W,CHIP,G2A',
 PRIM_FILE='./archive_libs/mstr_discrete/res/chips/chips.prt';

PART_NAME
 R25W140 'RES_0402-0.0,5%,1/16W,EMPTY,G2A':
 ROOM='NV_DIMM';

SECTION_NUMBER 1
 '@BASEBOARD_FAB2_LIB.BASEBOARD_FAB2(SCH_1):PAGE144_I148@MSTR_DISCRETE.RES(CHIPS)':
 C_PATH='@baseboard_fab2_lib.baseboard_fab2(sch_1):page144_i148@mstr_discrete.re~
s(chips)',
 P_PATH='@baseboard_fab2_lib.baseboard_fab2(sch_1):page144_i148@mstr_discrete.re~
s(chips)',
 PATH='I148',
 DRAWING='@BASEBOARD_FAB2_LIB.BASEBOARD_FAB2(SCH_1):PAGE144',
 WATTAGE='1/16W',
 TOLERANCE='5%',
 SEC_TYPE='0402',
 MATERIAL='EMPTY',
 BOM_COST='MEM_NV',
 PHYS_PAGE='144',
 XY='(-6700,-4300)',
 ROT='0',
 VER='1',
 VALUE='0.0',
 PACK_TYPE='0402',
 PART_NUMBER='G21497-005',
 LOCATION='R25W140',
 ROOM='NV_DIMM',
 SEC='1',
 CDS_LIB='mstr_discrete',
 CDS_PART_NAME='RES_0402-0.0,5%,1/16W,EMPTY,G2A',
 PRIM_FILE='./archive_libs/mstr_discrete/res/chips/chips.prt';

PART_NAME
 R25W141 'RES_0402-0.0,5%,1/16W,CHIP,G21A':
 GROUP='AST2500',
 ROOM='CPU0';

SECTION_NUMBER 1
 '@BASEBOARD_FAB2_LIB.BASEBOARD_FAB2(SCH_1):PAGE145_I160@MSTR_DISCRETE.RES(CHIPS)':
 C_PATH='@baseboard_fab2_lib.baseboard_fab2(sch_1):page145_i160@mstr_discrete.re~
s(chips)',
 P_PATH='@baseboard_fab2_lib.baseboard_fab2(sch_1):page145_i160@mstr_discrete.re~
s(chips)',
 PATH='I160',
 DRAWING='@BASEBOARD_FAB2_LIB.BASEBOARD_FAB2(SCH_1):PAGE145',
 WATTAGE='1/16W',
 TOLERANCE='5%',
 SEC_TYPE='0402',
 MATERIAL='CHIP',
 BOM_COST='PROC_SIDEBAND',
 PHYS_PAGE='145',
 XY='(-5950,-3450)',
 ROT='0',
 VER='1',
 VALUE='0.0',
 PACK_TYPE='0402',
 PART_NUMBER='G21497-005',
 LOCATION='R25W141',
 ROOM='CPU0',
 GROUP='AST2500',
 SEC='1',
 CDS_LIB='mstr_discrete',
 CDS_PART_NAME='RES_0402-0.0,5%,1/16W,CHIP,G21A',
 PRIM_FILE='./archive_libs/mstr_discrete/res/chips/chips.prt';

PART_NAME
 R25W142 'RES_0402-100.0K,1%,1/16W,CHIP,A':;

SECTION_NUMBER 1
 '@BASEBOARD_FAB2_LIB.BASEBOARD_FAB2(SCH_1):PAGE147_I156@MSTR_DISCRETE.RES(CHIPS)':
 C_PATH='@baseboard_fab2_lib.baseboard_fab2(sch_1):page147_i156@mstr_discrete.re~
s(chips)',
 P_PATH='@baseboard_fab2_lib.baseboard_fab2(sch_1):page147_i156@mstr_discrete.re~
s(chips)',
 PATH='I156',
 DRAWING='@BASEBOARD_FAB2_LIB.BASEBOARD_FAB2(SCH_1):PAGE147',
 WATTAGE='1/16W',
 TOLERANCE='1%',
 SEC_TYPE='0402',
 MATERIAL='CHIP',
 PHYS_PAGE='147',
 XY='(-4700,1950)',
 ROT='0',
 VER='2',
 VALUE='100.0K',
 PACK_TYPE='0402',
 PART_NUMBER='G21796-010',
 LOCATION='R25W142',
 SEC='1',
 CDS_LIB='mstr_discrete',
 CDS_PART_NAME='RES_0402-100.0K,1%,1/16W,CHIP,A',
 PRIM_FILE='./archive_libs/mstr_discrete/res/chips/chips.prt';

PART_NAME
 R25W143 'RES_0402-0.0,5%,1/16W,CHIP,G21A':
 ROOM='DEBUG';

SECTION_NUMBER 1
 '@BASEBOARD_FAB2_LIB.BASEBOARD_FAB2(SCH_1):PAGE147_I159@MSTR_DISCRETE.RES(CHIPS)':
 C_PATH='@baseboard_fab2_lib.baseboard_fab2(sch_1):page147_i159@mstr_discrete.re~
s(chips)',
 P_PATH='@baseboard_fab2_lib.baseboard_fab2(sch_1):page147_i159@mstr_discrete.re~
s(chips)',
 PATH='I159',
 DRAWING='@BASEBOARD_FAB2_LIB.BASEBOARD_FAB2(SCH_1):PAGE147',
 WATTAGE='1/16W',
 TOLERANCE='5%',
 SEC_TYPE='0402',
 MATERIAL='CHIP',
 PHYS_PAGE='147',
 XY='(1500,3400)',
 ROT='0',
 VER='1',
 VALUE='0.0',
 PACK_TYPE='0402',
 PART_NUMBER='G21497-005',
 LOCATION='R25W143',
 ROOM='DEBUG',
 SEC='1',
 CDS_LIB='mstr_discrete',
 CDS_PART_NAME='RES_0402-0.0,5%,1/16W,CHIP,G21A',
 PRIM_FILE='./archive_libs/mstr_discrete/res/chips/chips.prt';

PART_NAME
 R25W144 'RES_0402-0.0,5%,1/16W,CHIP,G21A':
 ROOM='BMC';

SECTION_NUMBER 1
 '@BASEBOARD_FAB2_LIB.BASEBOARD_FAB2(SCH_1):PAGE145_I173@MSTR_DISCRETE.RES(CHIPS)':
 C_PATH='@baseboard_fab2_lib.baseboard_fab2(sch_1):page145_i173@mstr_discrete.re~
s(chips)',
 P_PATH='@baseboard_fab2_lib.baseboard_fab2(sch_1):page145_i173@mstr_discrete.re~
s(chips)',
 PATH='I173',
 DRAWING='@BASEBOARD_FAB2_LIB.BASEBOARD_FAB2(SCH_1):PAGE145',
 WATTAGE='1/16W',
 TOLERANCE='5%',
 SEC_TYPE='0402',
 MATERIAL='CHIP',
 BOM_COST='SM_CONTROLLER',
 PHYS_PAGE='145',
 XY='(-1500,-2900)',
 ROT='0',
 VER='1',
 VALUE='0.0',
 PACK_TYPE='0402',
 PART_NUMBER='G21497-005',
 LOCATION='R25W144',
 ROOM='BMC',
 SEC='1',
 CDS_LIB='mstr_discrete',
 CDS_PART_NAME='RES_0402-0.0,5%,1/16W,CHIP,G21A',
 PRIM_FILE='./archive_libs/mstr_discrete/res/chips/chips.prt';

PART_NAME
 R25W145 'RES_0402-0.0,5%,1/16W,CHIP,G21A':
 ROOM='BMC';

SECTION_NUMBER 1
 '@BASEBOARD_FAB2_LIB.BASEBOARD_FAB2(SCH_1):PAGE145_I175@MSTR_DISCRETE.RES(CHIPS)':
 C_PATH='@baseboard_fab2_lib.baseboard_fab2(sch_1):page145_i175@mstr_discrete.re~
s(chips)',
 P_PATH='@baseboard_fab2_lib.baseboard_fab2(sch_1):page145_i175@mstr_discrete.re~
s(chips)',
 PATH='I175',
 DRAWING='@BASEBOARD_FAB2_LIB.BASEBOARD_FAB2(SCH_1):PAGE145',
 WATTAGE='1/16W',
 TOLERANCE='5%',
 SEC_TYPE='0402',
 MATERIAL='CHIP',
 BOM_COST='SM_CONTROLLER',
 PHYS_PAGE='145',
 XY='(-1500,-3000)',
 ROT='0',
 VER='1',
 VALUE='0.0',
 PACK_TYPE='0402',
 PART_NUMBER='G21497-005',
 LOCATION='R25W145',
 ROOM='BMC',
 SEC='1',
 CDS_LIB='mstr_discrete',
 CDS_PART_NAME='RES_0402-0.0,5%,1/16W,CHIP,G21A',
 PRIM_FILE='./archive_libs/mstr_discrete/res/chips/chips.prt';

PART_NAME
 R25W146 'RES_0402-4.75K,1%,1/16W,CHIP,GA':
 ROOM='BMC';

SECTION_NUMBER 1
 '@BASEBOARD_FAB2_LIB.BASEBOARD_FAB2(SCH_1):PAGE150_I199@MSTR_DISCRETE.RES(CHIPS)':
 C_PATH='@baseboard_fab2_lib.baseboard_fab2(sch_1):page150_i199@mstr_discrete.re~
s(chips)',
 P_PATH='@baseboard_fab2_lib.baseboard_fab2(sch_1):page150_i199@mstr_discrete.re~
s(chips)',
 PATH='I199',
 DRAWING='@BASEBOARD_FAB2_LIB.BASEBOARD_FAB2(SCH_1):PAGE150',
 WATTAGE='1/16W',
 TOLERANCE='1%',
 SEC_TYPE='0402',
 MATERIAL='CHIP',
 BOM_COST='SM_CONTROLLER',
 PHYS_PAGE='150',
 XY='(-600,-1300)',
 ROT='0',
 VER='1',
 VALUE='4.75K',
 PACK_TYPE='0402',
 PART_NUMBER='G21796-072',
 LOCATION='R25W146',
 ROOM='BMC',
 SEC='1',
 CDS_LIB='mstr_discrete',
 CDS_PART_NAME='RES_0402-4.75K,1%,1/16W,CHIP,GA',
 PRIM_FILE='./archive_libs/mstr_discrete/res/chips/chips.prt';

PART_NAME
 R25W148 'RES_0402-4.75K,1%,1/16W,CHIP,GA':
 ROOM='BMC';

SECTION_NUMBER 1
 '@BASEBOARD_FAB2_LIB.BASEBOARD_FAB2(SCH_1):PAGE150_I216@MSTR_DISCRETE.RES(CHIPS)':
 C_PATH='@baseboard_fab2_lib.baseboard_fab2(sch_1):page150_i216@mstr_discrete.re~
s(chips)',
 P_PATH='@baseboard_fab2_lib.baseboard_fab2(sch_1):page150_i216@mstr_discrete.re~
s(chips)',
 PATH='I216',
 DRAWING='@BASEBOARD_FAB2_LIB.BASEBOARD_FAB2(SCH_1):PAGE150',
 WATTAGE='1/16W',
 TOLERANCE='1%',
 SEC_TYPE='0402',
 MATERIAL='CHIP',
 BOM_COST='SM_CONTROLLER',
 PHYS_PAGE='150',
 XY='(-600,-2300)',
 ROT='0',
 VER='1',
 VALUE='4.75K',
 PACK_TYPE='0402',
 PART_NUMBER='G21796-072',
 LOCATION='R25W148',
 ROOM='BMC',
 SEC='1',
 CDS_LIB='mstr_discrete',
 CDS_PART_NAME='RES_0402-4.75K,1%,1/16W,CHIP,GA',
 PRIM_FILE='./archive_libs/mstr_discrete/res/chips/chips.prt';

PART_NAME
 R25W149 'RES_0402-4.75K,1%,1/16W,CHIP,GA':
 ROOM='BMC';

SECTION_NUMBER 1
 '@BASEBOARD_FAB2_LIB.BASEBOARD_FAB2(SCH_1):PAGE150_I219@MSTR_DISCRETE.RES(CHIPS)':
 C_PATH='@baseboard_fab2_lib.baseboard_fab2(sch_1):page150_i219@mstr_discrete.re~
s(chips)',
 P_PATH='@baseboard_fab2_lib.baseboard_fab2(sch_1):page150_i219@mstr_discrete.re~
s(chips)',
 PATH='I219',
 DRAWING='@BASEBOARD_FAB2_LIB.BASEBOARD_FAB2(SCH_1):PAGE150',
 WATTAGE='1/16W',
 TOLERANCE='1%',
 SEC_TYPE='0402',
 MATERIAL='CHIP',
 BOM_COST='SM_CONTROLLER',
 PHYS_PAGE='150',
 XY='(-600,-2700)',
 ROT='0',
 VER='1',
 VALUE='4.75K',
 PACK_TYPE='0402',
 PART_NUMBER='G21796-072',
 LOCATION='R25W149',
 ROOM='BMC',
 SEC='1',
 CDS_LIB='mstr_discrete',
 CDS_PART_NAME='RES_0402-4.75K,1%,1/16W,CHIP,GA',
 PRIM_FILE='./archive_libs/mstr_discrete/res/chips/chips.prt';

PART_NAME
 R25W150 'RES_0402-4.75K,1%,1/16W,CHIP,GA':
 ROOM='BMC';

SECTION_NUMBER 1
 '@BASEBOARD_FAB2_LIB.BASEBOARD_FAB2(SCH_1):PAGE150_I229@MSTR_DISCRETE.RES(CHIPS)':
 C_PATH='@baseboard_fab2_lib.baseboard_fab2(sch_1):page150_i229@mstr_discrete.re~
s(chips)',
 P_PATH='@baseboard_fab2_lib.baseboard_fab2(sch_1):page150_i229@mstr_discrete.re~
s(chips)',
 PATH='I229',
 DRAWING='@BASEBOARD_FAB2_LIB.BASEBOARD_FAB2(SCH_1):PAGE150',
 WATTAGE='1/16W',
 TOLERANCE='1%',
 SEC_TYPE='0402',
 MATERIAL='CHIP',
 BOM_COST='SM_CONTROLLER',
 PHYS_PAGE='150',
 XY='(-600,-3300)',
 ROT='0',
 VER='1',
 VALUE='4.75K',
 PACK_TYPE='0402',
 PART_NUMBER='G21796-072',
 LOCATION='R25W150',
 ROOM='BMC',
 SEC='1',
 CDS_LIB='mstr_discrete',
 CDS_PART_NAME='RES_0402-4.75K,1%,1/16W,CHIP,GA',
 PRIM_FILE='./archive_libs/mstr_discrete/res/chips/chips.prt';

PART_NAME
 R25W151 'RES_0402-4.75K,1%,1/16W,CHIP,GA':
 ROOM='BMC';

SECTION_NUMBER 1
 '@BASEBOARD_FAB2_LIB.BASEBOARD_FAB2(SCH_1):PAGE150_I232@MSTR_DISCRETE.RES(CHIPS)':
 C_PATH='@baseboard_fab2_lib.baseboard_fab2(sch_1):page150_i232@mstr_discrete.re~
s(chips)',
 P_PATH='@baseboard_fab2_lib.baseboard_fab2(sch_1):page150_i232@mstr_discrete.re~
s(chips)',
 PATH='I232',
 DRAWING='@BASEBOARD_FAB2_LIB.BASEBOARD_FAB2(SCH_1):PAGE150',
 WATTAGE='1/16W',
 TOLERANCE='1%',
 SEC_TYPE='0402',
 MATERIAL='CHIP',
 BOM_COST='SM_CONTROLLER',
 PHYS_PAGE='150',
 XY='(-600,-3650)',
 ROT='0',
 VER='1',
 VALUE='4.75K',
 PACK_TYPE='0402',
 PART_NUMBER='G21796-072',
 LOCATION='R25W151',
 ROOM='BMC',
 SEC='1',
 CDS_LIB='mstr_discrete',
 CDS_PART_NAME='RES_0402-4.75K,1%,1/16W,CHIP,GA',
 PRIM_FILE='./archive_libs/mstr_discrete/res/chips/chips.prt';

PART_NAME
 R25W152 'RES_0402-4.75K,1%,1/16W,CHIP,GA':
 ROOM='BMC';

SECTION_NUMBER 1
 '@BASEBOARD_FAB2_LIB.BASEBOARD_FAB2(SCH_1):PAGE150_I234@MSTR_DISCRETE.RES(CHIPS)':
 C_PATH='@baseboard_fab2_lib.baseboard_fab2(sch_1):page150_i234@mstr_discrete.re~
s(chips)',
 P_PATH='@baseboard_fab2_lib.baseboard_fab2(sch_1):page150_i234@mstr_discrete.re~
s(chips)',
 PATH='I234',
 DRAWING='@BASEBOARD_FAB2_LIB.BASEBOARD_FAB2(SCH_1):PAGE150',
 WATTAGE='1/16W',
 TOLERANCE='1%',
 SEC_TYPE='0402',
 MATERIAL='CHIP',
 BOM_COST='SM_CONTROLLER',
 PHYS_PAGE='150',
 XY='(1850,200)',
 ROT='0',
 VER='1',
 VALUE='4.75K',
 PACK_TYPE='0402',
 PART_NUMBER='G21796-072',
 LOCATION='R25W152',
 ROOM='BMC',
 SEC='1',
 CDS_LIB='mstr_discrete',
 CDS_PART_NAME='RES_0402-4.75K,1%,1/16W,CHIP,GA',
 PRIM_FILE='./archive_libs/mstr_discrete/res/chips/chips.prt';

PART_NAME
 R25W153 'RES_0402-4.75K,1%,1/16W,CHIP,GA':
 ROOM='BMC_MISC';

SECTION_NUMBER 1
 '@BASEBOARD_FAB2_LIB.BASEBOARD_FAB2(SCH_1):PAGE157_I396@MSTR_DISCRETE.RES(CHIPS)':
 C_PATH='@baseboard_fab2_lib.baseboard_fab2(sch_1):page157_i396@mstr_discrete.re~
s(chips)',
 P_PATH='@baseboard_fab2_lib.baseboard_fab2(sch_1):page157_i396@mstr_discrete.re~
s(chips)',
 PATH='I396',
 DRAWING='@BASEBOARD_FAB2_LIB.BASEBOARD_FAB2(SCH_1):PAGE157',
 WATTAGE='1/16W',
 TOLERANCE='1%',
 SEC_TYPE='0402',
 MATERIAL='CHIP',
 BOM_COST='SM_CONTROLLER',
 PHYS_PAGE='157',
 XY='(-2275,700)',
 ROT='0',
 VER='2',
 VALUE='4.75K',
 PACK_TYPE='0402',
 PART_NUMBER='G21796-072',
 LOCATION='R25W153',
 ROOM='BMC_MISC',
 SEC='1',
 CDS_LIB='mstr_discrete',
 CDS_PART_NAME='RES_0402-4.75K,1%,1/16W,CHIP,GA',
 PRIM_FILE='./archive_libs/mstr_discrete/res/chips/chips.prt';

PART_NAME
 R25W154 'RES_0402-0.0,5%,1/16W,CHIP,G21A':
 ROOM='BMC';

SECTION_NUMBER 1
 '@BASEBOARD_FAB2_LIB.BASEBOARD_FAB2(SCH_1):PAGE137_I133@MSTR_DISCRETE.RES(CHIPS)':
 C_PATH='@baseboard_fab2_lib.baseboard_fab2(sch_1):page137_i133@mstr_discrete.re~
s(chips)',
 P_PATH='@baseboard_fab2_lib.baseboard_fab2(sch_1):page137_i133@mstr_discrete.re~
s(chips)',
 PATH='I133',
 DRAWING='@BASEBOARD_FAB2_LIB.BASEBOARD_FAB2(SCH_1):PAGE137',
 WATTAGE='1/16W',
 TOLERANCE='5%',
 SEC_TYPE='0402',
 MATERIAL='CHIP',
 BOM_COST='SM_CONTROLLER',
 PHYS_PAGE='137',
 XY='(-1700,2350)',
 ROT='0',
 VER='1',
 VALUE='0.0',
 PACK_TYPE='0402',
 PART_NUMBER='G21497-005',
 LOCATION='R25W154',
 ROOM='BMC',
 SEC='1',
 CDS_LIB='mstr_discrete',
 CDS_PART_NAME='RES_0402-0.0,5%,1/16W,CHIP,G21A',
 PRIM_FILE='./archive_libs/mstr_discrete/res/chips/chips.prt';

PART_NAME
 R25W155 'RES_0402-0.0,5%,1/16W,CHIP,G21A':
 ROOM='USB';

SECTION_NUMBER 1
 '@BASEBOARD_FAB2_LIB.BASEBOARD_FAB2(SCH_1):PAGE148_I29@MSTR_DISCRETE.RES(CHIPS)':
 C_PATH='@baseboard_fab2_lib.baseboard_fab2(sch_1):page148_i29@mstr_discrete.res~
(chips)',
 P_PATH='@baseboard_fab2_lib.baseboard_fab2(sch_1):page148_i29@mstr_discrete.res~
(chips)',
 PATH='I29',
 DRAWING='@BASEBOARD_FAB2_LIB.BASEBOARD_FAB2(SCH_1):PAGE148',
 WATTAGE='1/16W',
 TOLERANCE='5%',
 SEC_TYPE='0402',
 MATERIAL='CHIP',
 BOM_COST='MIO_USB',
 PHYS_PAGE='148',
 XY='(-6850,2300)',
 ROT='0',
 VER='1',
 VALUE='0.0',
 PACK_TYPE='0402',
 PART_NUMBER='G21497-005',
 LOCATION='R25W155',
 ROOM='USB',
 SEC='1',
 CDS_LIB='mstr_discrete',
 CDS_PART_NAME='RES_0402-0.0,5%,1/16W,CHIP,G21A',
 PRIM_FILE='./archive_libs/mstr_discrete/res/chips/chips.prt';

PART_NAME
 R25W156 'RES_0402-3.32K,1%,1/16W,EMPTY,A':
 ROOM='NIC_SPRV';

SECTION_NUMBER 1
 '@BASEBOARD_FAB2_LIB.BASEBOARD_FAB2(SCH_1):PAGE150_I240@MSTR_DISCRETE.RES(CHIPS)':
 C_PATH='@baseboard_fab2_lib.baseboard_fab2(sch_1):page150_i240@mstr_discrete.re~
s(chips)',
 P_PATH='@baseboard_fab2_lib.baseboard_fab2(sch_1):page150_i240@mstr_discrete.re~
s(chips)',
 PATH='I240',
 DRAWING='@BASEBOARD_FAB2_LIB.BASEBOARD_FAB2(SCH_1):PAGE150',
 WATTAGE='1/16W',
 TOLERANCE='1%',
 SEC_TYPE='0402',
 MATERIAL='EMPTY',
 BOM_COST='NT_GBE_BASE',
 PHYS_PAGE='150',
 XY='(-600,-650)',
 ROT='1',
 VER='2',
 VALUE='3.32K',
 PACK_TYPE='0402',
 PART_NUMBER='G21796-027',
 LOCATION='R25W156',
 ROOM='NIC_SPRV',
 SEC='1',
 CDS_LIB='mstr_discrete',
 CDS_PART_NAME='RES_0402-3.32K,1%,1/16W,EMPTY,A',
 PRIM_FILE='./archive_libs/mstr_discrete/res/chips/chips.prt';

PART_NAME
 R25W157 'RES_0402-100.0K,1%,1/16W,CHIP,A':;

SECTION_NUMBER 1
 '@BASEBOARD_FAB2_LIB.BASEBOARD_FAB2(SCH_1):PAGE147_I164@MSTR_DISCRETE.RES(CHIPS)':
 C_PATH='@baseboard_fab2_lib.baseboard_fab2(sch_1):page147_i164@mstr_discrete.re~
s(chips)',
 P_PATH='@baseboard_fab2_lib.baseboard_fab2(sch_1):page147_i164@mstr_discrete.re~
s(chips)',
 PATH='I164',
 DRAWING='@BASEBOARD_FAB2_LIB.BASEBOARD_FAB2(SCH_1):PAGE147',
 WATTAGE='1/16W',
 TOLERANCE='1%',
 SEC_TYPE='0402',
 MATERIAL='CHIP',
 PHYS_PAGE='147',
 XY='(-4750,1300)',
 ROT='0',
 VER='2',
 VALUE='100.0K',
 PACK_TYPE='0402',
 PART_NUMBER='G21796-010',
 LOCATION='R25W157',
 SEC='1',
 CDS_LIB='mstr_discrete',
 CDS_PART_NAME='RES_0402-100.0K,1%,1/16W,CHIP,A',
 PRIM_FILE='./archive_libs/mstr_discrete/res/chips/chips.prt';

PART_NAME
 R25W158 'RES_0402-1.00K,1%,1/16W,CHIP,GA':
 ROOM='PROC_RSTS_PGOODS';

SECTION_NUMBER 1
 '@BASEBOARD_FAB2_LIB.BASEBOARD_FAB2(SCH_1):PAGE269_I22@MSTR_DISCRETE.RES(CHIPS)':
 C_PATH='@baseboard_fab2_lib.baseboard_fab2(sch_1):page269_i22@mstr_discrete.res~
(chips)',
 P_PATH='@baseboard_fab2_lib.baseboard_fab2(sch_1):page254_i22@mstr_discrete.res~
(chips)',
 PATH='I22',
 DRAWING='@BASEBOARD_FAB2_LIB.BASEBOARD_FAB2(SCH_1):PAGE269',
 WATTAGE='1/16W',
 TOLERANCE='1%',
 MATERIAL='CHIP',
 BOM_COST='PROC_SIDEBAND',
 PHYS_PAGE='254',
 XY='(-6450,6050)',
 ROT='0',
 VER='2',
 VALUE='1.00K',
 PACK_TYPE='0402',
 PART_NUMBER='G21796-026',
 LOCATION='R25W158',
 ROOM='PROC_RSTS_PGOODS',
 CDS_LIB='mstr_discrete',
 CDS_PART_NAME='RES_0402-1.00K,1%,1/16W,CHIP,GA',
 PRIM_FILE='./archive_libs/mstr_discrete/res/chips/chips.prt';

PART_NAME
 R25W159 'RES_0402-1.00K,1%,1/16W,CHIP,GA':
 ROOM='PROC_RSTS_PGOODS';

SECTION_NUMBER 1
 '@BASEBOARD_FAB2_LIB.BASEBOARD_FAB2(SCH_1):PAGE269_I24@MSTR_DISCRETE.RES(CHIPS)':
 C_PATH='@baseboard_fab2_lib.baseboard_fab2(sch_1):page269_i24@mstr_discrete.res~
(chips)',
 P_PATH='@baseboard_fab2_lib.baseboard_fab2(sch_1):page254_i24@mstr_discrete.res~
(chips)',
 PATH='I24',
 DRAWING='@BASEBOARD_FAB2_LIB.BASEBOARD_FAB2(SCH_1):PAGE269',
 WATTAGE='1/16W',
 TOLERANCE='1%',
 SEC_TYPE='0402',
 MATERIAL='CHIP',
 BOM_COST='PROC_SIDEBAND',
 PHYS_PAGE='254',
 XY='(-6050,6000)',
 ROT='0',
 VER='1',
 VALUE='1.00K',
 PACK_TYPE='0402',
 PART_NUMBER='G21796-026',
 LOCATION='R25W159',
 ROOM='PROC_RSTS_PGOODS',
 SEC='1',
 CDS_LIB='mstr_discrete',
 CDS_PART_NAME='RES_0402-1.00K,1%,1/16W,CHIP,GA',
 PRIM_FILE='./archive_libs/mstr_discrete/res/chips/chips.prt';

PART_NAME
 R25W160 'RES_0402-1.00K,1%,1/16W,CHIP,GA':
 ROOM='PROC_RSTS_PGOODS';

SECTION_NUMBER 1
 '@BASEBOARD_FAB2_LIB.BASEBOARD_FAB2(SCH_1):PAGE269_I20@MSTR_DISCRETE.RES(CHIPS)':
 C_PATH='@baseboard_fab2_lib.baseboard_fab2(sch_1):page269_i20@mstr_discrete.res~
(chips)',
 P_PATH='@baseboard_fab2_lib.baseboard_fab2(sch_1):page254_i20@mstr_discrete.res~
(chips)',
 PATH='I20',
 DRAWING='@BASEBOARD_FAB2_LIB.BASEBOARD_FAB2(SCH_1):PAGE269',
 WATTAGE='1/16W',
 TOLERANCE='1%',
 MATERIAL='CHIP',
 BOM_COST='PROC_SIDEBAND',
 PHYS_PAGE='254',
 XY='(-7050,6050)',
 ROT='0',
 VER='2',
 VALUE='1.00K',
 PACK_TYPE='0402',
 PART_NUMBER='G21796-026',
 LOCATION='R25W160',
 ROOM='PROC_RSTS_PGOODS',
 CDS_LIB='mstr_discrete',
 CDS_PART_NAME='RES_0402-1.00K,1%,1/16W,CHIP,GA',
 PRIM_FILE='./archive_libs/mstr_discrete/res/chips/chips.prt';

PART_NAME
 R25W161 'RES_0402-1.00K,1%,1/16W,CHIP,GA':
 ROOM='PROC_RSTS_PGOODS';

SECTION_NUMBER 1
 '@BASEBOARD_FAB2_LIB.BASEBOARD_FAB2(SCH_1):PAGE269_I21@MSTR_DISCRETE.RES(CHIPS)':
 C_PATH='@baseboard_fab2_lib.baseboard_fab2(sch_1):page269_i21@mstr_discrete.res~
(chips)',
 P_PATH='@baseboard_fab2_lib.baseboard_fab2(sch_1):page254_i21@mstr_discrete.res~
(chips)',
 PATH='I21',
 DRAWING='@BASEBOARD_FAB2_LIB.BASEBOARD_FAB2(SCH_1):PAGE269',
 WATTAGE='1/16W',
 TOLERANCE='1%',
 MATERIAL='CHIP',
 BOM_COST='PROC_SIDEBAND',
 PHYS_PAGE='254',
 XY='(-6750,6050)',
 ROT='0',
 VER='2',
 VALUE='1.00K',
 PACK_TYPE='0402',
 PART_NUMBER='G21796-026',
 LOCATION='R25W161',
 ROOM='PROC_RSTS_PGOODS',
 CDS_LIB='mstr_discrete',
 CDS_PART_NAME='RES_0402-1.00K,1%,1/16W,CHIP,GA',
 PRIM_FILE='./archive_libs/mstr_discrete/res/chips/chips.prt';

PART_NAME
 R25W164 'RES_0402-49.9,1%,1/16W,CHIP,G2A':
 ROOM='CPU0';

SECTION_NUMBER 1
 '@BASEBOARD_FAB2_LIB.BASEBOARD_FAB2(SCH_1):PAGE268_I29@MSTR_DISCRETE.RES(CHIPS)':
 C_PATH='@baseboard_fab2_lib.baseboard_fab2(sch_1):page268_i29@mstr_discrete.res~
(chips)',
 P_PATH='@baseboard_fab2_lib.baseboard_fab2(sch_1):page255_i29@mstr_discrete.res~
(chips)',
 PATH='I29',
 DRAWING='@BASEBOARD_FAB2_LIB.BASEBOARD_FAB2(SCH_1):PAGE268',
 POP='NOPOP',
 WATTAGE='1/16W',
 TOLERANCE='1%',
 SEC_TYPE='0402',
 MATERIAL='CHIP',
 BOM_COST='PROC_SIDEBAND',
 PHYS_PAGE='255',
 XY='(-5750,6250)',
 ROT='0',
 VER='2',
 VALUE='49.9',
 PACK_TYPE='0402',
 PART_NUMBER='G21796-047',
 LOCATION='R25W164',
 ROOM='CPU0',
 SEC='1',
 CDS_LIB='mstr_discrete',
 CDS_PART_NAME='RES_0402-49.9,1%,1/16W,CHIP,G2A',
 PRIM_FILE='./archive_libs/mstr_discrete/res/chips/chips.prt';

PART_NAME
 R25W165 'RES_0402-100.0,1%,1/16W,CHIP,GA':
 ROOM='PROC_SIDEBAND';

SECTION_NUMBER 1
 '@BASEBOARD_FAB2_LIB.BASEBOARD_FAB2(SCH_1):PAGE268_I28@MSTR_DISCRETE.RES(CHIPS)':
 C_PATH='@baseboard_fab2_lib.baseboard_fab2(sch_1):page268_i28@mstr_discrete.res~
(chips)',
 P_PATH='@baseboard_fab2_lib.baseboard_fab2(sch_1):page255_i28@mstr_discrete.res~
(chips)',
 PATH='I28',
 DRAWING='@BASEBOARD_FAB2_LIB.BASEBOARD_FAB2(SCH_1):PAGE268',
 WATTAGE='1/16W',
 TOLERANCE='1%',
 SEC_TYPE='0402',
 MATERIAL='CHIP',
 BOM_COST='PROC_SIDEBAND',
 PHYS_PAGE='255',
 XY='(-5750,5850)',
 ROT='0',
 VER='2',
 VALUE='100.0',
 PACK_TYPE='0402',
 PART_NUMBER='G21796-017',
 LOCATION='R25W165',
 ROOM='PROC_SIDEBAND',
 SEC='1',
 CDS_LIB='mstr_discrete',
 CDS_PART_NAME='RES_0402-100.0,1%,1/16W,CHIP,GA',
 PRIM_FILE='./archive_libs/mstr_discrete/res/chips/chips.prt';

PART_NAME
 R25W166 'RES_0402-1.00K,1%,1/16W,CHIP,GA':
 ROOM='PROC_SIDEBAND';

SECTION_NUMBER 1
 '@BASEBOARD_FAB2_LIB.BASEBOARD_FAB2(SCH_1):PAGE268_I26@MSTR_DISCRETE.RES(CHIPS)':
 C_PATH='@baseboard_fab2_lib.baseboard_fab2(sch_1):page268_i26@mstr_discrete.res~
(chips)',
 P_PATH='@baseboard_fab2_lib.baseboard_fab2(sch_1):page255_i26@mstr_discrete.res~
(chips)',
 PATH='I26',
 DRAWING='@BASEBOARD_FAB2_LIB.BASEBOARD_FAB2(SCH_1):PAGE268',
 WATTAGE='1/16W',
 TOLERANCE='1%',
 SEC_TYPE='0402',
 MATERIAL='CHIP',
 BOM_COST='PROC_SIDEBAND',
 PHYS_PAGE='255',
 XY='(-6000,5450)',
 ROT='0',
 VER='1',
 VALUE='1.00K',
 PACK_TYPE='0402',
 PART_NUMBER='G21796-026',
 LOCATION='R25W166',
 ROOM='PROC_SIDEBAND',
 SEC='1',
 CDS_LIB='mstr_discrete',
 CDS_PART_NAME='RES_0402-1.00K,1%,1/16W,CHIP,GA',
 PRIM_FILE='./archive_libs/mstr_discrete/res/chips/chips.prt';

PART_NAME
 R25W167 'RES_0402-1.00K,1%,1/16W,CHIP,GA':
 ROOM='PROC_RSTS_PGOODS';

SECTION_NUMBER 1
 '@BASEBOARD_FAB2_LIB.BASEBOARD_FAB2(SCH_1):PAGE269_I10@MSTR_DISCRETE.RES(CHIPS)':
 C_PATH='@baseboard_fab2_lib.baseboard_fab2(sch_1):page269_i10@mstr_discrete.res~
(chips)',
 P_PATH='@baseboard_fab2_lib.baseboard_fab2(sch_1):page254_i10@mstr_discrete.res~
(chips)',
 PATH='I10',
 DRAWING='@BASEBOARD_FAB2_LIB.BASEBOARD_FAB2(SCH_1):PAGE269',
 WATTAGE='1/16W',
 TOLERANCE='1%',
 MATERIAL='CHIP',
 BOM_COST='PROC_SIDEBAND',
 PHYS_PAGE='254',
 XY='(-6100,2900)',
 ROT='1',
 VER='2',
 VALUE='1.00K',
 PACK_TYPE='0402',
 PART_NUMBER='G21796-026',
 LOCATION='R25W167',
 ROOM='PROC_RSTS_PGOODS',
 CDS_LIB='mstr_discrete',
 CDS_PART_NAME='RES_0402-1.00K,1%,1/16W,CHIP,GA',
 PRIM_FILE='./archive_libs/mstr_discrete/res/chips/chips.prt';

PART_NAME
 R25W168 'RES_0402-1.00K,1%,1/16W,CHIP,GA':
 ROOM='PROC_RSTS_PGOODS';

SECTION_NUMBER 1
 '@BASEBOARD_FAB2_LIB.BASEBOARD_FAB2(SCH_1):PAGE269_I11@MSTR_DISCRETE.RES(CHIPS)':
 C_PATH='@baseboard_fab2_lib.baseboard_fab2(sch_1):page269_i11@mstr_discrete.res~
(chips)',
 P_PATH='@baseboard_fab2_lib.baseboard_fab2(sch_1):page254_i11@mstr_discrete.res~
(chips)',
 PATH='I11',
 DRAWING='@BASEBOARD_FAB2_LIB.BASEBOARD_FAB2(SCH_1):PAGE269',
 WATTAGE='1/16W',
 TOLERANCE='1%',
 MATERIAL='CHIP',
 BOM_COST='PROC_SIDEBAND',
 PHYS_PAGE='254',
 XY='(-4750,3500)',
 ROT='1',
 VER='2',
 VALUE='1.00K',
 PACK_TYPE='0402',
 PART_NUMBER='G21796-026',
 LOCATION='R25W168',
 ROOM='PROC_RSTS_PGOODS',
 CDS_LIB='mstr_discrete',
 CDS_PART_NAME='RES_0402-1.00K,1%,1/16W,CHIP,GA',
 PRIM_FILE='./archive_libs/mstr_discrete/res/chips/chips.prt';

PART_NAME
 R25W169 'RES_0402-1.00K,1%,1/16W,CHIP,GA':
 ROOM='PROC_RSTS_PGOODS';

SECTION_NUMBER 1
 '@BASEBOARD_FAB2_LIB.BASEBOARD_FAB2(SCH_1):PAGE269_I12@MSTR_DISCRETE.RES(CHIPS)':
 C_PATH='@baseboard_fab2_lib.baseboard_fab2(sch_1):page269_i12@mstr_discrete.res~
(chips)',
 P_PATH='@baseboard_fab2_lib.baseboard_fab2(sch_1):page254_i12@mstr_discrete.res~
(chips)',
 PATH='I12',
 DRAWING='@BASEBOARD_FAB2_LIB.BASEBOARD_FAB2(SCH_1):PAGE269',
 WATTAGE='1/16W',
 TOLERANCE='1%',
 MATERIAL='CHIP',
 BOM_COST='PROC_SIDEBAND',
 PHYS_PAGE='254',
 XY='(-4750,3700)',
 ROT='1',
 VER='2',
 VALUE='1.00K',
 PACK_TYPE='0402',
 PART_NUMBER='G21796-026',
 LOCATION='R25W169',
 ROOM='PROC_RSTS_PGOODS',
 CDS_LIB='mstr_discrete',
 CDS_PART_NAME='RES_0402-1.00K,1%,1/16W,CHIP,GA',
 PRIM_FILE='./archive_libs/mstr_discrete/res/chips/chips.prt';

PART_NAME
 R25W170 'RES_0402-1.00K,1%,1/16W,CHIP,GA':
 ROOM='PROC_RSTS_PGOODS';

SECTION_NUMBER 1
 '@BASEBOARD_FAB2_LIB.BASEBOARD_FAB2(SCH_1):PAGE269_I13@MSTR_DISCRETE.RES(CHIPS)':
 C_PATH='@baseboard_fab2_lib.baseboard_fab2(sch_1):page269_i13@mstr_discrete.res~
(chips)',
 P_PATH='@baseboard_fab2_lib.baseboard_fab2(sch_1):page254_i13@mstr_discrete.res~
(chips)',
 PATH='I13',
 DRAWING='@BASEBOARD_FAB2_LIB.BASEBOARD_FAB2(SCH_1):PAGE269',
 WATTAGE='1/16W',
 TOLERANCE='1%',
 MATERIAL='CHIP',
 BOM_COST='PROC_SIDEBAND',
 PHYS_PAGE='254',
 XY='(-4750,3900)',
 ROT='1',
 VER='2',
 VALUE='1.00K',
 PACK_TYPE='0402',
 PART_NUMBER='G21796-026',
 LOCATION='R25W170',
 ROOM='PROC_RSTS_PGOODS',
 CDS_LIB='mstr_discrete',
 CDS_PART_NAME='RES_0402-1.00K,1%,1/16W,CHIP,GA',
 PRIM_FILE='./archive_libs/mstr_discrete/res/chips/chips.prt';

PART_NAME
 R25W174 'RES_0402-10.0K,1%,1/16W,CHIP,GA':
 ROOM='CPU0';

SECTION_NUMBER 1
 '@BASEBOARD_FAB2_LIB.BASEBOARD_FAB2(SCH_1):PAGE269_I4@MSTR_DISCRETE.RES(CHIPS)':
 C_PATH='@baseboard_fab2_lib.baseboard_fab2(sch_1):page269_i4@mstr_discrete.res(~
chips)',
 P_PATH='@baseboard_fab2_lib.baseboard_fab2(sch_1):page254_i4@mstr_discrete.res(~
chips)',
 PATH='I4',
 DRAWING='@BASEBOARD_FAB2_LIB.BASEBOARD_FAB2(SCH_1):PAGE269',
 WATTAGE='1/16W',
 TOLERANCE='1%',
 SEC_TYPE='0402',
 MATERIAL='CHIP',
 BOM_COST='PROC_SIDEBAND',
 PHYS_PAGE='254',
 XY='(-6400,3850)',
 ROT='0',
 VER='2',
 VALUE='10.0K',
 PACK_TYPE='0402',
 PART_NUMBER='G21796-016',
 LOCATION='R25W174',
 ROOM='CPU0',
 SEC='1',
 CDS_LIB='mstr_discrete',
 CDS_PART_NAME='RES_0402-10.0K,1%,1/16W,CHIP,GA',
 PRIM_FILE='./archive_libs/mstr_discrete/res/chips/chips.prt';

PART_NAME
 R25W175 'RES_0402-1.00K,1%,1/16W,CHIP,GA':
 ROOM='PROC_RSTS_PGOODS';

SECTION_NUMBER 1
 '@BASEBOARD_FAB2_LIB.BASEBOARD_FAB2(SCH_1):PAGE268_I17@MSTR_DISCRETE.RES(CHIPS)':
 C_PATH='@baseboard_fab2_lib.baseboard_fab2(sch_1):page268_i17@mstr_discrete.res~
(chips)',
 P_PATH='@baseboard_fab2_lib.baseboard_fab2(sch_1):page255_i17@mstr_discrete.res~
(chips)',
 PATH='I17',
 DRAWING='@BASEBOARD_FAB2_LIB.BASEBOARD_FAB2(SCH_1):PAGE268',
 WATTAGE='1/16W',
 TOLERANCE='1%',
 MATERIAL='CHIP',
 BOM_COST='PROC_SIDEBAND',
 PHYS_PAGE='255',
 XY='(-8150,4950)',
 ROT='0',
 VER='2',
 VALUE='1.00K',
 PACK_TYPE='0402',
 PART_NUMBER='G21796-026',
 LOCATION='R25W175',
 ROOM='PROC_RSTS_PGOODS',
 CDS_LIB='mstr_discrete',
 CDS_PART_NAME='RES_0402-1.00K,1%,1/16W,CHIP,GA',
 PRIM_FILE='./archive_libs/mstr_discrete/res/chips/chips.prt';

PART_NAME
 R25W176 'RES_0402-1.00K,1%,1/16W,CHIP,GA':
 ROOM='PROC_RSTS_PGOODS';

SECTION_NUMBER 1
 '@BASEBOARD_FAB2_LIB.BASEBOARD_FAB2(SCH_1):PAGE268_I14@MSTR_DISCRETE.RES(CHIPS)':
 C_PATH='@baseboard_fab2_lib.baseboard_fab2(sch_1):page268_i14@mstr_discrete.res~
(chips)',
 P_PATH='@baseboard_fab2_lib.baseboard_fab2(sch_1):page255_i14@mstr_discrete.res~
(chips)',
 PATH='I14',
 DRAWING='@BASEBOARD_FAB2_LIB.BASEBOARD_FAB2(SCH_1):PAGE268',
 WATTAGE='1/16W',
 TOLERANCE='1%',
 MATERIAL='CHIP',
 BOM_COST='PROC_SIDEBAND',
 PHYS_PAGE='255',
 XY='(-8450,4950)',
 ROT='0',
 VER='2',
 VALUE='1.00K',
 PACK_TYPE='0402',
 PART_NUMBER='G21796-026',
 LOCATION='R25W176',
 ROOM='PROC_RSTS_PGOODS',
 CDS_LIB='mstr_discrete',
 CDS_PART_NAME='RES_0402-1.00K,1%,1/16W,CHIP,GA',
 PRIM_FILE='./archive_libs/mstr_discrete/res/chips/chips.prt';

PART_NAME
 R25W177 'RES_0402-1.00K,1%,1/16W,CHIP,GA':
 ROOM='PROC_RSTS_PGOODS';

SECTION_NUMBER 1
 '@BASEBOARD_FAB2_LIB.BASEBOARD_FAB2(SCH_1):PAGE269_I18@MSTR_DISCRETE.RES(CHIPS)':
 C_PATH='@baseboard_fab2_lib.baseboard_fab2(sch_1):page269_i18@mstr_discrete.res~
(chips)',
 P_PATH='@baseboard_fab2_lib.baseboard_fab2(sch_1):page254_i18@mstr_discrete.res~
(chips)',
 PATH='I18',
 DRAWING='@BASEBOARD_FAB2_LIB.BASEBOARD_FAB2(SCH_1):PAGE269',
 WATTAGE='1/16W',
 TOLERANCE='1%',
 MATERIAL='CHIP',
 BOM_COST='PROC_SIDEBAND',
 PHYS_PAGE='254',
 XY='(-7650,6050)',
 ROT='0',
 VER='2',
 VALUE='1.00K',
 PACK_TYPE='0402',
 PART_NUMBER='G21796-026',
 LOCATION='R25W177',
 ROOM='PROC_RSTS_PGOODS',
 CDS_LIB='mstr_discrete',
 CDS_PART_NAME='RES_0402-1.00K,1%,1/16W,CHIP,GA',
 PRIM_FILE='./archive_libs/mstr_discrete/res/chips/chips.prt';

PART_NAME
 R25W178 'RES_0402-1.00K,1%,1/16W,CHIP,GA':
 ROOM='PROC_RSTS_PGOODS';

SECTION_NUMBER 1
 '@BASEBOARD_FAB2_LIB.BASEBOARD_FAB2(SCH_1):PAGE269_I19@MSTR_DISCRETE.RES(CHIPS)':
 C_PATH='@baseboard_fab2_lib.baseboard_fab2(sch_1):page269_i19@mstr_discrete.res~
(chips)',
 P_PATH='@baseboard_fab2_lib.baseboard_fab2(sch_1):page254_i19@mstr_discrete.res~
(chips)',
 PATH='I19',
 DRAWING='@BASEBOARD_FAB2_LIB.BASEBOARD_FAB2(SCH_1):PAGE269',
 WATTAGE='1/16W',
 TOLERANCE='1%',
 MATERIAL='CHIP',
 BOM_COST='PROC_SIDEBAND',
 PHYS_PAGE='254',
 XY='(-7350,6050)',
 ROT='0',
 VER='2',
 VALUE='1.00K',
 PACK_TYPE='0402',
 PART_NUMBER='G21796-026',
 LOCATION='R25W178',
 ROOM='PROC_RSTS_PGOODS',
 CDS_LIB='mstr_discrete',
 CDS_PART_NAME='RES_0402-1.00K,1%,1/16W,CHIP,GA',
 PRIM_FILE='./archive_libs/mstr_discrete/res/chips/chips.prt';

PART_NAME
 R25W179 'RES_0402-1.00K,1%,1/16W,CHIP,GA':
 ROOM='PROC_RSTS_PGOODS';

SECTION_NUMBER 1
 '@BASEBOARD_FAB2_LIB.BASEBOARD_FAB2(SCH_1):PAGE268_I7@MSTR_DISCRETE.RES(CHIPS)':
 C_PATH='@baseboard_fab2_lib.baseboard_fab2(sch_1):page268_i7@mstr_discrete.res(~
chips)',
 P_PATH='@baseboard_fab2_lib.baseboard_fab2(sch_1):page255_i7@mstr_discrete.res(~
chips)',
 PATH='I7',
 DRAWING='@BASEBOARD_FAB2_LIB.BASEBOARD_FAB2(SCH_1):PAGE268',
 WATTAGE='1/16W',
 TOLERANCE='1%',
 MATERIAL='CHIP',
 BOM_COST='PROC_SIDEBAND',
 PHYS_PAGE='255',
 XY='(-7100,4150)',
 ROT='0',
 VER='2',
 VALUE='1.00K',
 PACK_TYPE='0402',
 PART_NUMBER='G21796-026',
 LOCATION='R25W179',
 ROOM='PROC_RSTS_PGOODS',
 CDS_LIB='mstr_discrete',
 CDS_PART_NAME='RES_0402-1.00K,1%,1/16W,CHIP,GA',
 PRIM_FILE='./archive_libs/mstr_discrete/res/chips/chips.prt';

PART_NAME
 R25W180 'RES_0402-1.00K,1%,1/16W,CHIP,GA':
 ROOM='PROC_RSTS_PGOODS';

SECTION_NUMBER 1
 '@BASEBOARD_FAB2_LIB.BASEBOARD_FAB2(SCH_1):PAGE268_I2@MSTR_DISCRETE.RES(CHIPS)':
 C_PATH='@baseboard_fab2_lib.baseboard_fab2(sch_1):page268_i2@mstr_discrete.res(~
chips)',
 P_PATH='@baseboard_fab2_lib.baseboard_fab2(sch_1):page255_i2@mstr_discrete.res(~
chips)',
 PATH='I2',
 DRAWING='@BASEBOARD_FAB2_LIB.BASEBOARD_FAB2(SCH_1):PAGE268',
 WATTAGE='1/16W',
 TOLERANCE='1%',
 MATERIAL='CHIP',
 BOM_COST='PROC_SIDEBAND',
 PHYS_PAGE='255',
 XY='(-7100,3350)',
 ROT='0',
 VER='2',
 VALUE='1.00K',
 PACK_TYPE='0402',
 PART_NUMBER='G21796-026',
 LOCATION='R25W180',
 ROOM='PROC_RSTS_PGOODS',
 CDS_LIB='mstr_discrete',
 CDS_PART_NAME='RES_0402-1.00K,1%,1/16W,CHIP,GA',
 PRIM_FILE='./archive_libs/mstr_discrete/res/chips/chips.prt';

PART_NAME
 R25W181 'RES_0402-0.0,5%,1/16W,CHIP,G21A':
 ROOM='DEBUG';

SECTION_NUMBER 1
 '@BASEBOARD_FAB2_LIB.BASEBOARD_FAB2(SCH_1):PAGE147_I173@MSTR_DISCRETE.RES(CHIPS)':
 C_PATH='@baseboard_fab2_lib.baseboard_fab2(sch_1):page147_i173@mstr_discrete.re~
s(chips)',
 P_PATH='@baseboard_fab2_lib.baseboard_fab2(sch_1):page147_i173@mstr_discrete.re~
s(chips)',
 PATH='I173',
 DRAWING='@BASEBOARD_FAB2_LIB.BASEBOARD_FAB2(SCH_1):PAGE147',
 WATTAGE='1/16W',
 TOLERANCE='5%',
 SEC_TYPE='0402',
 MATERIAL='CHIP',
 PHYS_PAGE='147',
 XY='(-4150,3100)',
 ROT='0',
 VER='1',
 VALUE='0.0',
 PACK_TYPE='0402',
 PART_NUMBER='G21497-005',
 LOCATION='R25W181',
 ROOM='DEBUG',
 SEC='1',
 CDS_LIB='mstr_discrete',
 CDS_PART_NAME='RES_0402-0.0,5%,1/16W,CHIP,G21A',
 PRIM_FILE='./archive_libs/mstr_discrete/res/chips/chips.prt';

PART_NAME
 R25W182 'RES_0402-0.0,5%,1/16W,CHIP,G21A':
 ROOM='DEBUG';

SECTION_NUMBER 1
 '@BASEBOARD_FAB2_LIB.BASEBOARD_FAB2(SCH_1):PAGE144_I151@MSTR_DISCRETE.RES(CHIPS)':
 C_PATH='@baseboard_fab2_lib.baseboard_fab2(sch_1):page144_i151@mstr_discrete.re~
s(chips)',
 P_PATH='@baseboard_fab2_lib.baseboard_fab2(sch_1):page144_i151@mstr_discrete.re~
s(chips)',
 PATH='I151',
 DRAWING='@BASEBOARD_FAB2_LIB.BASEBOARD_FAB2(SCH_1):PAGE144',
 POP='NOPOP',
 WATTAGE='1/16W',
 TOLERANCE='5%',
 SEC_TYPE='0402',
 MATERIAL='CHIP',
 PHYS_PAGE='144',
 XY='(-6700,-4050)',
 ROT='0',
 VER='1',
 VALUE='0.0',
 PACK_TYPE='0402',
 PART_NUMBER='G21497-005',
 LOCATION='R25W182',
 ROOM='DEBUG',
 SEC='1',
 CDS_LIB='mstr_discrete',
 CDS_PART_NAME='RES_0402-0.0,5%,1/16W,CHIP,G21A',
 PRIM_FILE='./archive_libs/mstr_discrete/res/chips/chips.prt';

PART_NAME
 R25W183 '374R2F-1-GP_SMD-RG-374R2F-1-GPA':;

SECTION_NUMBER 1
 '@BASEBOARD_FAB2_LIB.BASEBOARD_FAB2(SCH_1):PAGE268_I36@W_HDL.374R2F-1-GP(CHIPS)':
 C_PATH='@baseboard_fab2_lib.baseboard_fab2(sch_1):page268_i36@w_hdl.\374r2f-1-g~
p\(chips)',
 P_PATH='@baseboard_fab2_lib.baseboard_fab2(sch_1):page255_i36@w_hdl.\374r2f-1-g~
p\(chips)',
 PATH='I36',
 DRAWING='@BASEBOARD_FAB2_LIB.BASEBOARD_FAB2(SCH_1):PAGE268',
 PACK_SIZE='0402',
 RATED='1/16W',
 ATTRIBUTE='374 OHM',
 TOLERANCE='1%',
 PHYS_PAGE='255',
 XY='(-5150,6225)',
 ROT='0',
 VER='1',
 VALUE='374R2F-1-GP',
 PACK_TYPE='SMD-RG',
 PART_NUMBER='64.37405.6DL',
 LOCATION='R25W183',
 CDS_LIB='w_hdl',
 CDS_PART_NAME='374R2F-1-GP_SMD-RG-374R2F-1-GPA',
 PRIM_FILE='C:/<user>/w_hdl/374r2f#2d1#2dgp/chips/chips.prt';

PART_NAME
 R25W184 'RES_0402-0.0,5%,1/16W,CHIP,G21A':
 ROOM='BMC';

SECTION_NUMBER 1
 '@BASEBOARD_FAB2_LIB.BASEBOARD_FAB2(SCH_1):PAGE146_I166@MSTR_DISCRETE.RES(CHIPS)':
 C_PATH='@baseboard_fab2_lib.baseboard_fab2(sch_1):page146_i166@mstr_discrete.re~
s(chips)',
 P_PATH='@baseboard_fab2_lib.baseboard_fab2(sch_1):page146_i166@mstr_discrete.re~
s(chips)',
 PATH='I166',
 DRAWING='@BASEBOARD_FAB2_LIB.BASEBOARD_FAB2(SCH_1):PAGE146',
 WATTAGE='1/16W',
 TOLERANCE='5%',
 SEC_TYPE='0402',
 MATERIAL='CHIP',
 BOM_COST='SM_CONTROLLER',
 PHYS_PAGE='146',
 XY='(-1600,1800)',
 ROT='0',
 VER='1',
 VALUE='0.0',
 PACK_TYPE='0402',
 PART_NUMBER='G21497-005',
 LOCATION='R25W184',
 ROOM='BMC',
 SEC='1',
 CDS_LIB='mstr_discrete',
 CDS_PART_NAME='RES_0402-0.0,5%,1/16W,CHIP,G21A',
 PRIM_FILE='./archive_libs/mstr_discrete/res/chips/chips.prt';

PART_NAME
 R25W185 'RES_0402-4.75K,1%,1/16W,CHIP,GA':
 ROOM='BMC_MISC';

SECTION_NUMBER 1
 '@BASEBOARD_FAB2_LIB.BASEBOARD_FAB2(SCH_1):PAGE268_I54@MSTR_DISCRETE.RES(CHIPS)':
 C_PATH='@baseboard_fab2_lib.baseboard_fab2(sch_1):page268_i54@mstr_discrete.res~
(chips)',
 P_PATH='@baseboard_fab2_lib.baseboard_fab2(sch_1):page255_i54@mstr_discrete.res~
(chips)',
 PATH='I54',
 DRAWING='@BASEBOARD_FAB2_LIB.BASEBOARD_FAB2(SCH_1):PAGE268',
 WATTAGE='1/16W',
 TOLERANCE='1%',
 SEC_TYPE='0402',
 MATERIAL='CHIP',
 BOM_COST='SM_CONTROLLER',
 PHYS_PAGE='255',
 XY='(-3550,3500)',
 ROT='0',
 VER='2',
 VALUE='4.75K',
 PACK_TYPE='0402',
 PART_NUMBER='G21796-072',
 LOCATION='R25W185',
 ROOM='BMC_MISC',
 SEC='1',
 CDS_LIB='mstr_discrete',
 CDS_PART_NAME='RES_0402-4.75K,1%,1/16W,CHIP,GA',
 PRIM_FILE='./archive_libs/mstr_discrete/res/chips/chips.prt';

PART_NAME
 R25W186 'RES_0402-0.0,5%,1/16W,CHIP,G21A':
 ROOM='BMC_DEBUG_HEADER';

SECTION_NUMBER 1
 '@BASEBOARD_FAB2_LIB.BASEBOARD_FAB2(SCH_1):PAGE189_I77@MSTR_DISCRETE.RES(CHIPS)':
 C_PATH='@baseboard_fab2_lib.baseboard_fab2(sch_1):page189_i77@mstr_discrete.res~
(chips)',
 P_PATH='@baseboard_fab2_lib.baseboard_fab2(sch_1):page189_i77@mstr_discrete.res~
(chips)',
 PATH='I77',
 DRAWING='@BASEBOARD_FAB2_LIB.BASEBOARD_FAB2(SCH_1):PAGE189',
 WATTAGE='1/16W',
 TOLERANCE='5%',
 SEC_TYPE='0402',
 MATERIAL='CHIP',
 BOM_COST='DEBUG',
 PHYS_PAGE='189',
 XY='(-50,1800)',
 ROT='0',
 VER='1',
 VALUE='0.0',
 PACK_TYPE='0402',
 PART_NUMBER='G21497-005',
 LOCATION='R25W186',
 ROOM='BMC_DEBUG_HEADER',
 SEC='1',
 CDS_LIB='mstr_discrete',
 CDS_PART_NAME='RES_0402-0.0,5%,1/16W,CHIP,G21A',
 PRIM_FILE='./archive_libs/mstr_discrete/res/chips/chips.prt';

PART_NAME
 R25W187 'RES_0402-0.0,5%,1/16W,CHIP,G21A':
 ROOM='CPU0';

SECTION_NUMBER 1
 '@BASEBOARD_FAB2_LIB.BASEBOARD_FAB2(SCH_1):PAGE268_I66@MSTR_DISCRETE.RES(CHIPS)':
 C_PATH='@baseboard_fab2_lib.baseboard_fab2(sch_1):page268_i66@mstr_discrete.res~
(chips)',
 P_PATH='@baseboard_fab2_lib.baseboard_fab2(sch_1):page255_i66@mstr_discrete.res~
(chips)',
 PATH='I66',
 DRAWING='@BASEBOARD_FAB2_LIB.BASEBOARD_FAB2(SCH_1):PAGE268',
 WATTAGE='1/16W',
 TOLERANCE='5%',
 SEC_TYPE='0402',
 MATERIAL='CHIP',
 BOM_COST='PROC_SIDEBAND',
 PHYS_PAGE='255',
 XY='(-6000,5300)',
 ROT='0',
 VER='1',
 VALUE='0.0',
 PACK_TYPE='0402',
 PART_NUMBER='G21497-005',
 LOCATION='R25W187',
 ROOM='CPU0',
 SEC='1',
 CDS_LIB='mstr_discrete',
 CDS_PART_NAME='RES_0402-0.0,5%,1/16W,CHIP,G21A',
 PRIM_FILE='./archive_libs/mstr_discrete/res/chips/chips.prt';

PART_NAME
 R30W1 'RES_0402-0.0,5%,1/16W,CHIP,G21A':
 ROOM='PROC_SIDEBAND';

SECTION_NUMBER 1
 '@BASEBOARD_FAB2_LIB.BASEBOARD_FAB2(SCH_1):PAGE253_I13@MSTR_DISCRETE.RES(CHIPS)':
 C_PATH='@baseboard_fab2_lib.baseboard_fab2(sch_1):page253_i13@mstr_discrete.res~
(chips)',
 P_PATH='@baseboard_fab2_lib.baseboard_fab2(sch_1):page253_i13@mstr_discrete.res~
(chips)',
 PATH='I13',
 DRAWING='@BASEBOARD_FAB2_LIB.BASEBOARD_FAB2(SCH_1):PAGE253',
 WATTAGE='1/16W',
 TOLERANCE='5%',
 SEC_TYPE='0402',
 MATERIAL='CHIP',
 BOM_COST='PROC',
 PHYS_PAGE='253',
 XY='(-5350,3000)',
 ROT='0',
 VER='1',
 VALUE='0.0',
 PACK_TYPE='0402',
 PART_NUMBER='G21497-005',
 LOCATION='R30W1',
 ROOM='PROC_SIDEBAND',
 SEC='1',
 CDS_LIB='mstr_discrete',
 CDS_PART_NAME='RES_0402-0.0,5%,1/16W,CHIP,G21A',
 PRIM_FILE='./archive_libs/mstr_discrete/res/chips/chips.prt';

PART_NAME
 R30W2 'RES_0402-0.0,5%,1/16W,CHIP,G21A':
 ROOM='PROC_SIDEBAND';

SECTION_NUMBER 1
 '@BASEBOARD_FAB2_LIB.BASEBOARD_FAB2(SCH_1):PAGE253_I12@MSTR_DISCRETE.RES(CHIPS)':
 C_PATH='@baseboard_fab2_lib.baseboard_fab2(sch_1):page253_i12@mstr_discrete.res~
(chips)',
 P_PATH='@baseboard_fab2_lib.baseboard_fab2(sch_1):page253_i12@mstr_discrete.res~
(chips)',
 PATH='I12',
 DRAWING='@BASEBOARD_FAB2_LIB.BASEBOARD_FAB2(SCH_1):PAGE253',
 WATTAGE='1/16W',
 TOLERANCE='5%',
 SEC_TYPE='0402',
 MATERIAL='CHIP',
 BOM_COST='PROC',
 PHYS_PAGE='253',
 XY='(-5350,3950)',
 ROT='0',
 VER='1',
 VALUE='0.0',
 PACK_TYPE='0402',
 PART_NUMBER='G21497-005',
 LOCATION='R30W2',
 ROOM='PROC_SIDEBAND',
 SEC='1',
 CDS_LIB='mstr_discrete',
 CDS_PART_NAME='RES_0402-0.0,5%,1/16W,CHIP,G21A',
 PRIM_FILE='./archive_libs/mstr_discrete/res/chips/chips.prt';

PART_NAME
 R30W3 'RES_0402-0.0,5%,1/16W,CHIP,G21A':
 ROOM='PROC_SIDEBAND';

SECTION_NUMBER 1
 '@BASEBOARD_FAB2_LIB.BASEBOARD_FAB2(SCH_1):PAGE253_I15@MSTR_DISCRETE.RES(CHIPS)':
 C_PATH='@baseboard_fab2_lib.baseboard_fab2(sch_1):page253_i15@mstr_discrete.res~
(chips)',
 P_PATH='@baseboard_fab2_lib.baseboard_fab2(sch_1):page253_i15@mstr_discrete.res~
(chips)',
 PATH='I15',
 DRAWING='@BASEBOARD_FAB2_LIB.BASEBOARD_FAB2(SCH_1):PAGE253',
 WATTAGE='1/16W',
 TOLERANCE='5%',
 SEC_TYPE='0402',
 MATERIAL='CHIP',
 BOM_COST='PROC',
 PHYS_PAGE='253',
 XY='(-5350,1750)',
 ROT='0',
 VER='1',
 VALUE='0.0',
 PACK_TYPE='0402',
 PART_NUMBER='G21497-005',
 LOCATION='R30W3',
 ROOM='PROC_SIDEBAND',
 SEC='1',
 CDS_LIB='mstr_discrete',
 CDS_PART_NAME='RES_0402-0.0,5%,1/16W,CHIP,G21A',
 PRIM_FILE='./archive_libs/mstr_discrete/res/chips/chips.prt';

PART_NAME
 R30W4 'RES_0402-0.0,5%,1/16W,CHIP,G21A':
 ROOM='PROC_SIDEBAND';

SECTION_NUMBER 1
 '@BASEBOARD_FAB2_LIB.BASEBOARD_FAB2(SCH_1):PAGE253_I14@MSTR_DISCRETE.RES(CHIPS)':
 C_PATH='@baseboard_fab2_lib.baseboard_fab2(sch_1):page253_i14@mstr_discrete.res~
(chips)',
 P_PATH='@baseboard_fab2_lib.baseboard_fab2(sch_1):page253_i14@mstr_discrete.res~
(chips)',
 PATH='I14',
 DRAWING='@BASEBOARD_FAB2_LIB.BASEBOARD_FAB2(SCH_1):PAGE253',
 WATTAGE='1/16W',
 TOLERANCE='5%',
 SEC_TYPE='0402',
 MATERIAL='CHIP',
 BOM_COST='PROC',
 PHYS_PAGE='253',
 XY='(-5350,2700)',
 ROT='0',
 VER='1',
 VALUE='0.0',
 PACK_TYPE='0402',
 PART_NUMBER='G21497-005',
 LOCATION='R30W4',
 ROOM='PROC_SIDEBAND',
 SEC='1',
 CDS_LIB='mstr_discrete',
 CDS_PART_NAME='RES_0402-0.0,5%,1/16W,CHIP,G21A',
 PRIM_FILE='./archive_libs/mstr_discrete/res/chips/chips.prt';

PART_NAME
 R32W1 'RES_0402-4.02K,1%,1/16W,CHIP,GA':
 ROOM='PVCCIN_CPU1_VR';

SECTION_NUMBER 1
 '@BASEBOARD_FAB2_LIB.BASEBOARD_FAB2(SCH_1):PAGE185_I208@MSTR_DISCRETE.RES(CHIPS)':
 C_PATH='@baseboard_fab2_lib.baseboard_fab2(sch_1):page185_i208@mstr_discrete.re~
s(chips)',
 P_PATH='@baseboard_fab2_lib.baseboard_fab2(sch_1):page185_i208@mstr_discrete.re~
s(chips)',
 PATH='I208',
 DRAWING='@BASEBOARD_FAB2_LIB.BASEBOARD_FAB2(SCH_1):PAGE185',
 WATTAGE='1/16W',
 TOLERANCE='1%',
 SEC_TYPE='0402',
 MATERIAL='CHIP',
 PHYS_PAGE='185',
 XY='(-7800,1950)',
 ROT='0',
 VER='2',
 VALUE='4.02K',
 PACK_TYPE='0402',
 PART_NUMBER='G21796-082',
 LOCATION='R32W1',
 ROOM='PVCCIN_CPU1_VR',
 SEC='1',
 CDS_LIB='mstr_discrete',
 CDS_PART_NAME='RES_0402-4.02K,1%,1/16W,CHIP,GA',
 PRIM_FILE='./archive_libs/mstr_discrete/res/chips/chips.prt';

PART_NAME
 R32W2 'RES_0402-1.5K,1%,1/16W,CHIP,G2A':
 ROOM='PVCCIN_CPU0_VR';

SECTION_NUMBER 1
 '@BASEBOARD_FAB2_LIB.BASEBOARD_FAB2(SCH_1):PAGE185_I207@MSTR_DISCRETE.RES(CHIPS)':
 C_PATH='@baseboard_fab2_lib.baseboard_fab2(sch_1):page185_i207@mstr_discrete.re~
s(chips)',
 P_PATH='@baseboard_fab2_lib.baseboard_fab2(sch_1):page185_i207@mstr_discrete.re~
s(chips)',
 PATH='I207',
 DRAWING='@BASEBOARD_FAB2_LIB.BASEBOARD_FAB2(SCH_1):PAGE185',
 WATTAGE='1/16W',
 TOLERANCE='1%',
 SEC_TYPE='0402',
 MATERIAL='CHIP',
 PHYS_PAGE='185',
 XY='(-7800,1650)',
 ROT='0',
 VER='2',
 VALUE='1.5K',
 PACK_TYPE='0402',
 PART_NUMBER='G21796-003',
 LOCATION='R32W2',
 ROOM='PVCCIN_CPU0_VR',
 SEC='1',
 CDS_LIB='mstr_discrete',
 CDS_PART_NAME='RES_0402-1.5K,1%,1/16W,CHIP,G2A',
 PRIM_FILE='./archive_libs/mstr_discrete/res/chips/chips.prt';

PART_NAME
 R32W3 'RES_0402-3.3K,5%,1/16W,CHIP,G2A':;

SECTION_NUMBER 1
 '@BASEBOARD_FAB2_LIB.BASEBOARD_FAB2(SCH_1):PAGE185_I206@MSTR_DISCRETE.RES(CHIPS)':
 C_PATH='@baseboard_fab2_lib.baseboard_fab2(sch_1):page185_i206@mstr_discrete.re~
s(chips)',
 P_PATH='@baseboard_fab2_lib.baseboard_fab2(sch_1):page185_i206@mstr_discrete.re~
s(chips)',
 PATH='I206',
 DRAWING='@BASEBOARD_FAB2_LIB.BASEBOARD_FAB2(SCH_1):PAGE185',
 WATTAGE='1/16W',
 TOLERANCE='5%',
 SEC_TYPE='0402',
 MATERIAL='CHIP',
 PHYS_PAGE='185',
 XY='(-7800,1350)',
 ROT='5',
 VER='1',
 VALUE='3.3K',
 PACK_TYPE='0402',
 PART_NUMBER='G21497-013',
 LOCATION='R32W3',
 SEC='1',
 CDS_LIB='mstr_discrete',
 CDS_PART_NAME='RES_0402-3.3K,5%,1/16W,CHIP,G2A',
 PRIM_FILE='./archive_libs/mstr_discrete/res/chips/chips.prt';

PART_NAME
 R32W4 'RES_0402-49.9K,1%,1/16W,CHIP,GA':
 ROOM='V_SUPER';

SECTION_NUMBER 1
 '@BASEBOARD_FAB2_LIB.BASEBOARD_FAB2(SCH_1):PAGE185_I211@MSTR_DISCRETE.RES(CHIPS)':
 C_PATH='@baseboard_fab2_lib.baseboard_fab2(sch_1):page185_i211@mstr_discrete.re~
s(chips)',
 P_PATH='@baseboard_fab2_lib.baseboard_fab2(sch_1):page185_i211@mstr_discrete.re~
s(chips)',
 PATH='I211',
 DRAWING='@BASEBOARD_FAB2_LIB.BASEBOARD_FAB2(SCH_1):PAGE185',
 POP='NOPOP',
 WATTAGE='1/16W',
 TOLERANCE='1%',
 SEC_TYPE='0402',
 MATERIAL='CHIP',
 PHYS_PAGE='185',
 XY='(-7900,900)',
 ROT='0',
 VER='2',
 VALUE='49.9K',
 PACK_TYPE='0402',
 PART_NUMBER='G21796-048',
 LOCATION='R32W4',
 ROOM='V_SUPER',
 SEC='1',
 CDS_LIB='mstr_discrete',
 CDS_PART_NAME='RES_0402-49.9K,1%,1/16W,CHIP,GA',
 PRIM_FILE='./archive_libs/mstr_discrete/res/chips/chips.prt';

PART_NAME
 R32W5 'RES_0402-2.0K,1%,1/16W,CHIP,G2A':
 ROOM='SMBUS';

SECTION_NUMBER 1
 '@BASEBOARD_FAB2_LIB.BASEBOARD_FAB2(SCH_1):PAGE185_I216@MSTR_DISCRETE.RES(CHIPS)':
 C_PATH='@baseboard_fab2_lib.baseboard_fab2(sch_1):page185_i216@mstr_discrete.re~
s(chips)',
 P_PATH='@baseboard_fab2_lib.baseboard_fab2(sch_1):page185_i216@mstr_discrete.re~
s(chips)',
 PATH='I216',
 DRAWING='@BASEBOARD_FAB2_LIB.BASEBOARD_FAB2(SCH_1):PAGE185',
 WATTAGE='1/16W',
 TOLERANCE='1%',
 SEC_TYPE='0402',
 MATERIAL='CHIP',
 BOM_COST='SM_CONTROLLER',
 PHYS_PAGE='185',
 XY='(-5750,1150)',
 ROT='0',
 VER='2',
 VALUE='2.0K',
 PACK_TYPE='0402',
 PART_NUMBER='G21796-001',
 LOCATION='R32W5',
 ROOM='SMBUS',
 SEC='1',
 CDS_LIB='mstr_discrete',
 CDS_PART_NAME='RES_0402-2.0K,1%,1/16W,CHIP,G2A',
 PRIM_FILE='./archive_libs/mstr_discrete/res/chips/chips.prt';

PART_NAME
 R32W6 'RES_0402-2.0K,1%,1/16W,CHIP,G2A':
 ROOM='SMBUS';

SECTION_NUMBER 1
 '@BASEBOARD_FAB2_LIB.BASEBOARD_FAB2(SCH_1):PAGE185_I214@MSTR_DISCRETE.RES(CHIPS)':
 C_PATH='@baseboard_fab2_lib.baseboard_fab2(sch_1):page185_i214@mstr_discrete.re~
s(chips)',
 P_PATH='@baseboard_fab2_lib.baseboard_fab2(sch_1):page185_i214@mstr_discrete.re~
s(chips)',
 PATH='I214',
 DRAWING='@BASEBOARD_FAB2_LIB.BASEBOARD_FAB2(SCH_1):PAGE185',
 WATTAGE='1/16W',
 TOLERANCE='1%',
 SEC_TYPE='0402',
 MATERIAL='CHIP',
 BOM_COST='SM_CONTROLLER',
 PHYS_PAGE='185',
 XY='(-5450,1150)',
 ROT='0',
 VER='2',
 VALUE='2.0K',
 PACK_TYPE='0402',
 PART_NUMBER='G21796-001',
 LOCATION='R32W6',
 ROOM='SMBUS',
 SEC='1',
 CDS_LIB='mstr_discrete',
 CDS_PART_NAME='RES_0402-2.0K,1%,1/16W,CHIP,G2A',
 PRIM_FILE='./archive_libs/mstr_discrete/res/chips/chips.prt';

PART_NAME
 R32W7 'RES_0402-2.0K,1%,1/16W,CHIP,G2A':
 ROOM='SMBUS';

SECTION_NUMBER 1
 '@BASEBOARD_FAB2_LIB.BASEBOARD_FAB2(SCH_1):PAGE185_I215@MSTR_DISCRETE.RES(CHIPS)':
 C_PATH='@baseboard_fab2_lib.baseboard_fab2(sch_1):page185_i215@mstr_discrete.re~
s(chips)',
 P_PATH='@baseboard_fab2_lib.baseboard_fab2(sch_1):page185_i215@mstr_discrete.re~
s(chips)',
 PATH='I215',
 DRAWING='@BASEBOARD_FAB2_LIB.BASEBOARD_FAB2(SCH_1):PAGE185',
 WATTAGE='1/16W',
 TOLERANCE='1%',
 SEC_TYPE='0402',
 MATERIAL='CHIP',
 BOM_COST='SM_CONTROLLER',
 PHYS_PAGE='185',
 XY='(-5150,1150)',
 ROT='0',
 VER='2',
 VALUE='2.0K',
 PACK_TYPE='0402',
 PART_NUMBER='G21796-001',
 LOCATION='R32W7',
 ROOM='SMBUS',
 SEC='1',
 CDS_LIB='mstr_discrete',
 CDS_PART_NAME='RES_0402-2.0K,1%,1/16W,CHIP,G2A',
 PRIM_FILE='./archive_libs/mstr_discrete/res/chips/chips.prt';

PART_NAME
 R32W9 'RES_0402-10.0K,1%,1/16W,CHIP,GA':
 ROOM='CPU0';

SECTION_NUMBER 1
 '@BASEBOARD_FAB2_LIB.BASEBOARD_FAB2(SCH_1):PAGE185_I200@MSTR_DISCRETE.RES(CHIPS)':
 C_PATH='@baseboard_fab2_lib.baseboard_fab2(sch_1):page185_i200@mstr_discrete.re~
s(chips)',
 P_PATH='@baseboard_fab2_lib.baseboard_fab2(sch_1):page185_i200@mstr_discrete.re~
s(chips)',
 PATH='I200',
 DRAWING='@BASEBOARD_FAB2_LIB.BASEBOARD_FAB2(SCH_1):PAGE185',
 POP='NOPOP',
 WATTAGE='1/16W',
 TOLERANCE='1%',
 SEC_TYPE='0402',
 MATERIAL='CHIP',
 BOM_COST='PROC_SIDEBAND',
 PHYS_PAGE='185',
 XY='(-850,3450)',
 ROT='0',
 VER='2',
 VALUE='10.0K',
 PACK_TYPE='0402',
 PART_NUMBER='G21796-016',
 LOCATION='R32W9',
 ROOM='CPU0',
 SEC='1',
 CDS_LIB='mstr_discrete',
 CDS_PART_NAME='RES_0402-10.0K,1%,1/16W,CHIP,GA',
 PRIM_FILE='./archive_libs/mstr_discrete/res/chips/chips.prt';

PART_NAME
 R32W10 'RES_0402-0.0,5%,1/16W,CHIP,G21A':
 ROOM='IO_SLOT';

SECTION_NUMBER 1
 '@BASEBOARD_FAB2_LIB.BASEBOARD_FAB2(SCH_1):PAGE185_I183@MSTR_DISCRETE.RES(CHIPS)':
 C_PATH='@baseboard_fab2_lib.baseboard_fab2(sch_1):page185_i183@mstr_discrete.re~
s(chips)',
 P_PATH='@baseboard_fab2_lib.baseboard_fab2(sch_1):page185_i183@mstr_discrete.re~
s(chips)',
 PATH='I183',
 DRAWING='@BASEBOARD_FAB2_LIB.BASEBOARD_FAB2(SCH_1):PAGE185',
 WATTAGE='1/16W',
 TOLERANCE='5%',
 SEC_TYPE='0402',
 MATERIAL='CHIP',
 PHYS_PAGE='185',
 XY='(-2850,2925)',
 ROT='0',
 VER='1',
 VALUE='0.0',
 PACK_TYPE='0402',
 PART_NUMBER='G21497-005',
 LOCATION='R32W10',
 ROOM='IO_SLOT',
 SEC='1',
 CDS_LIB='mstr_discrete',
 CDS_PART_NAME='RES_0402-0.0,5%,1/16W,CHIP,G21A',
 PRIM_FILE='./archive_libs/mstr_discrete/res/chips/chips.prt';

PART_NAME
 R32W11 'RES_0402-0.0,5%,1/16W,CHIP,G21A':
 ROOM='IO_SLOT';

SECTION_NUMBER 1
 '@BASEBOARD_FAB2_LIB.BASEBOARD_FAB2(SCH_1):PAGE185_I184@MSTR_DISCRETE.RES(CHIPS)':
 C_PATH='@baseboard_fab2_lib.baseboard_fab2(sch_1):page185_i184@mstr_discrete.re~
s(chips)',
 P_PATH='@baseboard_fab2_lib.baseboard_fab2(sch_1):page185_i184@mstr_discrete.re~
s(chips)',
 PATH='I184',
 DRAWING='@BASEBOARD_FAB2_LIB.BASEBOARD_FAB2(SCH_1):PAGE185',
 WATTAGE='1/16W',
 TOLERANCE='5%',
 SEC_TYPE='0402',
 MATERIAL='CHIP',
 PHYS_PAGE='185',
 XY='(-2625,2875)',
 ROT='0',
 VER='1',
 VALUE='0.0',
 PACK_TYPE='0402',
 PART_NUMBER='G21497-005',
 LOCATION='R32W11',
 ROOM='IO_SLOT',
 SEC='1',
 CDS_LIB='mstr_discrete',
 CDS_PART_NAME='RES_0402-0.0,5%,1/16W,CHIP,G21A',
 PRIM_FILE='./archive_libs/mstr_discrete/res/chips/chips.prt';

PART_NAME
 R32W12 'RES_0402-0.0,5%,1/16W,CHIP,G21A':
 ROOM='IO_SLOT';

SECTION_NUMBER 1
 '@BASEBOARD_FAB2_LIB.BASEBOARD_FAB2(SCH_1):PAGE185_I187@MSTR_DISCRETE.RES(CHIPS)':
 C_PATH='@baseboard_fab2_lib.baseboard_fab2(sch_1):page185_i187@mstr_discrete.re~
s(chips)',
 P_PATH='@baseboard_fab2_lib.baseboard_fab2(sch_1):page185_i187@mstr_discrete.re~
s(chips)',
 PATH='I187',
 DRAWING='@BASEBOARD_FAB2_LIB.BASEBOARD_FAB2(SCH_1):PAGE185',
 WATTAGE='1/16W',
 TOLERANCE='5%',
 SEC_TYPE='0402',
 MATERIAL='CHIP',
 PHYS_PAGE='185',
 XY='(-2675,3700)',
 ROT='0',
 VER='1',
 VALUE='0.0',
 PACK_TYPE='0402',
 PART_NUMBER='G21497-005',
 LOCATION='R32W12',
 ROOM='IO_SLOT',
 SEC='1',
 CDS_LIB='mstr_discrete',
 CDS_PART_NAME='RES_0402-0.0,5%,1/16W,CHIP,G21A',
 PRIM_FILE='./archive_libs/mstr_discrete/res/chips/chips.prt';

PART_NAME
 R760 'RES_0402-0.0,5%,1/16W,CHIP,G21A':
 GROUP='PCIE_RISER',
 ROOM='PCIE_STEERING';

SECTION_NUMBER 1
 '@BASEBOARD_FAB2_LIB.BASEBOARD_FAB2(SCH_1):PAGE244_I64@MSTR_DISCRETE.RES(CHIPS)':
 C_PATH='@baseboard_fab2_lib.baseboard_fab2(sch_1):page244_i64@mstr_discrete.res~
(chips)',
 P_PATH='@baseboard_fab2_lib.baseboard_fab2(sch_1):page244_i64@mstr_discrete.res~
(chips)',
 PATH='I64',
 DRAWING='@BASEBOARD_FAB2_LIB.BASEBOARD_FAB2(SCH_1):PAGE244',
 WATTAGE='1/16W',
 TOLERANCE='5%',
 SEC_TYPE='0402',
 MATERIAL='CHIP',
 PHYS_PAGE='244',
 XY='(-3500,3025)',
 ROT='0',
 VER='2',
 VALUE='0.0',
 PACK_TYPE='0402',
 PART_NUMBER='G21497-005',
 ROOM='PCIE_STEERING',
 GROUP='PCIE_RISER',
 SEC='1',
 CDS_LIB='mstr_discrete',
 CDS_PART_NAME='RES_0402-0.0,5%,1/16W,CHIP,G21A',
 PRIM_FILE='./archive_libs/mstr_discrete/res/chips/chips.prt';

PART_NAME
 R767 'RES_0402-0.0,5%,1/16W,CHIP,G21A':
 GROUP='PCIE_RISER',
 ROOM='PCIE_STEERING';

SECTION_NUMBER 1
 '@BASEBOARD_FAB2_LIB.BASEBOARD_FAB2(SCH_1):PAGE244_I39@MSTR_DISCRETE.RES(CHIPS)':
 C_PATH='@baseboard_fab2_lib.baseboard_fab2(sch_1):page244_i39@mstr_discrete.res~
(chips)',
 P_PATH='@baseboard_fab2_lib.baseboard_fab2(sch_1):page244_i39@mstr_discrete.res~
(chips)',
 PATH='I39',
 DRAWING='@BASEBOARD_FAB2_LIB.BASEBOARD_FAB2(SCH_1):PAGE244',
 WATTAGE='1/16W',
 TOLERANCE='5%',
 SEC_TYPE='0402',
 MATERIAL='CHIP',
 PHYS_PAGE='244',
 XY='(-3425,1725)',
 ROT='0',
 VER='2',
 VALUE='0.0',
 PACK_TYPE='0402',
 PART_NUMBER='G21497-005',
 ROOM='PCIE_STEERING',
 GROUP='PCIE_RISER',
 SEC='1',
 CDS_LIB='mstr_discrete',
 CDS_PART_NAME='RES_0402-0.0,5%,1/16W,CHIP,G21A',
 PRIM_FILE='./archive_libs/mstr_discrete/res/chips/chips.prt';

PART_NAME
 R768 'RES_0402-0.0,5%,1/16W,CHIP,G21A':
 GROUP='PCIE_RISER',
 ROOM='PCIE_STEERING';

SECTION_NUMBER 1
 '@BASEBOARD_FAB2_LIB.BASEBOARD_FAB2(SCH_1):PAGE244_I66@MSTR_DISCRETE.RES(CHIPS)':
 C_PATH='@baseboard_fab2_lib.baseboard_fab2(sch_1):page244_i66@mstr_discrete.res~
(chips)',
 P_PATH='@baseboard_fab2_lib.baseboard_fab2(sch_1):page244_i66@mstr_discrete.res~
(chips)',
 PATH='I66',
 DRAWING='@BASEBOARD_FAB2_LIB.BASEBOARD_FAB2(SCH_1):PAGE244',
 WATTAGE='1/16W',
 TOLERANCE='5%',
 SEC_TYPE='0402',
 MATERIAL='CHIP',
 PHYS_PAGE='244',
 XY='(-3300,3375)',
 ROT='0',
 VER='2',
 VALUE='0.0',
 PACK_TYPE='0402',
 PART_NUMBER='G21497-005',
 ROOM='PCIE_STEERING',
 GROUP='PCIE_RISER',
 SEC='1',
 CDS_LIB='mstr_discrete',
 CDS_PART_NAME='RES_0402-0.0,5%,1/16W,CHIP,G21A',
 PRIM_FILE='./archive_libs/mstr_discrete/res/chips/chips.prt';

PART_NAME
 R769 'RES_0402-0.0,5%,1/16W,CHIP,G21A':
 GROUP='PCIE_RISER',
 ROOM='PCIE_STEERING';

SECTION_NUMBER 1
 '@BASEBOARD_FAB2_LIB.BASEBOARD_FAB2(SCH_1):PAGE244_I58@MSTR_DISCRETE.RES(CHIPS)':
 C_PATH='@baseboard_fab2_lib.baseboard_fab2(sch_1):page244_i58@mstr_discrete.res~
(chips)',
 P_PATH='@baseboard_fab2_lib.baseboard_fab2(sch_1):page244_i58@mstr_discrete.res~
(chips)',
 PATH='I58',
 DRAWING='@BASEBOARD_FAB2_LIB.BASEBOARD_FAB2(SCH_1):PAGE244',
 WATTAGE='1/16W',
 TOLERANCE='5%',
 SEC_TYPE='0402',
 MATERIAL='CHIP',
 PHYS_PAGE='244',
 XY='(-3225,2075)',
 ROT='0',
 VER='2',
 VALUE='0.0',
 PACK_TYPE='0402',
 PART_NUMBER='G21497-005',
 ROOM='PCIE_STEERING',
 GROUP='PCIE_RISER',
 SEC='1',
 CDS_LIB='mstr_discrete',
 CDS_PART_NAME='RES_0402-0.0,5%,1/16W,CHIP,G21A',
 PRIM_FILE='./archive_libs/mstr_discrete/res/chips/chips.prt';

PART_NAME
 R771 'RES_0402-0.0,5%,1/16W,CHIP,G21A':
 GROUP='PCIE_RISER',
 ROOM='PCIE_STEERING';

SECTION_NUMBER 1
 '@BASEBOARD_FAB2_LIB.BASEBOARD_FAB2(SCH_1):PAGE244_I65@MSTR_DISCRETE.RES(CHIPS)':
 C_PATH='@baseboard_fab2_lib.baseboard_fab2(sch_1):page244_i65@mstr_discrete.res~
(chips)',
 P_PATH='@baseboard_fab2_lib.baseboard_fab2(sch_1):page244_i65@mstr_discrete.res~
(chips)',
 PATH='I65',
 DRAWING='@BASEBOARD_FAB2_LIB.BASEBOARD_FAB2(SCH_1):PAGE244',
 WATTAGE='1/16W',
 TOLERANCE='5%',
 SEC_TYPE='0402',
 MATERIAL='CHIP',
 PHYS_PAGE='244',
 XY='(-3100,3025)',
 ROT='0',
 VER='2',
 VALUE='0.0',
 PACK_TYPE='0402',
 PART_NUMBER='G21497-005',
 ROOM='PCIE_STEERING',
 GROUP='PCIE_RISER',
 SEC='1',
 CDS_LIB='mstr_discrete',
 CDS_PART_NAME='RES_0402-0.0,5%,1/16W,CHIP,G21A',
 PRIM_FILE='./archive_libs/mstr_discrete/res/chips/chips.prt';

PART_NAME
 R774 'RES_0402-0.0,5%,1/16W,CHIP,G21A':
 GROUP='PCIE_RISER',
 ROOM='PCIE_STEERING';

SECTION_NUMBER 1
 '@BASEBOARD_FAB2_LIB.BASEBOARD_FAB2(SCH_1):PAGE244_I72@MSTR_DISCRETE.RES(CHIPS)':
 C_PATH='@baseboard_fab2_lib.baseboard_fab2(sch_1):page244_i72@mstr_discrete.res~
(chips)',
 P_PATH='@baseboard_fab2_lib.baseboard_fab2(sch_1):page244_i72@mstr_discrete.res~
(chips)',
 PATH='I72',
 DRAWING='@BASEBOARD_FAB2_LIB.BASEBOARD_FAB2(SCH_1):PAGE244',
 WATTAGE='1/16W',
 TOLERANCE='5%',
 SEC_TYPE='0402',
 MATERIAL='CHIP',
 PHYS_PAGE='244',
 XY='(-3025,1725)',
 ROT='0',
 VER='2',
 VALUE='0.0',
 PACK_TYPE='0402',
 PART_NUMBER='G21497-005',
 ROOM='PCIE_STEERING',
 GROUP='PCIE_RISER',
 SEC='1',
 CDS_LIB='mstr_discrete',
 CDS_PART_NAME='RES_0402-0.0,5%,1/16W,CHIP,G21A',
 PRIM_FILE='./archive_libs/mstr_discrete/res/chips/chips.prt';

PART_NAME
 R775 'RES_0402-0.0,5%,1/16W,CHIP,G21A':
 GROUP='PCIE_RISER',
 ROOM='PCIE_STEERING';

SECTION_NUMBER 1
 '@BASEBOARD_FAB2_LIB.BASEBOARD_FAB2(SCH_1):PAGE244_I93@MSTR_DISCRETE.RES(CHIPS)':
 C_PATH='@baseboard_fab2_lib.baseboard_fab2(sch_1):page244_i93@mstr_discrete.res~
(chips)',
 P_PATH='@baseboard_fab2_lib.baseboard_fab2(sch_1):page244_i93@mstr_discrete.res~
(chips)',
 PATH='I93',
 DRAWING='@BASEBOARD_FAB2_LIB.BASEBOARD_FAB2(SCH_1):PAGE244',
 WATTAGE='1/16W',
 TOLERANCE='5%',
 SEC_TYPE='0402',
 MATERIAL='CHIP',
 PHYS_PAGE='244',
 XY='(-2900,3375)',
 ROT='0',
 VER='2',
 VALUE='0.0',
 PACK_TYPE='0402',
 PART_NUMBER='G21497-005',
 ROOM='PCIE_STEERING',
 GROUP='PCIE_RISER',
 SEC='1',
 CDS_LIB='mstr_discrete',
 CDS_PART_NAME='RES_0402-0.0,5%,1/16W,CHIP,G21A',
 PRIM_FILE='./archive_libs/mstr_discrete/res/chips/chips.prt';

PART_NAME
 R777 'RES_0402-0.0,5%,1/16W,CHIP,G21A':
 GROUP='PCIE_RISER',
 ROOM='PCIE_STEERING';

SECTION_NUMBER 1
 '@BASEBOARD_FAB2_LIB.BASEBOARD_FAB2(SCH_1):PAGE244_I80@MSTR_DISCRETE.RES(CHIPS)':
 C_PATH='@baseboard_fab2_lib.baseboard_fab2(sch_1):page244_i80@mstr_discrete.res~
(chips)',
 P_PATH='@baseboard_fab2_lib.baseboard_fab2(sch_1):page244_i80@mstr_discrete.res~
(chips)',
 PATH='I80',
 DRAWING='@BASEBOARD_FAB2_LIB.BASEBOARD_FAB2(SCH_1):PAGE244',
 WATTAGE='1/16W',
 TOLERANCE='5%',
 SEC_TYPE='0402',
 MATERIAL='CHIP',
 PHYS_PAGE='244',
 XY='(-2825,2075)',
 ROT='0',
 VER='2',
 VALUE='0.0',
 PACK_TYPE='0402',
 PART_NUMBER='G21497-005',
 ROOM='PCIE_STEERING',
 GROUP='PCIE_RISER',
 SEC='1',
 CDS_LIB='mstr_discrete',
 CDS_PART_NAME='RES_0402-0.0,5%,1/16W,CHIP,G21A',
 PRIM_FILE='./archive_libs/mstr_discrete/res/chips/chips.prt';

PART_NAME
 R778 'RES_0402-0.0,5%,1/16W,CHIP,G21A':
 GROUP='PCIE_RISER',
 ROOM='PCIE_STEERING';

SECTION_NUMBER 1
 '@BASEBOARD_FAB2_LIB.BASEBOARD_FAB2(SCH_1):PAGE244_I94@MSTR_DISCRETE.RES(CHIPS)':
 C_PATH='@baseboard_fab2_lib.baseboard_fab2(sch_1):page244_i94@mstr_discrete.res~
(chips)',
 P_PATH='@baseboard_fab2_lib.baseboard_fab2(sch_1):page244_i94@mstr_discrete.res~
(chips)',
 PATH='I94',
 DRAWING='@BASEBOARD_FAB2_LIB.BASEBOARD_FAB2(SCH_1):PAGE244',
 WATTAGE='1/16W',
 TOLERANCE='5%',
 SEC_TYPE='0402',
 MATERIAL='CHIP',
 PHYS_PAGE='244',
 XY='(-2700,3025)',
 ROT='0',
 VER='2',
 VALUE='0.0',
 PACK_TYPE='0402',
 PART_NUMBER='G21497-005',
 ROOM='PCIE_STEERING',
 GROUP='PCIE_RISER',
 SEC='1',
 CDS_LIB='mstr_discrete',
 CDS_PART_NAME='RES_0402-0.0,5%,1/16W,CHIP,G21A',
 PRIM_FILE='./archive_libs/mstr_discrete/res/chips/chips.prt';

PART_NAME
 R779 'RES_0402-0.0,5%,1/16W,CHIP,G21A':
 GROUP='PCIE_RISER',
 ROOM='PCIE_STEERING';

SECTION_NUMBER 1
 '@BASEBOARD_FAB2_LIB.BASEBOARD_FAB2(SCH_1):PAGE244_I74@MSTR_DISCRETE.RES(CHIPS)':
 C_PATH='@baseboard_fab2_lib.baseboard_fab2(sch_1):page244_i74@mstr_discrete.res~
(chips)',
 P_PATH='@baseboard_fab2_lib.baseboard_fab2(sch_1):page244_i74@mstr_discrete.res~
(chips)',
 PATH='I74',
 DRAWING='@BASEBOARD_FAB2_LIB.BASEBOARD_FAB2(SCH_1):PAGE244',
 WATTAGE='1/16W',
 TOLERANCE='5%',
 SEC_TYPE='0402',
 MATERIAL='CHIP',
 PHYS_PAGE='244',
 XY='(-2625,1725)',
 ROT='0',
 VER='2',
 VALUE='0.0',
 PACK_TYPE='0402',
 PART_NUMBER='G21497-005',
 ROOM='PCIE_STEERING',
 GROUP='PCIE_RISER',
 SEC='1',
 CDS_LIB='mstr_discrete',
 CDS_PART_NAME='RES_0402-0.0,5%,1/16W,CHIP,G21A',
 PRIM_FILE='./archive_libs/mstr_discrete/res/chips/chips.prt';

PART_NAME
 R780 'RES_0402-0.0,5%,1/16W,CHIP,G21A':
 GROUP='PCIE_RISER',
 ROOM='PCIE_STEERING';

SECTION_NUMBER 1
 '@BASEBOARD_FAB2_LIB.BASEBOARD_FAB2(SCH_1):PAGE244_I97@MSTR_DISCRETE.RES(CHIPS)':
 C_PATH='@baseboard_fab2_lib.baseboard_fab2(sch_1):page244_i97@mstr_discrete.res~
(chips)',
 P_PATH='@baseboard_fab2_lib.baseboard_fab2(sch_1):page244_i97@mstr_discrete.res~
(chips)',
 PATH='I97',
 DRAWING='@BASEBOARD_FAB2_LIB.BASEBOARD_FAB2(SCH_1):PAGE244',
 WATTAGE='1/16W',
 TOLERANCE='5%',
 SEC_TYPE='0402',
 MATERIAL='CHIP',
 PHYS_PAGE='244',
 XY='(-2500,3375)',
 ROT='0',
 VER='2',
 VALUE='0.0',
 PACK_TYPE='0402',
 PART_NUMBER='G21497-005',
 ROOM='PCIE_STEERING',
 GROUP='PCIE_RISER',
 SEC='1',
 CDS_LIB='mstr_discrete',
 CDS_PART_NAME='RES_0402-0.0,5%,1/16W,CHIP,G21A',
 PRIM_FILE='./archive_libs/mstr_discrete/res/chips/chips.prt';

PART_NAME
 R781 'RES_0402-0.0,5%,1/16W,CHIP,G21A':
 GROUP='PCIE_RISER',
 ROOM='PCIE_STEERING';

SECTION_NUMBER 1
 '@BASEBOARD_FAB2_LIB.BASEBOARD_FAB2(SCH_1):PAGE244_I86@MSTR_DISCRETE.RES(CHIPS)':
 C_PATH='@baseboard_fab2_lib.baseboard_fab2(sch_1):page244_i86@mstr_discrete.res~
(chips)',
 P_PATH='@baseboard_fab2_lib.baseboard_fab2(sch_1):page244_i86@mstr_discrete.res~
(chips)',
 PATH='I86',
 DRAWING='@BASEBOARD_FAB2_LIB.BASEBOARD_FAB2(SCH_1):PAGE244',
 WATTAGE='1/16W',
 TOLERANCE='5%',
 SEC_TYPE='0402',
 MATERIAL='CHIP',
 PHYS_PAGE='244',
 XY='(-2425,2075)',
 ROT='0',
 VER='2',
 VALUE='0.0',
 PACK_TYPE='0402',
 PART_NUMBER='G21497-005',
 ROOM='PCIE_STEERING',
 GROUP='PCIE_RISER',
 SEC='1',
 CDS_LIB='mstr_discrete',
 CDS_PART_NAME='RES_0402-0.0,5%,1/16W,CHIP,G21A',
 PRIM_FILE='./archive_libs/mstr_discrete/res/chips/chips.prt';

PART_NAME
 R782 'RES_0402-0.0,5%,1/16W,CHIP,G21A':
 GROUP='PCIE_RISER',
 ROOM='PCIE_STEERING';

SECTION_NUMBER 1
 '@BASEBOARD_FAB2_LIB.BASEBOARD_FAB2(SCH_1):PAGE244_I98@MSTR_DISCRETE.RES(CHIPS)':
 C_PATH='@baseboard_fab2_lib.baseboard_fab2(sch_1):page244_i98@mstr_discrete.res~
(chips)',
 P_PATH='@baseboard_fab2_lib.baseboard_fab2(sch_1):page244_i98@mstr_discrete.res~
(chips)',
 PATH='I98',
 DRAWING='@BASEBOARD_FAB2_LIB.BASEBOARD_FAB2(SCH_1):PAGE244',
 WATTAGE='1/16W',
 TOLERANCE='5%',
 SEC_TYPE='0402',
 MATERIAL='CHIP',
 PHYS_PAGE='244',
 XY='(-2300,3025)',
 ROT='0',
 VER='2',
 VALUE='0.0',
 PACK_TYPE='0402',
 PART_NUMBER='G21497-005',
 ROOM='PCIE_STEERING',
 GROUP='PCIE_RISER',
 SEC='1',
 CDS_LIB='mstr_discrete',
 CDS_PART_NAME='RES_0402-0.0,5%,1/16W,CHIP,G21A',
 PRIM_FILE='./archive_libs/mstr_discrete/res/chips/chips.prt';

PART_NAME
 R783 'RES_0402-0.0,5%,1/16W,CHIP,G21A':
 GROUP='PCIE_RISER',
 ROOM='PCIE_STEERING';

SECTION_NUMBER 1
 '@BASEBOARD_FAB2_LIB.BASEBOARD_FAB2(SCH_1):PAGE244_I77@MSTR_DISCRETE.RES(CHIPS)':
 C_PATH='@baseboard_fab2_lib.baseboard_fab2(sch_1):page244_i77@mstr_discrete.res~
(chips)',
 P_PATH='@baseboard_fab2_lib.baseboard_fab2(sch_1):page244_i77@mstr_discrete.res~
(chips)',
 PATH='I77',
 DRAWING='@BASEBOARD_FAB2_LIB.BASEBOARD_FAB2(SCH_1):PAGE244',
 WATTAGE='1/16W',
 TOLERANCE='5%',
 SEC_TYPE='0402',
 MATERIAL='CHIP',
 PHYS_PAGE='244',
 XY='(-2225,1725)',
 ROT='0',
 VER='2',
 VALUE='0.0',
 PACK_TYPE='0402',
 PART_NUMBER='G21497-005',
 ROOM='PCIE_STEERING',
 GROUP='PCIE_RISER',
 SEC='1',
 CDS_LIB='mstr_discrete',
 CDS_PART_NAME='RES_0402-0.0,5%,1/16W,CHIP,G21A',
 PRIM_FILE='./archive_libs/mstr_discrete/res/chips/chips.prt';

PART_NAME
 R784 'RES_0402-0.0,5%,1/16W,CHIP,G21A':
 GROUP='PCIE_RISER',
 ROOM='PCIE_STEERING';

SECTION_NUMBER 1
 '@BASEBOARD_FAB2_LIB.BASEBOARD_FAB2(SCH_1):PAGE244_I99@MSTR_DISCRETE.RES(CHIPS)':
 C_PATH='@baseboard_fab2_lib.baseboard_fab2(sch_1):page244_i99@mstr_discrete.res~
(chips)',
 P_PATH='@baseboard_fab2_lib.baseboard_fab2(sch_1):page244_i99@mstr_discrete.res~
(chips)',
 PATH='I99',
 DRAWING='@BASEBOARD_FAB2_LIB.BASEBOARD_FAB2(SCH_1):PAGE244',
 WATTAGE='1/16W',
 TOLERANCE='5%',
 SEC_TYPE='0402',
 MATERIAL='CHIP',
 PHYS_PAGE='244',
 XY='(-2100,3375)',
 ROT='0',
 VER='2',
 VALUE='0.0',
 PACK_TYPE='0402',
 PART_NUMBER='G21497-005',
 ROOM='PCIE_STEERING',
 GROUP='PCIE_RISER',
 SEC='1',
 CDS_LIB='mstr_discrete',
 CDS_PART_NAME='RES_0402-0.0,5%,1/16W,CHIP,G21A',
 PRIM_FILE='./archive_libs/mstr_discrete/res/chips/chips.prt';

PART_NAME
 R785 'RES_0402-0.0,5%,1/16W,CHIP,G21A':
 GROUP='PCIE_RISER',
 ROOM='PCIE_STEERING';

SECTION_NUMBER 1
 '@BASEBOARD_FAB2_LIB.BASEBOARD_FAB2(SCH_1):PAGE244_I103@MSTR_DISCRETE.RES(CHIPS)':
 C_PATH='@baseboard_fab2_lib.baseboard_fab2(sch_1):page244_i103@mstr_discrete.re~
s(chips)',
 P_PATH='@baseboard_fab2_lib.baseboard_fab2(sch_1):page244_i103@mstr_discrete.re~
s(chips)',
 PATH='I103',
 DRAWING='@BASEBOARD_FAB2_LIB.BASEBOARD_FAB2(SCH_1):PAGE244',
 WATTAGE='1/16W',
 TOLERANCE='5%',
 SEC_TYPE='0402',
 MATERIAL='CHIP',
 PHYS_PAGE='244',
 XY='(-2025,2075)',
 ROT='0',
 VER='2',
 VALUE='0.0',
 PACK_TYPE='0402',
 PART_NUMBER='G21497-005',
 ROOM='PCIE_STEERING',
 GROUP='PCIE_RISER',
 SEC='1',
 CDS_LIB='mstr_discrete',
 CDS_PART_NAME='RES_0402-0.0,5%,1/16W,CHIP,G21A',
 PRIM_FILE='./archive_libs/mstr_discrete/res/chips/chips.prt';

PART_NAME
 RF1 'RES_0402-1.0K,0.1%,1/16W,CHIP,A':
 GROUP='POWER_FAIR',
 ROOM='SB';

SECTION_NUMBER 1
 '@BASEBOARD_FAB2_LIB.BASEBOARD_FAB2(SCH_1):PAGE201_I182@MSTR_DISCRETE.RES(CHIPS)':
 C_PATH='@baseboard_fab2_lib.baseboard_fab2(sch_1):page201_i182@mstr_discrete.re~
s(chips)',
 P_PATH='@baseboard_fab2_lib.baseboard_fab2(sch_1):page201_i182@mstr_discrete.re~
s(chips)',
 PATH='I182',
 DRAWING='@BASEBOARD_FAB2_LIB.BASEBOARD_FAB2(SCH_1):PAGE201',
 FAIR_SS='064.9530D.M001',
 WATTAGE='1/16W',
 TOLERANCE='0.1%',
 SEC_TYPE='0402',
 MATERIAL='CHIP',
 PHYS_PAGE='201',
 XY='(-6750,3500)',
 ROT='0',
 VER='1',
 VALUE='1.0K',
 PACK_TYPE='0402',
 PART_NUMBER='G85996-004',
 LOCATION='RF1',
 ROOM='SB',
 GROUP='POWER_FAIR',
 SEC='1',
 CDS_LIB='mstr_discrete',
 CDS_PART_NAME='RES_0402-1.0K,0.1%,1/16W,CHIP,A',
 PRIM_FILE='./archive_libs/mstr_discrete/res/chips/chips.prt';

PART_NAME
 RF2 'RES_0402-1.0K,0.1%,1/16W,CHIP,A':
 GROUP='POWER_FAIR',
 ROOM='SB';

SECTION_NUMBER 1
 '@BASEBOARD_FAB2_LIB.BASEBOARD_FAB2(SCH_1):PAGE201_I183@MSTR_DISCRETE.RES(CHIPS)':
 C_PATH='@baseboard_fab2_lib.baseboard_fab2(sch_1):page201_i183@mstr_discrete.re~
s(chips)',
 P_PATH='@baseboard_fab2_lib.baseboard_fab2(sch_1):page201_i183@mstr_discrete.re~
s(chips)',
 PATH='I183',
 DRAWING='@BASEBOARD_FAB2_LIB.BASEBOARD_FAB2(SCH_1):PAGE201',
 FAIR_SS='064.9530D.M001',
 WATTAGE='1/16W',
 TOLERANCE='0.1%',
 SEC_TYPE='0402',
 MATERIAL='CHIP',
 PHYS_PAGE='201',
 XY='(-6300,3500)',
 ROT='0',
 VER='1',
 VALUE='1.0K',
 PACK_TYPE='0402',
 PART_NUMBER='G85996-004',
 LOCATION='RF2',
 ROOM='SB',
 GROUP='POWER_FAIR',
 SEC='1',
 CDS_LIB='mstr_discrete',
 CDS_PART_NAME='RES_0402-1.0K,0.1%,1/16W,CHIP,A',
 PRIM_FILE='./archive_libs/mstr_discrete/res/chips/chips.prt';

PART_NAME
 RF3 'RES_0402-1.0K,0.1%,1/16W,CHIP,A':
 GROUP='POWER_FAIR',
 ROOM='SB';

SECTION_NUMBER 1
 '@BASEBOARD_FAB2_LIB.BASEBOARD_FAB2(SCH_1):PAGE201_I184@MSTR_DISCRETE.RES(CHIPS)':
 C_PATH='@baseboard_fab2_lib.baseboard_fab2(sch_1):page201_i184@mstr_discrete.re~
s(chips)',
 P_PATH='@baseboard_fab2_lib.baseboard_fab2(sch_1):page201_i184@mstr_discrete.re~
s(chips)',
 PATH='I184',
 DRAWING='@BASEBOARD_FAB2_LIB.BASEBOARD_FAB2(SCH_1):PAGE201',
 FAIR_SS='064.9530D.M001',
 WATTAGE='1/16W',
 TOLERANCE='0.1%',
 SEC_TYPE='0402',
 MATERIAL='CHIP',
 PHYS_PAGE='201',
 XY='(-5825,3500)',
 ROT='0',
 VER='1',
 VALUE='1.0K',
 PACK_TYPE='0402',
 PART_NUMBER='G85996-004',
 LOCATION='RF3',
 ROOM='SB',
 GROUP='POWER_FAIR',
 SEC='1',
 CDS_LIB='mstr_discrete',
 CDS_PART_NAME='RES_0402-1.0K,0.1%,1/16W,CHIP,A',
 PRIM_FILE='./archive_libs/mstr_discrete/res/chips/chips.prt';

PART_NAME
 RF4 'RES_0402-1.0K,0.1%,1/16W,CHIP,A':
 GROUP='POWER_FAIR',
 ROOM='SB';

SECTION_NUMBER 1
 '@BASEBOARD_FAB2_LIB.BASEBOARD_FAB2(SCH_1):PAGE201_I185@MSTR_DISCRETE.RES(CHIPS)':
 C_PATH='@baseboard_fab2_lib.baseboard_fab2(sch_1):page201_i185@mstr_discrete.re~
s(chips)',
 P_PATH='@baseboard_fab2_lib.baseboard_fab2(sch_1):page201_i185@mstr_discrete.re~
s(chips)',
 PATH='I185',
 DRAWING='@BASEBOARD_FAB2_LIB.BASEBOARD_FAB2(SCH_1):PAGE201',
 FAIR_SS='064.9530D.M001',
 WATTAGE='1/16W',
 TOLERANCE='0.1%',
 SEC_TYPE='0402',
 MATERIAL='CHIP',
 PHYS_PAGE='201',
 XY='(-5425,3500)',
 ROT='0',
 VER='1',
 VALUE='1.0K',
 PACK_TYPE='0402',
 PART_NUMBER='G85996-004',
 LOCATION='RF4',
 ROOM='SB',
 GROUP='POWER_FAIR',
 SEC='1',
 CDS_LIB='mstr_discrete',
 CDS_PART_NAME='RES_0402-1.0K,0.1%,1/16W,CHIP,A',
 PRIM_FILE='./archive_libs/mstr_discrete/res/chips/chips.prt';

PART_NAME
 RF5 'RES_0402-1.0K,0.1%,1/16W,CHIP,A':
 GROUP='POWER_FAIR',
 ROOM='SB';

SECTION_NUMBER 1
 '@BASEBOARD_FAB2_LIB.BASEBOARD_FAB2(SCH_1):PAGE201_I186@MSTR_DISCRETE.RES(CHIPS)':
 C_PATH='@baseboard_fab2_lib.baseboard_fab2(sch_1):page201_i186@mstr_discrete.re~
s(chips)',
 P_PATH='@baseboard_fab2_lib.baseboard_fab2(sch_1):page201_i186@mstr_discrete.re~
s(chips)',
 PATH='I186',
 DRAWING='@BASEBOARD_FAB2_LIB.BASEBOARD_FAB2(SCH_1):PAGE201',
 FAIR_SS='064.9530D.M001',
 WATTAGE='1/16W',
 TOLERANCE='0.1%',
 SEC_TYPE='0402',
 MATERIAL='CHIP',
 PHYS_PAGE='201',
 XY='(-5025,3500)',
 ROT='0',
 VER='1',
 VALUE='1.0K',
 PACK_TYPE='0402',
 PART_NUMBER='G85996-004',
 LOCATION='RF5',
 ROOM='SB',
 GROUP='POWER_FAIR',
 SEC='1',
 CDS_LIB='mstr_discrete',
 CDS_PART_NAME='RES_0402-1.0K,0.1%,1/16W,CHIP,A',
 PRIM_FILE='./archive_libs/mstr_discrete/res/chips/chips.prt';

PART_NAME
 RF6 'RES_0402-1.0K,0.1%,1/16W,CHIP,A':
 GROUP='POWER_FAIR',
 ROOM='SB';

SECTION_NUMBER 1
 '@BASEBOARD_FAB2_LIB.BASEBOARD_FAB2(SCH_1):PAGE201_I180@MSTR_DISCRETE.RES(CHIPS)':
 C_PATH='@baseboard_fab2_lib.baseboard_fab2(sch_1):page201_i180@mstr_discrete.re~
s(chips)',
 P_PATH='@baseboard_fab2_lib.baseboard_fab2(sch_1):page201_i180@mstr_discrete.re~
s(chips)',
 PATH='I180',
 DRAWING='@BASEBOARD_FAB2_LIB.BASEBOARD_FAB2(SCH_1):PAGE201',
 WATTAGE='1/16W',
 TOLERANCE='0.1%',
 SEC_TYPE='0402',
 MATERIAL='CHIP',
 PHYS_PAGE='201',
 XY='(-5800,1425)',
 ROT='0',
 VER='1',
 VALUE='1.0K',
 PACK_TYPE='0402',
 PART_NUMBER='G85996-004',
 LOCATION='RF6',
 ROOM='SB',
 GROUP='POWER_FAIR',
 SEC='1',
 CDS_LIB='mstr_discrete',
 CDS_PART_NAME='RES_0402-1.0K,0.1%,1/16W,CHIP,A',
 PRIM_FILE='./archive_libs/mstr_discrete/res/chips/chips.prt';

PART_NAME
 RF7 'RES_0402-1.0K,0.1%,1/16W,CHIP,A':
 GROUP='POWER_FAIR',
 ROOM='SB';

SECTION_NUMBER 1
 '@BASEBOARD_FAB2_LIB.BASEBOARD_FAB2(SCH_1):PAGE206_I150@MSTR_DISCRETE.RES(CHIPS)':
 C_PATH='@baseboard_fab2_lib.baseboard_fab2(sch_1):page206_i150@mstr_discrete.re~
s(chips)',
 P_PATH='@baseboard_fab2_lib.baseboard_fab2(sch_1):page206_i150@mstr_discrete.re~
s(chips)',
 PATH='I150',
 DRAWING='@BASEBOARD_FAB2_LIB.BASEBOARD_FAB2(SCH_1):PAGE206',
 FAIR_SS='064.9530D.M001',
 WATTAGE='1/16W',
 TOLERANCE='0.1%',
 SEC_TYPE='0402',
 MATERIAL='CHIP',
 PHYS_PAGE='206',
 XY='(-6775,3500)',
 ROT='0',
 VER='1',
 VALUE='1.0K',
 PACK_TYPE='0402',
 PART_NUMBER='G85996-004',
 LOCATION='RF7',
 ROOM='SB',
 GROUP='POWER_FAIR',
 SEC='1',
 CDS_LIB='mstr_discrete',
 CDS_PART_NAME='RES_0402-1.0K,0.1%,1/16W,CHIP,A',
 PRIM_FILE='./archive_libs/mstr_discrete/res/chips/chips.prt';

PART_NAME
 RF8 'RES_0402-1.0K,0.1%,1/16W,CHIP,A':
 GROUP='POWER_FAIR',
 ROOM='SB';

SECTION_NUMBER 1
 '@BASEBOARD_FAB2_LIB.BASEBOARD_FAB2(SCH_1):PAGE206_I151@MSTR_DISCRETE.RES(CHIPS)':
 C_PATH='@baseboard_fab2_lib.baseboard_fab2(sch_1):page206_i151@mstr_discrete.re~
s(chips)',
 P_PATH='@baseboard_fab2_lib.baseboard_fab2(sch_1):page206_i151@mstr_discrete.re~
s(chips)',
 PATH='I151',
 DRAWING='@BASEBOARD_FAB2_LIB.BASEBOARD_FAB2(SCH_1):PAGE206',
 FAIR_SS='064.9530D.M001',
 WATTAGE='1/16W',
 TOLERANCE='0.1%',
 SEC_TYPE='0402',
 MATERIAL='CHIP',
 PHYS_PAGE='206',
 XY='(-6375,3500)',
 ROT='0',
 VER='1',
 VALUE='1.0K',
 PACK_TYPE='0402',
 PART_NUMBER='G85996-004',
 LOCATION='RF8',
 ROOM='SB',
 GROUP='POWER_FAIR',
 SEC='1',
 CDS_LIB='mstr_discrete',
 CDS_PART_NAME='RES_0402-1.0K,0.1%,1/16W,CHIP,A',
 PRIM_FILE='./archive_libs/mstr_discrete/res/chips/chips.prt';

PART_NAME
 RF9 'RES_0402-1.0K,0.1%,1/16W,CHIP,A':
 GROUP='POWER_FAIR',
 ROOM='SB';

SECTION_NUMBER 1
 '@BASEBOARD_FAB2_LIB.BASEBOARD_FAB2(SCH_1):PAGE206_I152@MSTR_DISCRETE.RES(CHIPS)':
 C_PATH='@baseboard_fab2_lib.baseboard_fab2(sch_1):page206_i152@mstr_discrete.re~
s(chips)',
 P_PATH='@baseboard_fab2_lib.baseboard_fab2(sch_1):page206_i152@mstr_discrete.re~
s(chips)',
 PATH='I152',
 DRAWING='@BASEBOARD_FAB2_LIB.BASEBOARD_FAB2(SCH_1):PAGE206',
 FAIR_SS='064.9530D.M001',
 WATTAGE='1/16W',
 TOLERANCE='0.1%',
 SEC_TYPE='0402',
 MATERIAL='CHIP',
 PHYS_PAGE='206',
 XY='(-6000,3500)',
 ROT='0',
 VER='1',
 VALUE='1.0K',
 PACK_TYPE='0402',
 PART_NUMBER='G85996-004',
 LOCATION='RF9',
 ROOM='SB',
 GROUP='POWER_FAIR',
 SEC='1',
 CDS_LIB='mstr_discrete',
 CDS_PART_NAME='RES_0402-1.0K,0.1%,1/16W,CHIP,A',
 PRIM_FILE='./archive_libs/mstr_discrete/res/chips/chips.prt';

PART_NAME
 RF10 'RES_0402-1.0K,0.1%,1/16W,CHIP,A':
 GROUP='POWER_FAIR',
 ROOM='SB';

SECTION_NUMBER 1
 '@BASEBOARD_FAB2_LIB.BASEBOARD_FAB2(SCH_1):PAGE206_I153@MSTR_DISCRETE.RES(CHIPS)':
 C_PATH='@baseboard_fab2_lib.baseboard_fab2(sch_1):page206_i153@mstr_discrete.re~
s(chips)',
 P_PATH='@baseboard_fab2_lib.baseboard_fab2(sch_1):page206_i153@mstr_discrete.re~
s(chips)',
 PATH='I153',
 DRAWING='@BASEBOARD_FAB2_LIB.BASEBOARD_FAB2(SCH_1):PAGE206',
 FAIR_SS='064.9530D.M001',
 WATTAGE='1/16W',
 TOLERANCE='0.1%',
 SEC_TYPE='0402',
 MATERIAL='CHIP',
 PHYS_PAGE='206',
 XY='(-5550,3500)',
 ROT='0',
 VER='1',
 VALUE='1.0K',
 PACK_TYPE='0402',
 PART_NUMBER='G85996-004',
 LOCATION='RF10',
 ROOM='SB',
 GROUP='POWER_FAIR',
 SEC='1',
 CDS_LIB='mstr_discrete',
 CDS_PART_NAME='RES_0402-1.0K,0.1%,1/16W,CHIP,A',
 PRIM_FILE='./archive_libs/mstr_discrete/res/chips/chips.prt';

PART_NAME
 RF11 'RES_0402-1.0K,0.1%,1/16W,CHIP,A':
 GROUP='POWER_FAIR',
 ROOM='SB';

SECTION_NUMBER 1
 '@BASEBOARD_FAB2_LIB.BASEBOARD_FAB2(SCH_1):PAGE206_I154@MSTR_DISCRETE.RES(CHIPS)':
 C_PATH='@baseboard_fab2_lib.baseboard_fab2(sch_1):page206_i154@mstr_discrete.re~
s(chips)',
 P_PATH='@baseboard_fab2_lib.baseboard_fab2(sch_1):page206_i154@mstr_discrete.re~
s(chips)',
 PATH='I154',
 DRAWING='@BASEBOARD_FAB2_LIB.BASEBOARD_FAB2(SCH_1):PAGE206',
 FAIR_SS='064.9530D.M001',
 WATTAGE='1/16W',
 TOLERANCE='0.1%',
 SEC_TYPE='0402',
 MATERIAL='CHIP',
 PHYS_PAGE='206',
 XY='(-5100,3500)',
 ROT='0',
 VER='1',
 VALUE='1.0K',
 PACK_TYPE='0402',
 PART_NUMBER='G85996-004',
 LOCATION='RF11',
 ROOM='SB',
 GROUP='POWER_FAIR',
 SEC='1',
 CDS_LIB='mstr_discrete',
 CDS_PART_NAME='RES_0402-1.0K,0.1%,1/16W,CHIP,A',
 PRIM_FILE='./archive_libs/mstr_discrete/res/chips/chips.prt';

PART_NAME
 RF12 'RES_0402-1.0K,0.1%,1/16W,CHIP,A':
 GROUP='POWER_FAIR',
 ROOM='SB';

SECTION_NUMBER 1
 '@BASEBOARD_FAB2_LIB.BASEBOARD_FAB2(SCH_1):PAGE206_I149@MSTR_DISCRETE.RES(CHIPS)':
 C_PATH='@baseboard_fab2_lib.baseboard_fab2(sch_1):page206_i149@mstr_discrete.re~
s(chips)',
 P_PATH='@baseboard_fab2_lib.baseboard_fab2(sch_1):page206_i149@mstr_discrete.re~
s(chips)',
 PATH='I149',
 DRAWING='@BASEBOARD_FAB2_LIB.BASEBOARD_FAB2(SCH_1):PAGE206',
 FAIR_SS='064.1101D.M001',
 WATTAGE='1/16W',
 TOLERANCE='0.1%',
 SEC_TYPE='0402',
 MATERIAL='CHIP',
 PHYS_PAGE='206',
 XY='(-6500,1425)',
 ROT='0',
 VER='1',
 VALUE='1.0K',
 PACK_TYPE='0402',
 PART_NUMBER='G85996-004',
 LOCATION='RF12',
 ROOM='SB',
 GROUP='POWER_FAIR',
 SEC='1',
 CDS_LIB='mstr_discrete',
 CDS_PART_NAME='RES_0402-1.0K,0.1%,1/16W,CHIP,A',
 PRIM_FILE='./archive_libs/mstr_discrete/res/chips/chips.prt';

PART_NAME
 RF13 'RES_0402-1.0K,0.1%,1/16W,CHIP,A':
 GROUP='POWER_FAIR',
 ROOM='SB';

SECTION_NUMBER 1
 '@BASEBOARD_FAB2_LIB.BASEBOARD_FAB2(SCH_1):PAGE211_I96@MSTR_DISCRETE.RES(CHIPS)':
 C_PATH='@baseboard_fab2_lib.baseboard_fab2(sch_1):page211_i96@mstr_discrete.res~
(chips)',
 P_PATH='@baseboard_fab2_lib.baseboard_fab2(sch_1):page211_i96@mstr_discrete.res~
(chips)',
 PATH='I96',
 DRAWING='@BASEBOARD_FAB2_LIB.BASEBOARD_FAB2(SCH_1):PAGE211',
 WATTAGE='1/16W',
 TOLERANCE='0.1%',
 SEC_TYPE='0402',
 MATERIAL='CHIP',
 PHYS_PAGE='211',
 XY='(-1975,3750)',
 ROT='0',
 VER='1',
 VALUE='1.0K',
 PACK_TYPE='0402',
 PART_NUMBER='G85996-004',
 LOCATION='RF13',
 ROOM='SB',
 GROUP='POWER_FAIR',
 SEC='1',
 CDS_LIB='mstr_discrete',
 CDS_PART_NAME='RES_0402-1.0K,0.1%,1/16W,CHIP,A',
 PRIM_FILE='./archive_libs/mstr_discrete/res/chips/chips.prt';

PART_NAME
 RF14 'RES_0402-1.0K,0.1%,1/16W,CHIP,A':
 GROUP='POWER_FAIR',
 ROOM='SB';

SECTION_NUMBER 1
 '@BASEBOARD_FAB2_LIB.BASEBOARD_FAB2(SCH_1):PAGE213_I99@MSTR_DISCRETE.RES(CHIPS)':
 C_PATH='@baseboard_fab2_lib.baseboard_fab2(sch_1):page213_i99@mstr_discrete.res~
(chips)',
 P_PATH='@baseboard_fab2_lib.baseboard_fab2(sch_1):page213_i99@mstr_discrete.res~
(chips)',
 PATH='I99',
 DRAWING='@BASEBOARD_FAB2_LIB.BASEBOARD_FAB2(SCH_1):PAGE213',
 FAIR_SS='064.9090D.M001',
 WATTAGE='1/16W',
 TOLERANCE='0.1%',
 SEC_TYPE='0402',
 MATERIAL='CHIP',
 PHYS_PAGE='213',
 XY='(-1900,3725)',
 ROT='0',
 VER='1',
 VALUE='1.0K',
 PACK_TYPE='0402',
 PART_NUMBER='G85996-004',
 LOCATION='RF14',
 ROOM='SB',
 GROUP='POWER_FAIR',
 SEC='1',
 CDS_LIB='mstr_discrete',
 CDS_PART_NAME='RES_0402-1.0K,0.1%,1/16W,CHIP,A',
 PRIM_FILE='./archive_libs/mstr_discrete/res/chips/chips.prt';

PART_NAME
 RF15 'RES_0402-1.0K,0.1%,1/16W,CHIP,A':
 GROUP='POWER_FAIR',
 ROOM='SB';

SECTION_NUMBER 1
 '@BASEBOARD_FAB2_LIB.BASEBOARD_FAB2(SCH_1):PAGE215_I15@MSTR_DISCRETE.RES(CHIPS)':
 C_PATH='@baseboard_fab2_lib.baseboard_fab2(sch_1):page215_i15@mstr_discrete.res~
(chips)',
 P_PATH='@baseboard_fab2_lib.baseboard_fab2(sch_1):page215_i15@mstr_discrete.res~
(chips)',
 PATH='I15',
 DRAWING='@BASEBOARD_FAB2_LIB.BASEBOARD_FAB2(SCH_1):PAGE215',
 FAIR_SS='064.9090D.M001',
 WATTAGE='1/16W',
 TOLERANCE='0.1%',
 SEC_TYPE='0402',
 MATERIAL='CHIP',
 PHYS_PAGE='215',
 XY='(-250,2525)',
 ROT='0',
 VER='1',
 VALUE='1.0K',
 PACK_TYPE='0402',
 PART_NUMBER='G85996-004',
 LOCATION='RF15',
 ROOM='SB',
 GROUP='POWER_FAIR',
 SEC='1',
 CDS_LIB='mstr_discrete',
 CDS_PART_NAME='RES_0402-1.0K,0.1%,1/16W,CHIP,A',
 PRIM_FILE='./archive_libs/mstr_discrete/res/chips/chips.prt';

PART_NAME
 RF16 'RES_0402-1.0K,0.1%,1/16W,CHIP,A':
 GROUP='POWER_FAIR',
 ROOM='SB';

SECTION_NUMBER 1
 '@BASEBOARD_FAB2_LIB.BASEBOARD_FAB2(SCH_1):PAGE215_I27@MSTR_DISCRETE.RES(CHIPS)':
 C_PATH='@baseboard_fab2_lib.baseboard_fab2(sch_1):page215_i27@mstr_discrete.res~
(chips)',
 P_PATH='@baseboard_fab2_lib.baseboard_fab2(sch_1):page215_i27@mstr_discrete.res~
(chips)',
 PATH='I27',
 DRAWING='@BASEBOARD_FAB2_LIB.BASEBOARD_FAB2(SCH_1):PAGE215',
 BOM_SS='NOPOP',
 WATTAGE='1/16W',
 TOLERANCE='0.1%',
 SEC_TYPE='0402',
 MATERIAL='CHIP',
 PHYS_PAGE='215',
 XY='(650,2600)',
 ROT='0',
 VER='1',
 VALUE='1.0K',
 PACK_TYPE='0402',
 PART_NUMBER='G85996-004',
 LOCATION='RF16',
 ROOM='SB',
 GROUP='POWER_FAIR',
 SEC='1',
 CDS_LIB='mstr_discrete',
 CDS_PART_NAME='RES_0402-1.0K,0.1%,1/16W,CHIP,A',
 PRIM_FILE='./archive_libs/mstr_discrete/res/chips/chips.prt';

PART_NAME
 RF17 'RES_0402-1.0K,0.1%,1/16W,CHIP,A':
 GROUP='POWER_FAIR',
 ROOM='SB';

SECTION_NUMBER 1
 '@BASEBOARD_FAB2_LIB.BASEBOARD_FAB2(SCH_1):PAGE218_I18@MSTR_DISCRETE.RES(CHIPS)':
 C_PATH='@baseboard_fab2_lib.baseboard_fab2(sch_1):page218_i18@mstr_discrete.res~
(chips)',
 P_PATH='@baseboard_fab2_lib.baseboard_fab2(sch_1):page218_i18@mstr_discrete.res~
(chips)',
 PATH='I18',
 DRAWING='@BASEBOARD_FAB2_LIB.BASEBOARD_FAB2(SCH_1):PAGE218',
 FAIR_SS='064.9530D.M001',
 WATTAGE='1/16W',
 TOLERANCE='0.1%',
 SEC_TYPE='0402',
 MATERIAL='CHIP',
 PHYS_PAGE='218',
 XY='(-2200,2400)',
 ROT='0',
 VER='1',
 VALUE='1.0K',
 PACK_TYPE='0402',
 PART_NUMBER='G85996-004',
 LOCATION='RF17',
 ROOM='SB',
 GROUP='POWER_FAIR',
 SEC='1',
 CDS_LIB='mstr_discrete',
 CDS_PART_NAME='RES_0402-1.0K,0.1%,1/16W,CHIP,A',
 PRIM_FILE='./archive_libs/mstr_discrete/res/chips/chips.prt';

PART_NAME
 RF18 'RES_0402-1.0K,0.1%,1/16W,CHIP,A':
 GROUP='POWER_FAIR',
 ROOM='SB';

SECTION_NUMBER 1
 '@BASEBOARD_FAB2_LIB.BASEBOARD_FAB2(SCH_1):PAGE218_I19@MSTR_DISCRETE.RES(CHIPS)':
 C_PATH='@baseboard_fab2_lib.baseboard_fab2(sch_1):page218_i19@mstr_discrete.res~
(chips)',
 P_PATH='@baseboard_fab2_lib.baseboard_fab2(sch_1):page218_i19@mstr_discrete.res~
(chips)',
 PATH='I19',
 DRAWING='@BASEBOARD_FAB2_LIB.BASEBOARD_FAB2(SCH_1):PAGE218',
 BOM_SS='NOPOP',
 WATTAGE='1/16W',
 TOLERANCE='0.1%',
 SEC_TYPE='0402',
 MATERIAL='CHIP',
 PHYS_PAGE='218',
 XY='(-1550,2400)',
 ROT='0',
 VER='1',
 VALUE='1.0K',
 PACK_TYPE='0402',
 PART_NUMBER='G85996-004',
 LOCATION='RF18',
 ROOM='SB',
 GROUP='POWER_FAIR',
 SEC='1',
 CDS_LIB='mstr_discrete',
 CDS_PART_NAME='RES_0402-1.0K,0.1%,1/16W,CHIP,A',
 PRIM_FILE='./archive_libs/mstr_discrete/res/chips/chips.prt';

PART_NAME
 RF19 'RES_0402-1.0K,0.1%,1/16W,CHIP,A':
 GROUP='POWER_FAIR',
 ROOM='SB';

SECTION_NUMBER 1
 '@BASEBOARD_FAB2_LIB.BASEBOARD_FAB2(SCH_1):PAGE223_I16@MSTR_DISCRETE.RES(CHIPS)':
 C_PATH='@baseboard_fab2_lib.baseboard_fab2(sch_1):page223_i16@mstr_discrete.res~
(chips)',
 P_PATH='@baseboard_fab2_lib.baseboard_fab2(sch_1):page223_i16@mstr_discrete.res~
(chips)',
 PATH='I16',
 DRAWING='@BASEBOARD_FAB2_LIB.BASEBOARD_FAB2(SCH_1):PAGE223',
 FAIR_SS='064.9530D.M001',
 WATTAGE='1/16W',
 TOLERANCE='0.1%',
 SEC_TYPE='0402',
 MATERIAL='CHIP',
 PHYS_PAGE='223',
 XY='(-1100,2450)',
 ROT='0',
 VER='1',
 VALUE='1.0K',
 PACK_TYPE='0402',
 PART_NUMBER='G85996-004',
 LOCATION='RF19',
 ROOM='SB',
 GROUP='POWER_FAIR',
 SEC='1',
 CDS_LIB='mstr_discrete',
 CDS_PART_NAME='RES_0402-1.0K,0.1%,1/16W,CHIP,A',
 PRIM_FILE='./archive_libs/mstr_discrete/res/chips/chips.prt';

PART_NAME
 RF20 'RES_0402-1.0K,0.1%,1/16W,CHIP,A':
 GROUP='POWER_FAIR',
 ROOM='SB';

SECTION_NUMBER 1
 '@BASEBOARD_FAB2_LIB.BASEBOARD_FAB2(SCH_1):PAGE223_I19@MSTR_DISCRETE.RES(CHIPS)':
 C_PATH='@baseboard_fab2_lib.baseboard_fab2(sch_1):page223_i19@mstr_discrete.res~
(chips)',
 P_PATH='@baseboard_fab2_lib.baseboard_fab2(sch_1):page223_i19@mstr_discrete.res~
(chips)',
 PATH='I19',
 DRAWING='@BASEBOARD_FAB2_LIB.BASEBOARD_FAB2(SCH_1):PAGE223',
 BOM_SS='NOPOP',
 WATTAGE='1/16W',
 TOLERANCE='0.1%',
 SEC_TYPE='0402',
 MATERIAL='CHIP',
 PHYS_PAGE='223',
 XY='(-225,2450)',
 ROT='0',
 VER='1',
 VALUE='1.0K',
 PACK_TYPE='0402',
 PART_NUMBER='G85996-004',
 LOCATION='RF20',
 ROOM='SB',
 GROUP='POWER_FAIR',
 SEC='1',
 CDS_LIB='mstr_discrete',
 CDS_PART_NAME='RES_0402-1.0K,0.1%,1/16W,CHIP,A',
 PRIM_FILE='./archive_libs/mstr_discrete/res/chips/chips.prt';

PART_NAME
 RF21 'RES_0402-1.0K,0.1%,1/16W,CHIP,A':
 GROUP='POWER_FAIR',
 ROOM='SB';

SECTION_NUMBER 1
 '@BASEBOARD_FAB2_LIB.BASEBOARD_FAB2(SCH_1):PAGE226_I16@MSTR_DISCRETE.RES(CHIPS)':
 C_PATH='@baseboard_fab2_lib.baseboard_fab2(sch_1):page226_i16@mstr_discrete.res~
(chips)',
 P_PATH='@baseboard_fab2_lib.baseboard_fab2(sch_1):page226_i16@mstr_discrete.res~
(chips)',
 PATH='I16',
 DRAWING='@BASEBOARD_FAB2_LIB.BASEBOARD_FAB2(SCH_1):PAGE226',
 FAIR_SS='064.9090D.M001',
 WATTAGE='1/16W',
 TOLERANCE='0.1%',
 SEC_TYPE='0402',
 MATERIAL='CHIP',
 PHYS_PAGE='226',
 XY='(-1550,2025)',
 ROT='0',
 VER='1',
 VALUE='1.0K',
 PACK_TYPE='0402',
 PART_NUMBER='G85996-004',
 LOCATION='RF21',
 ROOM='SB',
 GROUP='POWER_FAIR',
 SEC='1',
 CDS_LIB='mstr_discrete',
 CDS_PART_NAME='RES_0402-1.0K,0.1%,1/16W,CHIP,A',
 PRIM_FILE='./archive_libs/mstr_discrete/res/chips/chips.prt';

PART_NAME
 RF22 'RES_0402-1.0K,0.1%,1/16W,CHIP,A':
 GROUP='POWER_FAIR',
 ROOM='SB';

SECTION_NUMBER 1
 '@BASEBOARD_FAB2_LIB.BASEBOARD_FAB2(SCH_1):PAGE226_I18@MSTR_DISCRETE.RES(CHIPS)':
 C_PATH='@baseboard_fab2_lib.baseboard_fab2(sch_1):page226_i18@mstr_discrete.res~
(chips)',
 P_PATH='@baseboard_fab2_lib.baseboard_fab2(sch_1):page226_i18@mstr_discrete.res~
(chips)',
 PATH='I18',
 DRAWING='@BASEBOARD_FAB2_LIB.BASEBOARD_FAB2(SCH_1):PAGE226',
 BOM_SS='NOPOP',
 WATTAGE='1/16W',
 TOLERANCE='0.1%',
 SEC_TYPE='0402',
 MATERIAL='CHIP',
 PHYS_PAGE='226',
 XY='(-775,2025)',
 ROT='0',
 VER='1',
 VALUE='1.0K',
 PACK_TYPE='0402',
 PART_NUMBER='G85996-004',
 LOCATION='RF22',
 ROOM='SB',
 GROUP='POWER_FAIR',
 SEC='1',
 CDS_LIB='mstr_discrete',
 CDS_PART_NAME='RES_0402-1.0K,0.1%,1/16W,CHIP,A',
 PRIM_FILE='./archive_libs/mstr_discrete/res/chips/chips.prt';

PART_NAME
 RF23 'RES_0402-1.0K,0.1%,1/16W,CHIP,A':
 GROUP='POWER_FAIR',
 ROOM='SB';

SECTION_NUMBER 1
 '@BASEBOARD_FAB2_LIB.BASEBOARD_FAB2(SCH_1):PAGE235_I241@MSTR_DISCRETE.RES(CHIPS)':
 C_PATH='@baseboard_fab2_lib.baseboard_fab2(sch_1):page235_i241@mstr_discrete.re~
s(chips)',
 P_PATH='@baseboard_fab2_lib.baseboard_fab2(sch_1):page235_i241@mstr_discrete.re~
s(chips)',
 PATH='I241',
 DRAWING='@BASEBOARD_FAB2_LIB.BASEBOARD_FAB2(SCH_1):PAGE235',
 WATTAGE='1/16W',
 TOLERANCE='0.1%',
 SEC_TYPE='0402',
 MATERIAL='CHIP',
 PHYS_PAGE='235',
 XY='(-11775,4650)',
 ROT='0',
 VER='1',
 VALUE='1.0K',
 PACK_TYPE='0402',
 PART_NUMBER='G85996-004',
 LOCATION='RF23',
 ROOM='SB',
 GROUP='POWER_FAIR',
 SEC='1',
 CDS_LIB='mstr_discrete',
 CDS_PART_NAME='RES_0402-1.0K,0.1%,1/16W,CHIP,A',
 PRIM_FILE='./archive_libs/mstr_discrete/res/chips/chips.prt';

PART_NAME
 RF24 'RES_0402-1.0K,0.1%,1/16W,CHIP,A':
 GROUP='POWER_FAIR',
 ROOM='SB';

SECTION_NUMBER 1
 '@BASEBOARD_FAB2_LIB.BASEBOARD_FAB2(SCH_1):PAGE235_I242@MSTR_DISCRETE.RES(CHIPS)':
 C_PATH='@baseboard_fab2_lib.baseboard_fab2(sch_1):page235_i242@mstr_discrete.re~
s(chips)',
 P_PATH='@baseboard_fab2_lib.baseboard_fab2(sch_1):page235_i242@mstr_discrete.re~
s(chips)',
 PATH='I242',
 DRAWING='@BASEBOARD_FAB2_LIB.BASEBOARD_FAB2(SCH_1):PAGE235',
 WATTAGE='1/16W',
 TOLERANCE='0.1%',
 SEC_TYPE='0402',
 MATERIAL='CHIP',
 PHYS_PAGE='235',
 XY='(-11100,3000)',
 ROT='0',
 VER='1',
 VALUE='1.0K',
 PACK_TYPE='0402',
 PART_NUMBER='G85996-004',
 LOCATION='RF24',
 ROOM='SB',
 GROUP='POWER_FAIR',
 SEC='1',
 CDS_LIB='mstr_discrete',
 CDS_PART_NAME='RES_0402-1.0K,0.1%,1/16W,CHIP,A',
 PRIM_FILE='./archive_libs/mstr_discrete/res/chips/chips.prt';

PART_NAME
 RM1E1 'CONN3_G98259001_PIP-CONN,G9825A':;

SECTION_NUMBER 1
 '@BASEBOARD_FAB2_LIB.BASEBOARD_FAB2(SCH_1):PAGE195_I26@MSTR_CONN.CONN3_G98259001(CHIPS)':
 C_PATH='@baseboard_fab2_lib.baseboard_fab2(sch_1):page195_i26@mstr_conn.conn3_g~
98259001(chips)',
 P_PATH='@baseboard_fab2_lib.baseboard_fab2(sch_1):page195_i26@mstr_conn.conn3_g~
98259001(chips)',
 PATH='I26',
 DRAWING='@BASEBOARD_FAB2_LIB.BASEBOARD_FAB2(SCH_1):PAGE195',
 MATERIAL='CONN',
 PHYS_PAGE='195',
 XY='(-925,3725)',
 ROT='0',
 VER='1',
 PACK_TYPE='PIP',
 PART_NUMBER='G98259-001',
 LOCATION='RM1E1',
 CDS_LIB='mstr_conn',
 CDS_PART_NAME='CONN3_G98259001_PIP-CONN,G9825A',
 PRIM_FILE='./archive_libs/mstr_conn/conn3_g98259001/chips/chips.prt';

PART_NAME
 RM1G1 'STFT363B238R224H453-GP_DISCRETA':;

SECTION_NUMBER 1
 '@BASEBOARD_FAB2_LIB.BASEBOARD_FAB2(SCH_1):PAGE195_I117@W_HDL.STFT363B238R224H453-GP(CHIPS)':
 C_PATH='@baseboard_fab2_lib.baseboard_fab2(sch_1):page195_i117@w_hdl.\stft363b2~
38r224h453-gp\(chips)',
 P_PATH='@baseboard_fab2_lib.baseboard_fab2(sch_1):page195_i117@w_hdl.\stft363b2~
38r224h453-gp\(chips)',
 PATH='I117',
 DRAWING='@BASEBOARD_FAB2_LIB.BASEBOARD_FAB2(SCH_1):PAGE195',
 SEC_TYPE='DISCRET-GC1',
 PHYS_PAGE='195',
 XY='(-7650,4750)',
 ROT='0',
 VER='1',
 VALUE='STFT363B238R224H453-GP',
 PACK_TYPE='DISCRET-GC1',
 PART_NUMBER='086.2AT24.04R6',
 LOCATION='RM1G1',
 SEC='1',
 CDS_LIB='w_hdl',
 CDS_PART_NAME='STFT363B238R224H453-GP_DISCRETA',
 PRIM_FILE='C:/<user>/w_hdl/stft363b238r224h453#2dgp/chips/chips.prt';

PART_NAME
 RM8D1 'STANDOFF_TH1-SO,H72821-001':;

SECTION_NUMBER 1
 '@BASEBOARD_FAB2_LIB.BASEBOARD_FAB2(SCH_1):PAGE184_I104@MSTR_MISC.STANDOFF(CHIPS)':
 C_PATH='@baseboard_fab2_lib.baseboard_fab2(sch_1):page184_i104@mstr_misc.stando~
ff(chips)',
 P_PATH='@baseboard_fab2_lib.baseboard_fab2(sch_1):page184_i104@mstr_misc.stando~
ff(chips)',
 PATH='I104',
 DRAWING='@BASEBOARD_FAB2_LIB.BASEBOARD_FAB2(SCH_1):PAGE184',
 SEC_TYPE='TH1',
 MATERIAL='SO',
 PHYS_PAGE='184',
 XY='(-5125,-1900)',
 ROT='0',
 VER='2',
 PACK_TYPE='TH1',
 PART_NUMBER='H72821-001',
 LOCATION='RM8D1',
 SEC='1',
 CDS_LIB='mstr_misc',
 CDS_PART_NAME='STANDOFF_TH1-SO,H72821-001',
 PRIM_FILE='./archive_libs/mstr_misc/standoff/chips/chips.prt';

PART_NAME
 RN8F1 'RES_0402-4.75K,1%,1/16W,CHIP,GA':
 ROOM='BMC_BOOT_SPI';

SECTION_NUMBER 1
 '@BASEBOARD_FAB2_LIB.BASEBOARD_FAB2(SCH_1):PAGE137_I142@MSTR_DISCRETE.RES(CHIPS)':
 C_PATH='@baseboard_fab2_lib.baseboard_fab2(sch_1):page137_i142@mstr_discrete.re~
s(chips)',
 P_PATH='@baseboard_fab2_lib.baseboard_fab2(sch_1):page137_i142@mstr_discrete.re~
s(chips)',
 PATH='I142',
 DRAWING='@BASEBOARD_FAB2_LIB.BASEBOARD_FAB2(SCH_1):PAGE137',
 WATTAGE='1/16W',
 TOLERANCE='1%',
 SEC_TYPE='0402',
 MATERIAL='CHIP',
 BOM_COST='SM_MEM',
 PHYS_PAGE='137',
 XY='(-1250,4100)',
 ROT='2',
 VER='2',
 VALUE='4.75K',
 PACK_TYPE='0402',
 PART_NUMBER='G21796-072',
 LOCATION='RN8F1',
 ROOM='BMC_BOOT_SPI',
 SEC='1',
 CDS_LIB='mstr_discrete',
 CDS_PART_NAME='RES_0402-4.75K,1%,1/16W,CHIP,GA',
 PRIM_FILE='./archive_libs/mstr_discrete/res/chips/chips.prt';

PART_NAME
 RN8F2 'RES_0402-4.75K,1%,1/16W,EMPTY,A':
 ROOM='BMC_BOOT_SPI';

SECTION_NUMBER 1
 '@BASEBOARD_FAB2_LIB.BASEBOARD_FAB2(SCH_1):PAGE246_I20@MSTR_DISCRETE.RES(CHIPS)':
 C_PATH='@baseboard_fab2_lib.baseboard_fab2(sch_1):page246_i20@mstr_discrete.res~
(chips)',
 P_PATH='@baseboard_fab2_lib.baseboard_fab2(sch_1):page246_i20@mstr_discrete.res~
(chips)',
 PATH='I20',
 DRAWING='@BASEBOARD_FAB2_LIB.BASEBOARD_FAB2(SCH_1):PAGE246',
 WATTAGE='1/16W',
 TOLERANCE='1%',
 SEC_TYPE='0402',
 MATERIAL='EMPTY',
 BOM_COST='SM_MEM',
 PHYS_PAGE='246',
 XY='(-6225,3225)',
 ROT='2',
 VER='2',
 VALUE='4.75K',
 PACK_TYPE='0402',
 PART_NUMBER='G21796-072',
 LOCATION='RN8F2',
 ROOM='BMC_BOOT_SPI',
 SEC='1',
 CDS_LIB='mstr_discrete',
 CDS_PART_NAME='RES_0402-4.75K,1%,1/16W,EMPTY,A',
 PRIM_FILE='./archive_libs/mstr_discrete/res/chips/chips.prt';

PART_NAME
 RN8F3 'RES_0402-4.75K,1%,1/16W,CHIP,GA':
 ROOM='BMC_BOOT_SPI';

SECTION_NUMBER 1
 '@BASEBOARD_FAB2_LIB.BASEBOARD_FAB2(SCH_1):PAGE246_I11@MSTR_DISCRETE.RES(CHIPS)':
 C_PATH='@baseboard_fab2_lib.baseboard_fab2(sch_1):page246_i11@mstr_discrete.res~
(chips)',
 P_PATH='@baseboard_fab2_lib.baseboard_fab2(sch_1):page246_i11@mstr_discrete.res~
(chips)',
 PATH='I11',
 DRAWING='@BASEBOARD_FAB2_LIB.BASEBOARD_FAB2(SCH_1):PAGE246',
 WATTAGE='1/16W',
 TOLERANCE='1%',
 SEC_TYPE='0402',
 MATERIAL='CHIP',
 BOM_COST='SM_MEM',
 PHYS_PAGE='246',
 XY='(-5775,3200)',
 ROT='2',
 VER='2',
 VALUE='4.75K',
 PACK_TYPE='0402',
 PART_NUMBER='G21796-072',
 LOCATION='RN8F3',
 ROOM='BMC_BOOT_SPI',
 SEC='1',
 CDS_LIB='mstr_discrete',
 CDS_PART_NAME='RES_0402-4.75K,1%,1/16W,CHIP,GA',
 PRIM_FILE='./archive_libs/mstr_discrete/res/chips/chips.prt';

PART_NAME
 RN8F4 'RES_0402-4.75K,1%,1/16W,EMPTY,A':
 ROOM='BMC_BOOT_SPI';

SECTION_NUMBER 1
 '@BASEBOARD_FAB2_LIB.BASEBOARD_FAB2(SCH_1):PAGE246_I12@MSTR_DISCRETE.RES(CHIPS)':
 C_PATH='@baseboard_fab2_lib.baseboard_fab2(sch_1):page246_i12@mstr_discrete.res~
(chips)',
 P_PATH='@baseboard_fab2_lib.baseboard_fab2(sch_1):page246_i12@mstr_discrete.res~
(chips)',
 PATH='I12',
 DRAWING='@BASEBOARD_FAB2_LIB.BASEBOARD_FAB2(SCH_1):PAGE246',
 WATTAGE='1/16W',
 TOLERANCE='1%',
 SEC_TYPE='0402',
 MATERIAL='EMPTY',
 BOM_COST='SM_MEM',
 PHYS_PAGE='246',
 XY='(-5225,3225)',
 ROT='2',
 VER='2',
 VALUE='4.75K',
 PACK_TYPE='0402',
 PART_NUMBER='G21796-072',
 LOCATION='RN8F4',
 ROOM='BMC_BOOT_SPI',
 SEC='1',
 CDS_LIB='mstr_discrete',
 CDS_PART_NAME='RES_0402-4.75K,1%,1/16W,EMPTY,A',
 PRIM_FILE='./archive_libs/mstr_discrete/res/chips/chips.prt';

PART_NAME
 RN8F5 'RES_0402-33.2,1%,1/16W,CHIP,G2A':
 ROOM='BMC_BOOT_SPI';

SECTION_NUMBER 1
 '@BASEBOARD_FAB2_LIB.BASEBOARD_FAB2(SCH_1):PAGE246_I9@MSTR_DISCRETE.RES(CHIPS)':
 C_PATH='@baseboard_fab2_lib.baseboard_fab2(sch_1):page246_i9@mstr_discrete.res(~
chips)',
 P_PATH='@baseboard_fab2_lib.baseboard_fab2(sch_1):page246_i9@mstr_discrete.res(~
chips)',
 PATH='I9',
 DRAWING='@BASEBOARD_FAB2_LIB.BASEBOARD_FAB2(SCH_1):PAGE246',
 WATTAGE='1/16W',
 TOLERANCE='1%',
 SEC_TYPE='0402',
 MATERIAL='CHIP',
 BOM_COST='SM_MEM',
 PHYS_PAGE='246',
 XY='(-5725,2750)',
 ROT='0',
 VER='1',
 VALUE='33.2',
 PACK_TYPE='0402',
 PART_NUMBER='G21796-074',
 LOCATION='RN8F5',
 ROOM='BMC_BOOT_SPI',
 SEC='1',
 CDS_LIB='mstr_discrete',
 CDS_PART_NAME='RES_0402-33.2,1%,1/16W,CHIP,G2A',
 PRIM_FILE='./archive_libs/mstr_discrete/res/chips/chips.prt';

PART_NAME
 RN8F6 '82KR2F-1-GP_SMD-RG-82KR2F-1-GPA':;

SECTION_NUMBER 1
 '@BASEBOARD_FAB2_LIB.BASEBOARD_FAB2(SCH_1):PAGE246_I19@W_HDL.82KR2F-1-GP(CHIPS)':
 C_PATH='@baseboard_fab2_lib.baseboard_fab2(sch_1):page246_i19@w_hdl.\82kr2f-1-g~
p\(chips)',
 P_PATH='@baseboard_fab2_lib.baseboard_fab2(sch_1):page246_i19@w_hdl.\82kr2f-1-g~
p\(chips)',
 PATH='I19',
 DRAWING='@BASEBOARD_FAB2_LIB.BASEBOARD_FAB2(SCH_1):PAGE246',
 PACK_SIZE='0402',
 RATED='1/16W',
 ATTRIBUTE='82KOHM',
 TOLERANCE='1%',
 PHYS_PAGE='246',
 XY='(-6225,2300)',
 ROT='0',
 VER='1',
 VALUE='82KR2F-1-GP',
 PACK_TYPE='SMD-RG',
 PART_NUMBER='64.82025.6DL',
 LOCATION='RN8F6',
 CDS_LIB='w_hdl',
 CDS_PART_NAME='82KR2F-1-GP_SMD-RG-82KR2F-1-GPA',
 PRIM_FILE='C:/<user>/w_hdl/82kr2f#2d1#2dgp/chips/chips.prt';

PART_NAME
 RT1 'RES_0603-0,5.0%,1/10W,CHIP,G22A':
 ROOM='NIC_SPRV';

SECTION_NUMBER 1
 '@BASEBOARD_FAB2_LIB.BASEBOARD_FAB2(SCH_1):PAGE202_I101@MSTR_DISCRETE.RES(CHIPS)':
 C_PATH='@baseboard_fab2_lib.baseboard_fab2(sch_1):page202_i101@mstr_discrete.re~
s(chips)',
 P_PATH='@baseboard_fab2_lib.baseboard_fab2(sch_1):page202_i101@mstr_discrete.re~
s(chips)',
 PATH='I101',
 DRAWING='@BASEBOARD_FAB2_LIB.BASEBOARD_FAB2(SCH_1):PAGE202',
 WATTAGE='1/10W',
 TOLERANCE='5.0%',
 SEC_TYPE='0603',
 MATERIAL='CHIP',
 BOM_COST='NT_GBE_BASE',
 PHYS_PAGE='202',
 XY='(-5025,3575)',
 ROT='0',
 VER='1',
 VALUE='0',
 PACK_TYPE='0603',
 PART_NUMBER='G22178-002',
 LOCATION='RT1',
 ROOM='NIC_SPRV',
 SEC='1',
 CDS_LIB='mstr_discrete',
 CDS_PART_NAME='RES_0603-0,5.0%,1/10W,CHIP,G22A',
 PRIM_FILE='./archive_libs/mstr_discrete/res/chips/chips.prt';

PART_NAME
 RT2 '1R3F-GP_RCL_GP-1R3F-GP,64.1R00A':;

SECTION_NUMBER 1
 '@BASEBOARD_FAB2_LIB.BASEBOARD_FAB2(SCH_1):PAGE202_I114@W_HDL.1R3F-GP(CHIPS)':
 C_PATH='@baseboard_fab2_lib.baseboard_fab2(sch_1):page202_i114@w_hdl.\1r3f-gp\(~
chips)',
 P_PATH='@baseboard_fab2_lib.baseboard_fab2(sch_1):page202_i114@w_hdl.\1r3f-gp\(~
chips)',
 PATH='I114',
 DRAWING='@BASEBOARD_FAB2_LIB.BASEBOARD_FAB2(SCH_1):PAGE202',
 PACK_SIZE='0603',
 RATED='1/10W',
 ATTRIBUTE='1 OHM',
 POP='NOPOP',
 TOLERANCE='1%',
 SEC_TYPE='RCL_GP',
 PHYS_PAGE='202',
 XY='(-2550,2950)',
 ROT='0',
 VER='1',
 VALUE='1R3F-GP',
 PACK_TYPE='RCL_GP',
 PART_NUMBER='64.1R005.55L',
 LOCATION='RT2',
 SEC='1',
 CDS_LIB='w_hdl',
 CDS_PART_NAME='1R3F-GP_RCL_GP-1R3F-GP,64.1R00A',
 PRIM_FILE='C:/<user>/w_hdl/1r3f#2dgp/chips/chips.prt';

PART_NAME
 RT3 'RES_0603-0,5.0%,1/10W,CHIP,G22A':
 ROOM='NIC_SPRV';

SECTION_NUMBER 1
 '@BASEBOARD_FAB2_LIB.BASEBOARD_FAB2(SCH_1):PAGE202_I102@MSTR_DISCRETE.RES(CHIPS)':
 C_PATH='@baseboard_fab2_lib.baseboard_fab2(sch_1):page202_i102@mstr_discrete.re~
s(chips)',
 P_PATH='@baseboard_fab2_lib.baseboard_fab2(sch_1):page202_i102@mstr_discrete.re~
s(chips)',
 PATH='I102',
 DRAWING='@BASEBOARD_FAB2_LIB.BASEBOARD_FAB2(SCH_1):PAGE202',
 WATTAGE='1/10W',
 TOLERANCE='5.0%',
 SEC_TYPE='0603',
 MATERIAL='CHIP',
 BOM_COST='NT_GBE_BASE',
 PHYS_PAGE='202',
 XY='(-5025,950)',
 ROT='0',
 VER='1',
 VALUE='0',
 PACK_TYPE='0603',
 PART_NUMBER='G22178-002',
 LOCATION='RT3',
 ROOM='NIC_SPRV',
 SEC='1',
 CDS_LIB='mstr_discrete',
 CDS_PART_NAME='RES_0603-0,5.0%,1/10W,CHIP,G22A',
 PRIM_FILE='./archive_libs/mstr_discrete/res/chips/chips.prt';

PART_NAME
 RT4 '1R3F-GP_RCL_GP-1R3F-GP,64.1R00A':;

SECTION_NUMBER 1
 '@BASEBOARD_FAB2_LIB.BASEBOARD_FAB2(SCH_1):PAGE202_I115@W_HDL.1R3F-GP(CHIPS)':
 C_PATH='@baseboard_fab2_lib.baseboard_fab2(sch_1):page202_i115@w_hdl.\1r3f-gp\(~
chips)',
 P_PATH='@baseboard_fab2_lib.baseboard_fab2(sch_1):page202_i115@w_hdl.\1r3f-gp\(~
chips)',
 PATH='I115',
 DRAWING='@BASEBOARD_FAB2_LIB.BASEBOARD_FAB2(SCH_1):PAGE202',
 PACK_SIZE='0603',
 RATED='1/10W',
 ATTRIBUTE='1 OHM',
 POP='NOPOP',
 TOLERANCE='1%',
 SEC_TYPE='RCL_GP',
 PHYS_PAGE='202',
 XY='(-2550,525)',
 ROT='0',
 VER='1',
 VALUE='1R3F-GP',
 PACK_TYPE='RCL_GP',
 PART_NUMBER='64.1R005.55L',
 LOCATION='RT4',
 SEC='1',
 CDS_LIB='w_hdl',
 CDS_PART_NAME='1R3F-GP_RCL_GP-1R3F-GP,64.1R00A',
 PRIM_FILE='C:/<user>/w_hdl/1r3f#2dgp/chips/chips.prt';

PART_NAME
 RT5 'RES_0603-0,5.0%,1/10W,CHIP,G22A':
 ROOM='NIC_SPRV';

SECTION_NUMBER 1
 '@BASEBOARD_FAB2_LIB.BASEBOARD_FAB2(SCH_1):PAGE227_I138@MSTR_DISCRETE.RES(CHIPS)':
 C_PATH='@baseboard_fab2_lib.baseboard_fab2(sch_1):page227_i138@mstr_discrete.re~
s(chips)',
 P_PATH='@baseboard_fab2_lib.baseboard_fab2(sch_1):page227_i138@mstr_discrete.re~
s(chips)',
 PATH='I138',
 DRAWING='@BASEBOARD_FAB2_LIB.BASEBOARD_FAB2(SCH_1):PAGE227',
 WATTAGE='1/10W',
 TOLERANCE='5.0%',
 SEC_TYPE='0603',
 MATERIAL='CHIP',
 BOM_COST='NT_GBE_BASE',
 PHYS_PAGE='227',
 XY='(100,2025)',
 ROT='0',
 VER='1',
 VALUE='0',
 PACK_TYPE='0603',
 PART_NUMBER='G22178-002',
 LOCATION='RT5',
 ROOM='NIC_SPRV',
 SEC='1',
 CDS_LIB='mstr_discrete',
 CDS_PART_NAME='RES_0603-0,5.0%,1/10W,CHIP,G22A',
 PRIM_FILE='./archive_libs/mstr_discrete/res/chips/chips.prt';

PART_NAME
 RT6 '1R3F-GP_RCL_GP-1R3F-GP,64.1R00A':;

SECTION_NUMBER 1
 '@BASEBOARD_FAB2_LIB.BASEBOARD_FAB2(SCH_1):PAGE227_I149@W_HDL.1R3F-GP(CHIPS)':
 C_PATH='@baseboard_fab2_lib.baseboard_fab2(sch_1):page227_i149@w_hdl.\1r3f-gp\(~
chips)',
 P_PATH='@baseboard_fab2_lib.baseboard_fab2(sch_1):page227_i149@w_hdl.\1r3f-gp\(~
chips)',
 PATH='I149',
 DRAWING='@BASEBOARD_FAB2_LIB.BASEBOARD_FAB2(SCH_1):PAGE227',
 PACK_SIZE='0603',
 RATED='1/10W',
 ATTRIBUTE='1 OHM',
 POP='NOPOP',
 TOLERANCE='1%',
 SEC_TYPE='RCL_GP',
 PHYS_PAGE='227',
 XY='(2825,1325)',
 ROT='0',
 VER='1',
 VALUE='1R3F-GP',
 PACK_TYPE='RCL_GP',
 PART_NUMBER='64.1R005.55L',
 LOCATION='RT6',
 SEC='1',
 CDS_LIB='w_hdl',
 CDS_PART_NAME='1R3F-GP_RCL_GP-1R3F-GP,64.1R00A',
 PRIM_FILE='C:/<user>/w_hdl/1r3f#2dgp/chips/chips.prt';

PART_NAME
 RT7 '1R3F-GP_RCL_GP-1R3F-GP,64.1R00A':;

SECTION_NUMBER 1
 '@BASEBOARD_FAB2_LIB.BASEBOARD_FAB2(SCH_1):PAGE227_I150@W_HDL.1R3F-GP(CHIPS)':
 C_PATH='@baseboard_fab2_lib.baseboard_fab2(sch_1):page227_i150@w_hdl.\1r3f-gp\(~
chips)',
 P_PATH='@baseboard_fab2_lib.baseboard_fab2(sch_1):page227_i150@w_hdl.\1r3f-gp\(~
chips)',
 PATH='I150',
 DRAWING='@BASEBOARD_FAB2_LIB.BASEBOARD_FAB2(SCH_1):PAGE227',
 PACK_SIZE='0603',
 RATED='1/10W',
 ATTRIBUTE='1 OHM',
 BOM_SS='NOPOP',
 POP='NOPOP',
 TOLERANCE='1%',
 SEC_TYPE='RCL_GP',
 PHYS_PAGE='227',
 XY='(2925,-800)',
 ROT='0',
 VER='1',
 VALUE='1R3F-GP',
 PACK_TYPE='RCL_GP',
 PART_NUMBER='64.1R005.55L',
 LOCATION='RT7',
 SEC='1',
 CDS_LIB='w_hdl',
 CDS_PART_NAME='1R3F-GP_RCL_GP-1R3F-GP,64.1R00A',
 PRIM_FILE='C:/<user>/w_hdl/1r3f#2dgp/chips/chips.prt';

PART_NAME
 RT8 'RES_0603-0,5.0%,1/10W,CHIP,G22A':
 ROOM='NIC_SPRV';

SECTION_NUMBER 1
 '@BASEBOARD_FAB2_LIB.BASEBOARD_FAB2(SCH_1):PAGE227_I139@MSTR_DISCRETE.RES(CHIPS)':
 C_PATH='@baseboard_fab2_lib.baseboard_fab2(sch_1):page227_i139@mstr_discrete.re~
s(chips)',
 P_PATH='@baseboard_fab2_lib.baseboard_fab2(sch_1):page227_i139@mstr_discrete.re~
s(chips)',
 PATH='I139',
 DRAWING='@BASEBOARD_FAB2_LIB.BASEBOARD_FAB2(SCH_1):PAGE227',
 BOM_SS='NOPOP',
 WATTAGE='1/10W',
 TOLERANCE='5.0%',
 SEC_TYPE='0603',
 MATERIAL='CHIP',
 BOM_COST='NT_GBE_BASE',
 PHYS_PAGE='227',
 XY='(225,-250)',
 ROT='0',
 VER='1',
 VALUE='0',
 PACK_TYPE='0603',
 PART_NUMBER='G22178-002',
 LOCATION='RT8',
 ROOM='NIC_SPRV',
 SEC='1',
 CDS_LIB='mstr_discrete',
 CDS_PART_NAME='RES_0603-0,5.0%,1/10W,CHIP,G22A',
 PRIM_FILE='./archive_libs/mstr_discrete/res/chips/chips.prt';

PART_NAME
 RT8P1 'RES_0603-100.0K,1%,1/10W,CHIP,A':
 ROOM='CPU1';

SECTION_NUMBER 1
 '@BASEBOARD_FAB2_LIB.BASEBOARD_FAB2(SCH_1):PAGE71_I49@MSTR_DISCRETE.RES(CHIPS)':
 C_PATH='@baseboard_fab2_lib.baseboard_fab2(sch_1):page71_i49@mstr_discrete.res(~
chips)',
 P_PATH='@baseboard_fab2_lib.baseboard_fab2(sch_1):page71_i49@mstr_discrete.res(~
chips)',
 PATH='I49',
 DRAWING='@BASEBOARD_FAB2_LIB.BASEBOARD_FAB2(SCH_1):PAGE71',
 WATTAGE='1/10W',
 TOLERANCE='1%',
 SEC_TYPE='0603',
 MATERIAL='CHIP',
 BOM_COST='PROC_SOCKET',
 PHYS_PAGE='71',
 XY='(-1100,1400)',
 ROT='0',
 VER='2',
 VALUE='100.0K',
 PACK_TYPE='0603',
 PART_NUMBER='G22026-050',
 LOCATION='RT8P1',
 ROOM='CPU1',
 SEC='1',
 CDS_LIB='mstr_discrete',
 CDS_PART_NAME='RES_0603-100.0K,1%,1/10W,CHIP,A',
 PRIM_FILE='./archive_libs/mstr_discrete/res/chips/chips.prt';

PART_NAME
 RT9 'RES_0603-0,5.0%,1/10W,CHIP,G22A':
 ROOM='NIC_SPRV';

SECTION_NUMBER 1
 '@BASEBOARD_FAB2_LIB.BASEBOARD_FAB2(SCH_1):PAGE209_I75@MSTR_DISCRETE.RES(CHIPS)':
 C_PATH='@baseboard_fab2_lib.baseboard_fab2(sch_1):page209_i75@mstr_discrete.res~
(chips)',
 P_PATH='@baseboard_fab2_lib.baseboard_fab2(sch_1):page209_i75@mstr_discrete.res~
(chips)',
 PATH='I75',
 DRAWING='@BASEBOARD_FAB2_LIB.BASEBOARD_FAB2(SCH_1):PAGE209',
 WATTAGE='1/10W',
 TOLERANCE='5.0%',
 SEC_TYPE='0603',
 MATERIAL='CHIP',
 BOM_COST='NT_GBE_BASE',
 PHYS_PAGE='209',
 XY='(-4800,3575)',
 ROT='0',
 VER='1',
 VALUE='0',
 PACK_TYPE='0603',
 PART_NUMBER='G22178-002',
 LOCATION='RT9',
 ROOM='NIC_SPRV',
 SEC='1',
 CDS_LIB='mstr_discrete',
 CDS_PART_NAME='RES_0603-0,5.0%,1/10W,CHIP,G22A',
 PRIM_FILE='./archive_libs/mstr_discrete/res/chips/chips.prt';

PART_NAME
 RT10 '1R3F-GP_RCL_GP-1R3F-GP,64.1R00A':;

SECTION_NUMBER 1
 '@BASEBOARD_FAB2_LIB.BASEBOARD_FAB2(SCH_1):PAGE209_I90@W_HDL.1R3F-GP(CHIPS)':
 C_PATH='@baseboard_fab2_lib.baseboard_fab2(sch_1):page209_i90@w_hdl.\1r3f-gp\(c~
hips)',
 P_PATH='@baseboard_fab2_lib.baseboard_fab2(sch_1):page209_i90@w_hdl.\1r3f-gp\(c~
hips)',
 PATH='I90',
 DRAWING='@BASEBOARD_FAB2_LIB.BASEBOARD_FAB2(SCH_1):PAGE209',
 PACK_SIZE='0603',
 RATED='1/10W',
 ATTRIBUTE='1 OHM',
 POP='NOPOP',
 TOLERANCE='1%',
 SEC_TYPE='RCL_GP',
 PHYS_PAGE='209',
 XY='(-2400,2975)',
 ROT='0',
 VER='1',
 VALUE='1R3F-GP',
 PACK_TYPE='RCL_GP',
 PART_NUMBER='64.1R005.55L',
 LOCATION='RT10',
 SEC='1',
 CDS_LIB='w_hdl',
 CDS_PART_NAME='1R3F-GP_RCL_GP-1R3F-GP,64.1R00A',
 PRIM_FILE='C:/<user>/w_hdl/1r3f#2dgp/chips/chips.prt';

PART_NAME
 RT11 'RES_0603-0,5.0%,1/10W,CHIP,G22A':
 ROOM='NIC_SPRV';

SECTION_NUMBER 1
 '@BASEBOARD_FAB2_LIB.BASEBOARD_FAB2(SCH_1):PAGE208_I108@MSTR_DISCRETE.RES(CHIPS)':
 C_PATH='@baseboard_fab2_lib.baseboard_fab2(sch_1):page208_i108@mstr_discrete.re~
s(chips)',
 P_PATH='@baseboard_fab2_lib.baseboard_fab2(sch_1):page208_i108@mstr_discrete.re~
s(chips)',
 PATH='I108',
 DRAWING='@BASEBOARD_FAB2_LIB.BASEBOARD_FAB2(SCH_1):PAGE208',
 WATTAGE='1/10W',
 TOLERANCE='5.0%',
 SEC_TYPE='0603',
 MATERIAL='CHIP',
 BOM_COST='NT_GBE_BASE',
 PHYS_PAGE='208',
 XY='(-4975,3700)',
 ROT='0',
 VER='1',
 VALUE='0',
 PACK_TYPE='0603',
 PART_NUMBER='G22178-002',
 LOCATION='RT11',
 ROOM='NIC_SPRV',
 SEC='1',
 CDS_LIB='mstr_discrete',
 CDS_PART_NAME='RES_0603-0,5.0%,1/10W,CHIP,G22A',
 PRIM_FILE='./archive_libs/mstr_discrete/res/chips/chips.prt';

PART_NAME
 RT12 '1R3F-GP_RCL_GP-1R3F-GP,64.1R00A':;

SECTION_NUMBER 1
 '@BASEBOARD_FAB2_LIB.BASEBOARD_FAB2(SCH_1):PAGE208_I120@W_HDL.1R3F-GP(CHIPS)':
 C_PATH='@baseboard_fab2_lib.baseboard_fab2(sch_1):page208_i120@w_hdl.\1r3f-gp\(~
chips)',
 P_PATH='@baseboard_fab2_lib.baseboard_fab2(sch_1):page208_i120@w_hdl.\1r3f-gp\(~
chips)',
 PATH='I120',
 DRAWING='@BASEBOARD_FAB2_LIB.BASEBOARD_FAB2(SCH_1):PAGE208',
 PACK_SIZE='0603',
 RATED='1/10W',
 ATTRIBUTE='1 OHM',
 POP='NOPOP',
 TOLERANCE='1%',
 SEC_TYPE='RCL_GP',
 PHYS_PAGE='208',
 XY='(-2225,3175)',
 ROT='0',
 VER='1',
 VALUE='1R3F-GP',
 PACK_TYPE='RCL_GP',
 PART_NUMBER='64.1R005.55L',
 LOCATION='RT12',
 SEC='1',
 CDS_LIB='w_hdl',
 CDS_PART_NAME='1R3F-GP_RCL_GP-1R3F-GP,64.1R00A',
 PRIM_FILE='C:/<user>/w_hdl/1r3f#2dgp/chips/chips.prt';

PART_NAME
 RT13 '1R3F-GP_RCL_GP-1R3F-GP,64.1R00A':;

SECTION_NUMBER 1
 '@BASEBOARD_FAB2_LIB.BASEBOARD_FAB2(SCH_1):PAGE208_I121@W_HDL.1R3F-GP(CHIPS)':
 C_PATH='@baseboard_fab2_lib.baseboard_fab2(sch_1):page208_i121@w_hdl.\1r3f-gp\(~
chips)',
 P_PATH='@baseboard_fab2_lib.baseboard_fab2(sch_1):page208_i121@w_hdl.\1r3f-gp\(~
chips)',
 PATH='I121',
 DRAWING='@BASEBOARD_FAB2_LIB.BASEBOARD_FAB2(SCH_1):PAGE208',
 PACK_SIZE='0603',
 RATED='1/10W',
 ATTRIBUTE='1 OHM',
 POP='NOPOP',
 TOLERANCE='1%',
 SEC_TYPE='RCL_GP',
 PHYS_PAGE='208',
 XY='(-2075,550)',
 ROT='0',
 VER='1',
 VALUE='1R3F-GP',
 PACK_TYPE='RCL_GP',
 PART_NUMBER='64.1R005.55L',
 LOCATION='RT13',
 SEC='1',
 CDS_LIB='w_hdl',
 CDS_PART_NAME='1R3F-GP_RCL_GP-1R3F-GP,64.1R00A',
 PRIM_FILE='C:/<user>/w_hdl/1r3f#2dgp/chips/chips.prt';

PART_NAME
 RT14 'RES_0603-0,5.0%,1/10W,CHIP,G22A':
 ROOM='NIC_SPRV';

SECTION_NUMBER 1
 '@BASEBOARD_FAB2_LIB.BASEBOARD_FAB2(SCH_1):PAGE208_I109@MSTR_DISCRETE.RES(CHIPS)':
 C_PATH='@baseboard_fab2_lib.baseboard_fab2(sch_1):page208_i109@mstr_discrete.re~
s(chips)',
 P_PATH='@baseboard_fab2_lib.baseboard_fab2(sch_1):page208_i109@mstr_discrete.re~
s(chips)',
 PATH='I109',
 DRAWING='@BASEBOARD_FAB2_LIB.BASEBOARD_FAB2(SCH_1):PAGE208',
 WATTAGE='1/10W',
 TOLERANCE='5.0%',
 SEC_TYPE='0603',
 MATERIAL='CHIP',
 BOM_COST='NT_GBE_BASE',
 PHYS_PAGE='208',
 XY='(-4975,1075)',
 ROT='0',
 VER='1',
 VALUE='0',
 PACK_TYPE='0603',
 PART_NUMBER='G22178-002',
 LOCATION='RT14',
 ROOM='NIC_SPRV',
 SEC='1',
 CDS_LIB='mstr_discrete',
 CDS_PART_NAME='RES_0603-0,5.0%,1/10W,CHIP,G22A',
 PRIM_FILE='./archive_libs/mstr_discrete/res/chips/chips.prt';

PART_NAME
 RT15 'RES_0603-0,5.0%,1/10W,CHIP,G22A':
 ROOM='NIC_SPRV';

SECTION_NUMBER 1
 '@BASEBOARD_FAB2_LIB.BASEBOARD_FAB2(SCH_1):PAGE207_I99@MSTR_DISCRETE.RES(CHIPS)':
 C_PATH='@baseboard_fab2_lib.baseboard_fab2(sch_1):page207_i99@mstr_discrete.res~
(chips)',
 P_PATH='@baseboard_fab2_lib.baseboard_fab2(sch_1):page207_i99@mstr_discrete.res~
(chips)',
 PATH='I99',
 DRAWING='@BASEBOARD_FAB2_LIB.BASEBOARD_FAB2(SCH_1):PAGE207',
 WATTAGE='1/10W',
 TOLERANCE='5.0%',
 SEC_TYPE='0603',
 MATERIAL='CHIP',
 BOM_COST='NT_GBE_BASE',
 PHYS_PAGE='207',
 XY='(-4825,3675)',
 ROT='0',
 VER='1',
 VALUE='0',
 PACK_TYPE='0603',
 PART_NUMBER='G22178-002',
 LOCATION='RT15',
 ROOM='NIC_SPRV',
 SEC='1',
 CDS_LIB='mstr_discrete',
 CDS_PART_NAME='RES_0603-0,5.0%,1/10W,CHIP,G22A',
 PRIM_FILE='./archive_libs/mstr_discrete/res/chips/chips.prt';

PART_NAME
 RT16 '1R3F-GP_RCL_GP-1R3F-GP,64.1R00A':;

SECTION_NUMBER 1
 '@BASEBOARD_FAB2_LIB.BASEBOARD_FAB2(SCH_1):PAGE207_I111@W_HDL.1R3F-GP(CHIPS)':
 C_PATH='@baseboard_fab2_lib.baseboard_fab2(sch_1):page207_i111@w_hdl.\1r3f-gp\(~
chips)',
 P_PATH='@baseboard_fab2_lib.baseboard_fab2(sch_1):page207_i111@w_hdl.\1r3f-gp\(~
chips)',
 PATH='I111',
 DRAWING='@BASEBOARD_FAB2_LIB.BASEBOARD_FAB2(SCH_1):PAGE207',
 PACK_SIZE='0603',
 RATED='1/10W',
 ATTRIBUTE='1 OHM',
 POP='NOPOP',
 TOLERANCE='1%',
 SEC_TYPE='RCL_GP',
 PHYS_PAGE='207',
 XY='(-2225,3050)',
 ROT='0',
 VER='1',
 VALUE='1R3F-GP',
 PACK_TYPE='RCL_GP',
 PART_NUMBER='64.1R005.55L',
 LOCATION='RT16',
 SEC='1',
 CDS_LIB='w_hdl',
 CDS_PART_NAME='1R3F-GP_RCL_GP-1R3F-GP,64.1R00A',
 PRIM_FILE='C:/<user>/w_hdl/1r3f#2dgp/chips/chips.prt';

PART_NAME
 RT17 'RES_0603-0,5.0%,1/10W,CHIP,G22A':
 ROOM='NIC_SPRV';

SECTION_NUMBER 1
 '@BASEBOARD_FAB2_LIB.BASEBOARD_FAB2(SCH_1):PAGE207_I100@MSTR_DISCRETE.RES(CHIPS)':
 C_PATH='@baseboard_fab2_lib.baseboard_fab2(sch_1):page207_i100@mstr_discrete.re~
s(chips)',
 P_PATH='@baseboard_fab2_lib.baseboard_fab2(sch_1):page207_i100@mstr_discrete.re~
s(chips)',
 PATH='I100',
 DRAWING='@BASEBOARD_FAB2_LIB.BASEBOARD_FAB2(SCH_1):PAGE207',
 WATTAGE='1/10W',
 TOLERANCE='5.0%',
 SEC_TYPE='0603',
 MATERIAL='CHIP',
 BOM_COST='NT_GBE_BASE',
 PHYS_PAGE='207',
 XY='(-4700,1025)',
 ROT='0',
 VER='1',
 VALUE='0',
 PACK_TYPE='0603',
 PART_NUMBER='G22178-002',
 LOCATION='RT17',
 ROOM='NIC_SPRV',
 SEC='1',
 CDS_LIB='mstr_discrete',
 CDS_PART_NAME='RES_0603-0,5.0%,1/10W,CHIP,G22A',
 PRIM_FILE='./archive_libs/mstr_discrete/res/chips/chips.prt';

PART_NAME
 RT18 '1R3F-GP_RCL_GP-1R3F-GP,64.1R00A':;

SECTION_NUMBER 1
 '@BASEBOARD_FAB2_LIB.BASEBOARD_FAB2(SCH_1):PAGE207_I112@W_HDL.1R3F-GP(CHIPS)':
 C_PATH='@baseboard_fab2_lib.baseboard_fab2(sch_1):page207_i112@w_hdl.\1r3f-gp\(~
chips)',
 P_PATH='@baseboard_fab2_lib.baseboard_fab2(sch_1):page207_i112@w_hdl.\1r3f-gp\(~
chips)',
 PATH='I112',
 DRAWING='@BASEBOARD_FAB2_LIB.BASEBOARD_FAB2(SCH_1):PAGE207',
 PACK_SIZE='0603',
 RATED='1/10W',
 ATTRIBUTE='1 OHM',
 POP='NOPOP',
 TOLERANCE='1%',
 SEC_TYPE='RCL_GP',
 PHYS_PAGE='207',
 XY='(-1925,550)',
 ROT='0',
 VER='1',
 VALUE='1R3F-GP',
 PACK_TYPE='RCL_GP',
 PART_NUMBER='64.1R005.55L',
 LOCATION='RT18',
 SEC='1',
 CDS_LIB='w_hdl',
 CDS_PART_NAME='1R3F-GP_RCL_GP-1R3F-GP,64.1R00A',
 PRIM_FILE='C:/<user>/w_hdl/1r3f#2dgp/chips/chips.prt';

PART_NAME
 RT19 'RES_0603-0,5.0%,1/10W,CHIP,G22A':
 ROOM='NIC_SPRV';

SECTION_NUMBER 1
 '@BASEBOARD_FAB2_LIB.BASEBOARD_FAB2(SCH_1):PAGE224_I144@MSTR_DISCRETE.RES(CHIPS)':
 C_PATH='@baseboard_fab2_lib.baseboard_fab2(sch_1):page224_i144@mstr_discrete.re~
s(chips)',
 P_PATH='@baseboard_fab2_lib.baseboard_fab2(sch_1):page224_i144@mstr_discrete.re~
s(chips)',
 PATH='I144',
 DRAWING='@BASEBOARD_FAB2_LIB.BASEBOARD_FAB2(SCH_1):PAGE224',
 WATTAGE='1/10W',
 TOLERANCE='5.0%',
 SEC_TYPE='0603',
 MATERIAL='CHIP',
 BOM_COST='NT_GBE_BASE',
 PHYS_PAGE='224',
 XY='(100,2000)',
 ROT='0',
 VER='1',
 VALUE='0',
 PACK_TYPE='0603',
 PART_NUMBER='G22178-002',
 LOCATION='RT19',
 ROOM='NIC_SPRV',
 SEC='1',
 CDS_LIB='mstr_discrete',
 CDS_PART_NAME='RES_0603-0,5.0%,1/10W,CHIP,G22A',
 PRIM_FILE='./archive_libs/mstr_discrete/res/chips/chips.prt';

PART_NAME
 RT20 '1R3F-GP_RCL_GP-1R3F-GP,64.1R00A':;

SECTION_NUMBER 1
 '@BASEBOARD_FAB2_LIB.BASEBOARD_FAB2(SCH_1):PAGE224_I156@W_HDL.1R3F-GP(CHIPS)':
 C_PATH='@baseboard_fab2_lib.baseboard_fab2(sch_1):page224_i156@w_hdl.\1r3f-gp\(~
chips)',
 P_PATH='@baseboard_fab2_lib.baseboard_fab2(sch_1):page224_i156@w_hdl.\1r3f-gp\(~
chips)',
 PATH='I156',
 DRAWING='@BASEBOARD_FAB2_LIB.BASEBOARD_FAB2(SCH_1):PAGE224',
 PACK_SIZE='0603',
 RATED='1/10W',
 ATTRIBUTE='1 OHM',
 POP='NOPOP',
 TOLERANCE='1%',
 SEC_TYPE='RCL_GP',
 PHYS_PAGE='224',
 XY='(2900,1475)',
 ROT='0',
 VER='1',
 VALUE='1R3F-GP',
 PACK_TYPE='RCL_GP',
 PART_NUMBER='64.1R005.55L',
 LOCATION='RT20',
 SEC='1',
 CDS_LIB='w_hdl',
 CDS_PART_NAME='1R3F-GP_RCL_GP-1R3F-GP,64.1R00A',
 PRIM_FILE='C:/<user>/w_hdl/1r3f#2dgp/chips/chips.prt';

PART_NAME
 RT21 'RES_0603-0,5.0%,1/10W,CHIP,G22A':
 ROOM='NIC_SPRV';

SECTION_NUMBER 1
 '@BASEBOARD_FAB2_LIB.BASEBOARD_FAB2(SCH_1):PAGE224_I145@MSTR_DISCRETE.RES(CHIPS)':
 C_PATH='@baseboard_fab2_lib.baseboard_fab2(sch_1):page224_i145@mstr_discrete.re~
s(chips)',
 P_PATH='@baseboard_fab2_lib.baseboard_fab2(sch_1):page224_i145@mstr_discrete.re~
s(chips)',
 PATH='I145',
 DRAWING='@BASEBOARD_FAB2_LIB.BASEBOARD_FAB2(SCH_1):PAGE224',
 BOM_SS='NOPOP',
 WATTAGE='1/10W',
 TOLERANCE='5.0%',
 SEC_TYPE='0603',
 MATERIAL='CHIP',
 BOM_COST='NT_GBE_BASE',
 PHYS_PAGE='224',
 XY='(275,-325)',
 ROT='0',
 VER='1',
 VALUE='0',
 PACK_TYPE='0603',
 PART_NUMBER='G22178-002',
 LOCATION='RT21',
 ROOM='NIC_SPRV',
 SEC='1',
 CDS_LIB='mstr_discrete',
 CDS_PART_NAME='RES_0603-0,5.0%,1/10W,CHIP,G22A',
 PRIM_FILE='./archive_libs/mstr_discrete/res/chips/chips.prt';

PART_NAME
 RT22 '1R3F-GP_RCL_GP-1R3F-GP,64.1R00A':;

SECTION_NUMBER 1
 '@BASEBOARD_FAB2_LIB.BASEBOARD_FAB2(SCH_1):PAGE224_I157@W_HDL.1R3F-GP(CHIPS)':
 C_PATH='@baseboard_fab2_lib.baseboard_fab2(sch_1):page224_i157@w_hdl.\1r3f-gp\(~
chips)',
 P_PATH='@baseboard_fab2_lib.baseboard_fab2(sch_1):page224_i157@w_hdl.\1r3f-gp\(~
chips)',
 PATH='I157',
 DRAWING='@BASEBOARD_FAB2_LIB.BASEBOARD_FAB2(SCH_1):PAGE224',
 PACK_SIZE='0603',
 RATED='1/10W',
 ATTRIBUTE='1 OHM',
 BOM_SS='NOPOP',
 POP='NOPOP',
 TOLERANCE='1%',
 SEC_TYPE='RCL_GP',
 PHYS_PAGE='224',
 XY='(3250,-925)',
 ROT='0',
 VER='1',
 VALUE='1R3F-GP',
 PACK_TYPE='RCL_GP',
 PART_NUMBER='64.1R005.55L',
 LOCATION='RT22',
 SEC='1',
 CDS_LIB='w_hdl',
 CDS_PART_NAME='1R3F-GP_RCL_GP-1R3F-GP,64.1R00A',
 PRIM_FILE='C:/<user>/w_hdl/1r3f#2dgp/chips/chips.prt';

PART_NAME
 RT23 'RES_0603-0,5.0%,1/10W,CHIP,G22A':
 ROOM='NIC_SPRV';

SECTION_NUMBER 1
 '@BASEBOARD_FAB2_LIB.BASEBOARD_FAB2(SCH_1):PAGE204_I99@MSTR_DISCRETE.RES(CHIPS)':
 C_PATH='@baseboard_fab2_lib.baseboard_fab2(sch_1):page204_i99@mstr_discrete.res~
(chips)',
 P_PATH='@baseboard_fab2_lib.baseboard_fab2(sch_1):page204_i99@mstr_discrete.res~
(chips)',
 PATH='I99',
 DRAWING='@BASEBOARD_FAB2_LIB.BASEBOARD_FAB2(SCH_1):PAGE204',
 WATTAGE='1/10W',
 TOLERANCE='5.0%',
 SEC_TYPE='0603',
 MATERIAL='CHIP',
 BOM_COST='NT_GBE_BASE',
 PHYS_PAGE='204',
 XY='(-4875,3725)',
 ROT='0',
 VER='1',
 VALUE='0',
 PACK_TYPE='0603',
 PART_NUMBER='G22178-002',
 LOCATION='RT23',
 ROOM='NIC_SPRV',
 SEC='1',
 CDS_LIB='mstr_discrete',
 CDS_PART_NAME='RES_0603-0,5.0%,1/10W,CHIP,G22A',
 PRIM_FILE='./archive_libs/mstr_discrete/res/chips/chips.prt';

PART_NAME
 RT24 '1R3F-GP_RCL_GP-1R3F-GP,64.1R00A':;

SECTION_NUMBER 1
 '@BASEBOARD_FAB2_LIB.BASEBOARD_FAB2(SCH_1):PAGE204_I114@W_HDL.1R3F-GP(CHIPS)':
 C_PATH='@baseboard_fab2_lib.baseboard_fab2(sch_1):page204_i114@w_hdl.\1r3f-gp\(~
chips)',
 P_PATH='@baseboard_fab2_lib.baseboard_fab2(sch_1):page204_i114@w_hdl.\1r3f-gp\(~
chips)',
 PATH='I114',
 DRAWING='@BASEBOARD_FAB2_LIB.BASEBOARD_FAB2(SCH_1):PAGE204',
 PACK_SIZE='0603',
 RATED='1/10W',
 ATTRIBUTE='1 OHM',
 POP='NOPOP',
 TOLERANCE='1%',
 SEC_TYPE='RCL_GP',
 PHYS_PAGE='204',
 XY='(-1975,3175)',
 ROT='0',
 VER='1',
 VALUE='1R3F-GP',
 PACK_TYPE='RCL_GP',
 PART_NUMBER='64.1R005.55L',
 LOCATION='RT24',
 SEC='1',
 CDS_LIB='w_hdl',
 CDS_PART_NAME='1R3F-GP_RCL_GP-1R3F-GP,64.1R00A',
 PRIM_FILE='C:/<user>/w_hdl/1r3f#2dgp/chips/chips.prt';

PART_NAME
 RT25 'RES_0603-0,5.0%,1/10W,CHIP,G22A':
 ROOM='NIC_SPRV';

SECTION_NUMBER 1
 '@BASEBOARD_FAB2_LIB.BASEBOARD_FAB2(SCH_1):PAGE203_I122@MSTR_DISCRETE.RES(CHIPS)':
 C_PATH='@baseboard_fab2_lib.baseboard_fab2(sch_1):page203_i122@mstr_discrete.re~
s(chips)',
 P_PATH='@baseboard_fab2_lib.baseboard_fab2(sch_1):page203_i122@mstr_discrete.re~
s(chips)',
 PATH='I122',
 DRAWING='@BASEBOARD_FAB2_LIB.BASEBOARD_FAB2(SCH_1):PAGE203',
 WATTAGE='1/10W',
 TOLERANCE='5.0%',
 SEC_TYPE='0603',
 MATERIAL='CHIP',
 BOM_COST='NT_GBE_BASE',
 PHYS_PAGE='203',
 XY='(-4725,3725)',
 ROT='0',
 VER='1',
 VALUE='0',
 PACK_TYPE='0603',
 PART_NUMBER='G22178-002',
 LOCATION='RT25',
 ROOM='NIC_SPRV',
 SEC='1',
 CDS_LIB='mstr_discrete',
 CDS_PART_NAME='RES_0603-0,5.0%,1/10W,CHIP,G22A',
 PRIM_FILE='./archive_libs/mstr_discrete/res/chips/chips.prt';

PART_NAME
 RT26 '1R3F-GP_RCL_GP-1R3F-GP,64.1R00A':;

SECTION_NUMBER 1
 '@BASEBOARD_FAB2_LIB.BASEBOARD_FAB2(SCH_1):PAGE203_I134@W_HDL.1R3F-GP(CHIPS)':
 C_PATH='@baseboard_fab2_lib.baseboard_fab2(sch_1):page203_i134@w_hdl.\1r3f-gp\(~
chips)',
 P_PATH='@baseboard_fab2_lib.baseboard_fab2(sch_1):page203_i134@w_hdl.\1r3f-gp\(~
chips)',
 PATH='I134',
 DRAWING='@BASEBOARD_FAB2_LIB.BASEBOARD_FAB2(SCH_1):PAGE203',
 PACK_SIZE='0603',
 RATED='1/10W',
 ATTRIBUTE='1 OHM',
 POP='NOPOP',
 TOLERANCE='1%',
 SEC_TYPE='RCL_GP',
 PHYS_PAGE='203',
 XY='(-1950,3200)',
 ROT='0',
 VER='1',
 VALUE='1R3F-GP',
 PACK_TYPE='RCL_GP',
 PART_NUMBER='64.1R005.55L',
 LOCATION='RT26',
 SEC='1',
 CDS_LIB='w_hdl',
 CDS_PART_NAME='1R3F-GP_RCL_GP-1R3F-GP,64.1R00A',
 PRIM_FILE='C:/<user>/w_hdl/1r3f#2dgp/chips/chips.prt';

PART_NAME
 RT27 '1R3F-GP_RCL_GP-1R3F-GP,64.1R00A':;

SECTION_NUMBER 1
 '@BASEBOARD_FAB2_LIB.BASEBOARD_FAB2(SCH_1):PAGE203_I135@W_HDL.1R3F-GP(CHIPS)':
 C_PATH='@baseboard_fab2_lib.baseboard_fab2(sch_1):page203_i135@w_hdl.\1r3f-gp\(~
chips)',
 P_PATH='@baseboard_fab2_lib.baseboard_fab2(sch_1):page203_i135@w_hdl.\1r3f-gp\(~
chips)',
 PATH='I135',
 DRAWING='@BASEBOARD_FAB2_LIB.BASEBOARD_FAB2(SCH_1):PAGE203',
 PACK_SIZE='0603',
 RATED='1/10W',
 ATTRIBUTE='1 OHM',
 POP='NOPOP',
 TOLERANCE='1%',
 SEC_TYPE='RCL_GP',
 PHYS_PAGE='203',
 XY='(-1975,550)',
 ROT='0',
 VER='1',
 VALUE='1R3F-GP',
 PACK_TYPE='RCL_GP',
 PART_NUMBER='64.1R005.55L',
 LOCATION='RT27',
 SEC='1',
 CDS_LIB='w_hdl',
 CDS_PART_NAME='1R3F-GP_RCL_GP-1R3F-GP,64.1R00A',
 PRIM_FILE='C:/<user>/w_hdl/1r3f#2dgp/chips/chips.prt';

PART_NAME
 RT28 'RES_0603-0,5.0%,1/10W,CHIP,G22A':
 ROOM='NIC_SPRV';

SECTION_NUMBER 1
 '@BASEBOARD_FAB2_LIB.BASEBOARD_FAB2(SCH_1):PAGE203_I123@MSTR_DISCRETE.RES(CHIPS)':
 C_PATH='@baseboard_fab2_lib.baseboard_fab2(sch_1):page203_i123@mstr_discrete.re~
s(chips)',
 P_PATH='@baseboard_fab2_lib.baseboard_fab2(sch_1):page203_i123@mstr_discrete.re~
s(chips)',
 PATH='I123',
 DRAWING='@BASEBOARD_FAB2_LIB.BASEBOARD_FAB2(SCH_1):PAGE203',
 WATTAGE='1/10W',
 TOLERANCE='5.0%',
 SEC_TYPE='0603',
 MATERIAL='CHIP',
 BOM_COST='NT_GBE_BASE',
 PHYS_PAGE='203',
 XY='(-4950,975)',
 ROT='0',
 VER='1',
 VALUE='0',
 PACK_TYPE='0603',
 PART_NUMBER='G22178-002',
 LOCATION='RT28',
 ROOM='NIC_SPRV',
 SEC='1',
 CDS_LIB='mstr_discrete',
 CDS_PART_NAME='RES_0603-0,5.0%,1/10W,CHIP,G22A',
 PRIM_FILE='./archive_libs/mstr_discrete/res/chips/chips.prt';

PART_NAME
 RT29 '1R3F-GP_RCL_GP-1R3F-GP,64.1R00A':;

SECTION_NUMBER 1
 '@BASEBOARD_FAB2_LIB.BASEBOARD_FAB2(SCH_1):PAGE219_I153@W_HDL.1R3F-GP(CHIPS)':
 C_PATH='@baseboard_fab2_lib.baseboard_fab2(sch_1):page219_i153@w_hdl.\1r3f-gp\(~
chips)',
 P_PATH='@baseboard_fab2_lib.baseboard_fab2(sch_1):page219_i153@w_hdl.\1r3f-gp\(~
chips)',
 PATH='I153',
 DRAWING='@BASEBOARD_FAB2_LIB.BASEBOARD_FAB2(SCH_1):PAGE219',
 PACK_SIZE='0603',
 RATED='1/10W',
 ATTRIBUTE='1 OHM',
 POP='NOPOP',
 TOLERANCE='1%',
 SEC_TYPE='RCL_GP',
 PHYS_PAGE='219',
 XY='(2850,1325)',
 ROT='0',
 VER='1',
 VALUE='1R3F-GP',
 PACK_TYPE='RCL_GP',
 PART_NUMBER='64.1R005.55L',
 LOCATION='RT29',
 SEC='1',
 CDS_LIB='w_hdl',
 CDS_PART_NAME='1R3F-GP_RCL_GP-1R3F-GP,64.1R00A',
 PRIM_FILE='C:/<user>/w_hdl/1r3f#2dgp/chips/chips.prt';

PART_NAME
 RT30 'RES_0603-0,5.0%,1/10W,CHIP,G22A':
 ROOM='NIC_SPRV';

SECTION_NUMBER 1
 '@BASEBOARD_FAB2_LIB.BASEBOARD_FAB2(SCH_1):PAGE219_I141@MSTR_DISCRETE.RES(CHIPS)':
 C_PATH='@baseboard_fab2_lib.baseboard_fab2(sch_1):page219_i141@mstr_discrete.re~
s(chips)',
 P_PATH='@baseboard_fab2_lib.baseboard_fab2(sch_1):page219_i141@mstr_discrete.re~
s(chips)',
 PATH='I141',
 DRAWING='@BASEBOARD_FAB2_LIB.BASEBOARD_FAB2(SCH_1):PAGE219',
 WATTAGE='1/10W',
 TOLERANCE='5.0%',
 SEC_TYPE='0603',
 MATERIAL='CHIP',
 BOM_COST='NT_GBE_BASE',
 PHYS_PAGE='219',
 XY='(-125,1900)',
 ROT='0',
 VER='1',
 VALUE='0',
 PACK_TYPE='0603',
 PART_NUMBER='G22178-002',
 LOCATION='RT30',
 ROOM='NIC_SPRV',
 SEC='1',
 CDS_LIB='mstr_discrete',
 CDS_PART_NAME='RES_0603-0,5.0%,1/10W,CHIP,G22A',
 PRIM_FILE='./archive_libs/mstr_discrete/res/chips/chips.prt';

PART_NAME
 RT31 'RES_0603-0,5.0%,1/10W,CHIP,G22A':
 ROOM='NIC_SPRV';

SECTION_NUMBER 1
 '@BASEBOARD_FAB2_LIB.BASEBOARD_FAB2(SCH_1):PAGE219_I142@MSTR_DISCRETE.RES(CHIPS)':
 C_PATH='@baseboard_fab2_lib.baseboard_fab2(sch_1):page219_i142@mstr_discrete.re~
s(chips)',
 P_PATH='@baseboard_fab2_lib.baseboard_fab2(sch_1):page219_i142@mstr_discrete.re~
s(chips)',
 PATH='I142',
 DRAWING='@BASEBOARD_FAB2_LIB.BASEBOARD_FAB2(SCH_1):PAGE219',
 BOM_SS='NOPOP',
 WATTAGE='1/10W',
 TOLERANCE='5.0%',
 SEC_TYPE='0603',
 MATERIAL='CHIP',
 BOM_COST='NT_GBE_BASE',
 PHYS_PAGE='219',
 XY='(175,-350)',
 ROT='0',
 VER='1',
 VALUE='0',
 PACK_TYPE='0603',
 PART_NUMBER='G22178-002',
 LOCATION='RT31',
 ROOM='NIC_SPRV',
 SEC='1',
 CDS_LIB='mstr_discrete',
 CDS_PART_NAME='RES_0603-0,5.0%,1/10W,CHIP,G22A',
 PRIM_FILE='./archive_libs/mstr_discrete/res/chips/chips.prt';

PART_NAME
 RT32 '1R3F-GP_RCL_GP-1R3F-GP,64.1R00A':;

SECTION_NUMBER 1
 '@BASEBOARD_FAB2_LIB.BASEBOARD_FAB2(SCH_1):PAGE219_I154@W_HDL.1R3F-GP(CHIPS)':
 C_PATH='@baseboard_fab2_lib.baseboard_fab2(sch_1):page219_i154@w_hdl.\1r3f-gp\(~
chips)',
 P_PATH='@baseboard_fab2_lib.baseboard_fab2(sch_1):page219_i154@w_hdl.\1r3f-gp\(~
chips)',
 PATH='I154',
 DRAWING='@BASEBOARD_FAB2_LIB.BASEBOARD_FAB2(SCH_1):PAGE219',
 PACK_SIZE='0603',
 RATED='1/10W',
 ATTRIBUTE='1 OHM',
 BOM_SS='NOPOP',
 POP='NOPOP',
 TOLERANCE='1%',
 SEC_TYPE='RCL_GP',
 PHYS_PAGE='219',
 XY='(2875,-925)',
 ROT='0',
 VER='1',
 VALUE='1R3F-GP',
 PACK_TYPE='RCL_GP',
 PART_NUMBER='64.1R005.55L',
 LOCATION='RT32',
 SEC='1',
 CDS_LIB='w_hdl',
 CDS_PART_NAME='1R3F-GP_RCL_GP-1R3F-GP,64.1R00A',
 PRIM_FILE='C:/<user>/w_hdl/1r3f#2dgp/chips/chips.prt';

PART_NAME
 RT33 'RES_0603-0,5.0%,1/10W,CHIP,G22A':
 ROOM='NIC_SPRV';

SECTION_NUMBER 1
 '@BASEBOARD_FAB2_LIB.BASEBOARD_FAB2(SCH_1):PAGE216_I139@MSTR_DISCRETE.RES(CHIPS)':
 C_PATH='@baseboard_fab2_lib.baseboard_fab2(sch_1):page216_i139@mstr_discrete.re~
s(chips)',
 P_PATH='@baseboard_fab2_lib.baseboard_fab2(sch_1):page216_i139@mstr_discrete.re~
s(chips)',
 PATH='I139',
 DRAWING='@BASEBOARD_FAB2_LIB.BASEBOARD_FAB2(SCH_1):PAGE216',
 WATTAGE='1/10W',
 TOLERANCE='5.0%',
 SEC_TYPE='0603',
 MATERIAL='CHIP',
 BOM_COST='NT_GBE_BASE',
 PHYS_PAGE='216',
 XY='(125,2075)',
 ROT='0',
 VER='1',
 VALUE='0',
 PACK_TYPE='0603',
 PART_NUMBER='G22178-002',
 LOCATION='RT33',
 ROOM='NIC_SPRV',
 SEC='1',
 CDS_LIB='mstr_discrete',
 CDS_PART_NAME='RES_0603-0,5.0%,1/10W,CHIP,G22A',
 PRIM_FILE='./archive_libs/mstr_discrete/res/chips/chips.prt';

PART_NAME
 RT34 '1R3F-GP_RCL_GP-1R3F-GP,64.1R00A':;

SECTION_NUMBER 1
 '@BASEBOARD_FAB2_LIB.BASEBOARD_FAB2(SCH_1):PAGE216_I151@W_HDL.1R3F-GP(CHIPS)':
 C_PATH='@baseboard_fab2_lib.baseboard_fab2(sch_1):page216_i151@w_hdl.\1r3f-gp\(~
chips)',
 P_PATH='@baseboard_fab2_lib.baseboard_fab2(sch_1):page216_i151@w_hdl.\1r3f-gp\(~
chips)',
 PATH='I151',
 DRAWING='@BASEBOARD_FAB2_LIB.BASEBOARD_FAB2(SCH_1):PAGE216',
 PACK_SIZE='0603',
 RATED='1/10W',
 ATTRIBUTE='1 OHM',
 POP='NOPOP',
 TOLERANCE='1%',
 SEC_TYPE='RCL_GP',
 PHYS_PAGE='216',
 XY='(2900,1500)',
 ROT='0',
 VER='1',
 VALUE='1R3F-GP',
 PACK_TYPE='RCL_GP',
 PART_NUMBER='64.1R005.55L',
 LOCATION='RT34',
 SEC='1',
 CDS_LIB='w_hdl',
 CDS_PART_NAME='1R3F-GP_RCL_GP-1R3F-GP,64.1R00A',
 PRIM_FILE='C:/<user>/w_hdl/1r3f#2dgp/chips/chips.prt';

PART_NAME
 RT35 '1R3F-GP_RCL_GP-1R3F-GP,64.1R00A':;

SECTION_NUMBER 1
 '@BASEBOARD_FAB2_LIB.BASEBOARD_FAB2(SCH_1):PAGE216_I152@W_HDL.1R3F-GP(CHIPS)':
 C_PATH='@baseboard_fab2_lib.baseboard_fab2(sch_1):page216_i152@w_hdl.\1r3f-gp\(~
chips)',
 P_PATH='@baseboard_fab2_lib.baseboard_fab2(sch_1):page216_i152@w_hdl.\1r3f-gp\(~
chips)',
 PATH='I152',
 DRAWING='@BASEBOARD_FAB2_LIB.BASEBOARD_FAB2(SCH_1):PAGE216',
 PACK_SIZE='0603',
 RATED='1/10W',
 ATTRIBUTE='1 OHM',
 BOM_SS='NOPOP',
 POP='NOPOP',
 TOLERANCE='1%',
 SEC_TYPE='RCL_GP',
 PHYS_PAGE='216',
 XY='(2900,-850)',
 ROT='0',
 VER='1',
 VALUE='1R3F-GP',
 PACK_TYPE='RCL_GP',
 PART_NUMBER='64.1R005.55L',
 LOCATION='RT35',
 SEC='1',
 CDS_LIB='w_hdl',
 CDS_PART_NAME='1R3F-GP_RCL_GP-1R3F-GP,64.1R00A',
 PRIM_FILE='C:/<user>/w_hdl/1r3f#2dgp/chips/chips.prt';

PART_NAME
 RT36 'RES_0603-0,5.0%,1/10W,CHIP,G22A':
 ROOM='NIC_SPRV';

SECTION_NUMBER 1
 '@BASEBOARD_FAB2_LIB.BASEBOARD_FAB2(SCH_1):PAGE216_I140@MSTR_DISCRETE.RES(CHIPS)':
 C_PATH='@baseboard_fab2_lib.baseboard_fab2(sch_1):page216_i140@mstr_discrete.re~
s(chips)',
 P_PATH='@baseboard_fab2_lib.baseboard_fab2(sch_1):page216_i140@mstr_discrete.re~
s(chips)',
 PATH='I140',
 DRAWING='@BASEBOARD_FAB2_LIB.BASEBOARD_FAB2(SCH_1):PAGE216',
 BOM_SS='NOPOP',
 WATTAGE='1/10W',
 TOLERANCE='5.0%',
 SEC_TYPE='0603',
 MATERIAL='CHIP',
 BOM_COST='NT_GBE_BASE',
 PHYS_PAGE='216',
 XY='(100,-275)',
 ROT='0',
 VER='1',
 VALUE='0',
 PACK_TYPE='0603',
 PART_NUMBER='G22178-002',
 LOCATION='RT36',
 ROOM='NIC_SPRV',
 SEC='1',
 CDS_LIB='mstr_discrete',
 CDS_PART_NAME='RES_0603-0,5.0%,1/10W,CHIP,G22A',
 PRIM_FILE='./archive_libs/mstr_discrete/res/chips/chips.prt';

PART_NAME
 RT37 'RES_0603-0,5.0%,1/10W,CHIP,G22A':
 ROOM='NIC_SPRV';

SECTION_NUMBER 1
 '@BASEBOARD_FAB2_LIB.BASEBOARD_FAB2(SCH_1):PAGE210_I68@MSTR_DISCRETE.RES(CHIPS)':
 C_PATH='@baseboard_fab2_lib.baseboard_fab2(sch_1):page210_i68@mstr_discrete.res~
(chips)',
 P_PATH='@baseboard_fab2_lib.baseboard_fab2(sch_1):page210_i68@mstr_discrete.res~
(chips)',
 PATH='I68',
 DRAWING='@BASEBOARD_FAB2_LIB.BASEBOARD_FAB2(SCH_1):PAGE210',
 WATTAGE='1/10W',
 TOLERANCE='5.0%',
 SEC_TYPE='0603',
 MATERIAL='CHIP',
 BOM_COST='NT_GBE_BASE',
 PHYS_PAGE='210',
 XY='(-5400,3375)',
 ROT='0',
 VER='1',
 VALUE='0',
 PACK_TYPE='0603',
 PART_NUMBER='G22178-002',
 LOCATION='RT37',
 ROOM='NIC_SPRV',
 SEC='1',
 CDS_LIB='mstr_discrete',
 CDS_PART_NAME='RES_0603-0,5.0%,1/10W,CHIP,G22A',
 PRIM_FILE='./archive_libs/mstr_discrete/res/chips/chips.prt';

PART_NAME
 RT38 '1R3F-GP_RCL_GP-1R3F-GP,64.1R00A':;

SECTION_NUMBER 1
 '@BASEBOARD_FAB2_LIB.BASEBOARD_FAB2(SCH_1):PAGE210_I74@W_HDL.1R3F-GP(CHIPS)':
 C_PATH='@baseboard_fab2_lib.baseboard_fab2(sch_1):page210_i74@w_hdl.\1r3f-gp\(c~
hips)',
 P_PATH='@baseboard_fab2_lib.baseboard_fab2(sch_1):page210_i74@w_hdl.\1r3f-gp\(c~
hips)',
 PATH='I74',
 DRAWING='@BASEBOARD_FAB2_LIB.BASEBOARD_FAB2(SCH_1):PAGE210',
 PACK_SIZE='0603',
 RATED='1/10W',
 ATTRIBUTE='1 OHM',
 POP='NOPOP',
 TOLERANCE='1%',
 SEC_TYPE='RCL_GP',
 PHYS_PAGE='210',
 XY='(-2500,2825)',
 ROT='0',
 VER='1',
 VALUE='1R3F-GP',
 PACK_TYPE='RCL_GP',
 PART_NUMBER='64.1R005.55L',
 LOCATION='RT38',
 SEC='1',
 CDS_LIB='w_hdl',
 CDS_PART_NAME='1R3F-GP_RCL_GP-1R3F-GP,64.1R00A',
 PRIM_FILE='C:/<user>/w_hdl/1r3f#2dgp/chips/chips.prt';

PART_NAME
 RT39 '1R3F-GP_RCL_GP-1R3F-GP,64.1R00A':;

SECTION_NUMBER 1
 '@BASEBOARD_FAB2_LIB.BASEBOARD_FAB2(SCH_1):PAGE205_I84@W_HDL.1R3F-GP(CHIPS)':
 C_PATH='@baseboard_fab2_lib.baseboard_fab2(sch_1):page205_i84@w_hdl.\1r3f-gp\(c~
hips)',
 P_PATH='@baseboard_fab2_lib.baseboard_fab2(sch_1):page205_i84@w_hdl.\1r3f-gp\(c~
hips)',
 PATH='I84',
 DRAWING='@BASEBOARD_FAB2_LIB.BASEBOARD_FAB2(SCH_1):PAGE205',
 PACK_SIZE='0603',
 RATED='1/10W',
 ATTRIBUTE='1 OHM',
 POP='NOPOP',
 TOLERANCE='1%',
 SEC_TYPE='RCL_GP',
 PHYS_PAGE='205',
 XY='(-2050,3150)',
 ROT='0',
 VER='1',
 VALUE='1R3F-GP',
 PACK_TYPE='RCL_GP',
 PART_NUMBER='64.1R005.55L',
 LOCATION='RT39',
 SEC='1',
 CDS_LIB='w_hdl',
 CDS_PART_NAME='1R3F-GP_RCL_GP-1R3F-GP,64.1R00A',
 PRIM_FILE='C:/<user>/w_hdl/1r3f#2dgp/chips/chips.prt';

PART_NAME
 RT40 'RES_0603-0,5.0%,1/10W,CHIP,G22A':
 ROOM='NIC_SPRV';

SECTION_NUMBER 1
 '@BASEBOARD_FAB2_LIB.BASEBOARD_FAB2(SCH_1):PAGE205_I78@MSTR_DISCRETE.RES(CHIPS)':
 C_PATH='@baseboard_fab2_lib.baseboard_fab2(sch_1):page205_i78@mstr_discrete.res~
(chips)',
 P_PATH='@baseboard_fab2_lib.baseboard_fab2(sch_1):page205_i78@mstr_discrete.res~
(chips)',
 PATH='I78',
 DRAWING='@BASEBOARD_FAB2_LIB.BASEBOARD_FAB2(SCH_1):PAGE205',
 WATTAGE='1/10W',
 TOLERANCE='5.0%',
 SEC_TYPE='0603',
 MATERIAL='CHIP',
 BOM_COST='NT_GBE_BASE',
 PHYS_PAGE='205',
 XY='(-5250,3700)',
 ROT='0',
 VER='1',
 VALUE='0',
 PACK_TYPE='0603',
 PART_NUMBER='G22178-002',
 LOCATION='RT40',
 ROOM='NIC_SPRV',
 SEC='1',
 CDS_LIB='mstr_discrete',
 CDS_PART_NAME='RES_0603-0,5.0%,1/10W,CHIP,G22A',
 PRIM_FILE='./archive_libs/mstr_discrete/res/chips/chips.prt';

PART_NAME
 RT41 'RES_0603-0,5.0%,1/10W,CHIP,G22A':
 ROOM='NIC_SPRV';

SECTION_NUMBER 1
 '@BASEBOARD_FAB2_LIB.BASEBOARD_FAB2(SCH_1):PAGE214_I145@MSTR_DISCRETE.RES(CHIPS)':
 C_PATH='@baseboard_fab2_lib.baseboard_fab2(sch_1):page214_i145@mstr_discrete.re~
s(chips)',
 P_PATH='@baseboard_fab2_lib.baseboard_fab2(sch_1):page214_i145@mstr_discrete.re~
s(chips)',
 PATH='I145',
 DRAWING='@BASEBOARD_FAB2_LIB.BASEBOARD_FAB2(SCH_1):PAGE214',
 WATTAGE='1/10W',
 TOLERANCE='5.0%',
 SEC_TYPE='0603',
 MATERIAL='CHIP',
 BOM_COST='NT_GBE_BASE',
 PHYS_PAGE='214',
 XY='(-675,3700)',
 ROT='0',
 VER='1',
 VALUE='0',
 PACK_TYPE='0603',
 PART_NUMBER='G22178-002',
 LOCATION='RT41',
 ROOM='NIC_SPRV',
 SEC='1',
 CDS_LIB='mstr_discrete',
 CDS_PART_NAME='RES_0603-0,5.0%,1/10W,CHIP,G22A',
 PRIM_FILE='./archive_libs/mstr_discrete/res/chips/chips.prt';

PART_NAME
 RT42 '1R3F-GP_RCL_GP-1R3F-GP,64.1R00A':;

SECTION_NUMBER 1
 '@BASEBOARD_FAB2_LIB.BASEBOARD_FAB2(SCH_1):PAGE214_I176@W_HDL.1R3F-GP(CHIPS)':
 C_PATH='@baseboard_fab2_lib.baseboard_fab2(sch_1):page214_i176@w_hdl.\1r3f-gp\(~
chips)',
 P_PATH='@baseboard_fab2_lib.baseboard_fab2(sch_1):page214_i176@w_hdl.\1r3f-gp\(~
chips)',
 PATH='I176',
 DRAWING='@BASEBOARD_FAB2_LIB.BASEBOARD_FAB2(SCH_1):PAGE214',
 PACK_SIZE='0603',
 RATED='1/10W',
 ATTRIBUTE='1 OHM',
 POP='NOPOP',
 TOLERANCE='1%',
 SEC_TYPE='RCL_GP',
 PHYS_PAGE='214',
 XY='(2200,3100)',
 ROT='0',
 VER='1',
 VALUE='1R3F-GP',
 PACK_TYPE='RCL_GP',
 PART_NUMBER='64.1R005.55L',
 LOCATION='RT42',
 SEC='1',
 CDS_LIB='w_hdl',
 CDS_PART_NAME='1R3F-GP_RCL_GP-1R3F-GP,64.1R00A',
 PRIM_FILE='C:/<user>/w_hdl/1r3f#2dgp/chips/chips.prt';

PART_NAME
 RT43 '1R3F-GP_RCL_GP-1R3F-GP,64.1R00A':;

SECTION_NUMBER 1
 '@BASEBOARD_FAB2_LIB.BASEBOARD_FAB2(SCH_1):PAGE236_I182@W_HDL.1R3F-GP(CHIPS)':
 C_PATH='@baseboard_fab2_lib.baseboard_fab2(sch_1):page236_i182@w_hdl.\1r3f-gp\(~
chips)',
 P_PATH='@baseboard_fab2_lib.baseboard_fab2(sch_1):page236_i182@w_hdl.\1r3f-gp\(~
chips)',
 PATH='I182',
 DRAWING='@BASEBOARD_FAB2_LIB.BASEBOARD_FAB2(SCH_1):PAGE236',
 PACK_SIZE='0603',
 RATED='1/10W',
 ATTRIBUTE='1 OHM',
 POP='NOPOP',
 TOLERANCE='1%',
 SEC_TYPE='RCL_GP',
 PHYS_PAGE='236',
 XY='(10550,3550)',
 ROT='0',
 VER='1',
 VALUE='1R3F-GP',
 PACK_TYPE='RCL_GP',
 PART_NUMBER='64.1R005.55L',
 LOCATION='RT43',
 SEC='1',
 CDS_LIB='w_hdl',
 CDS_PART_NAME='1R3F-GP_RCL_GP-1R3F-GP,64.1R00A',
 PRIM_FILE='C:/<user>/w_hdl/1r3f#2dgp/chips/chips.prt';

PART_NAME
 RT44 'RES_0603-0,5.0%,1/10W,CHIP,G22A':
 ROOM='NIC_SPRV';

SECTION_NUMBER 1
 '@BASEBOARD_FAB2_LIB.BASEBOARD_FAB2(SCH_1):PAGE236_I153@MSTR_DISCRETE.RES(CHIPS)':
 C_PATH='@baseboard_fab2_lib.baseboard_fab2(sch_1):page236_i153@mstr_discrete.re~
s(chips)',
 P_PATH='@baseboard_fab2_lib.baseboard_fab2(sch_1):page236_i153@mstr_discrete.re~
s(chips)',
 PATH='I153',
 DRAWING='@BASEBOARD_FAB2_LIB.BASEBOARD_FAB2(SCH_1):PAGE236',
 WATTAGE='1/10W',
 TOLERANCE='5.0%',
 SEC_TYPE='0603',
 MATERIAL='CHIP',
 BOM_COST='NT_GBE_BASE',
 PHYS_PAGE='236',
 XY='(8025,4050)',
 ROT='0',
 VER='1',
 VALUE='0',
 PACK_TYPE='0603',
 PART_NUMBER='G22178-002',
 LOCATION='RT44',
 ROOM='NIC_SPRV',
 SEC='1',
 CDS_LIB='mstr_discrete',
 CDS_PART_NAME='RES_0603-0,5.0%,1/10W,CHIP,G22A',
 PRIM_FILE='./archive_libs/mstr_discrete/res/chips/chips.prt';

PART_NAME
 RT45 '1R3F-GP_RCL_GP-1R3F-GP,64.1R00A':;

SECTION_NUMBER 1
 '@BASEBOARD_FAB2_LIB.BASEBOARD_FAB2(SCH_1):PAGE236_I183@W_HDL.1R3F-GP(CHIPS)':
 C_PATH='@baseboard_fab2_lib.baseboard_fab2(sch_1):page236_i183@w_hdl.\1r3f-gp\(~
chips)',
 P_PATH='@baseboard_fab2_lib.baseboard_fab2(sch_1):page236_i183@w_hdl.\1r3f-gp\(~
chips)',
 PATH='I183',
 DRAWING='@BASEBOARD_FAB2_LIB.BASEBOARD_FAB2(SCH_1):PAGE236',
 PACK_SIZE='0603',
 RATED='1/10W',
 ATTRIBUTE='1 OHM',
 POP='NOPOP',
 TOLERANCE='1%',
 SEC_TYPE='RCL_GP',
 PHYS_PAGE='236',
 XY='(11050,1850)',
 ROT='0',
 VER='1',
 VALUE='1R3F-GP',
 PACK_TYPE='RCL_GP',
 PART_NUMBER='64.1R005.55L',
 LOCATION='RT45',
 SEC='1',
 CDS_LIB='w_hdl',
 CDS_PART_NAME='1R3F-GP_RCL_GP-1R3F-GP,64.1R00A',
 PRIM_FILE='C:/<user>/w_hdl/1r3f#2dgp/chips/chips.prt';

PART_NAME
 RT46 'RES_0603-0,5.0%,1/10W,CHIP,G22A':
 ROOM='NIC_SPRV';

SECTION_NUMBER 1
 '@BASEBOARD_FAB2_LIB.BASEBOARD_FAB2(SCH_1):PAGE236_I154@MSTR_DISCRETE.RES(CHIPS)':
 C_PATH='@baseboard_fab2_lib.baseboard_fab2(sch_1):page236_i154@mstr_discrete.re~
s(chips)',
 P_PATH='@baseboard_fab2_lib.baseboard_fab2(sch_1):page236_i154@mstr_discrete.re~
s(chips)',
 PATH='I154',
 DRAWING='@BASEBOARD_FAB2_LIB.BASEBOARD_FAB2(SCH_1):PAGE236',
 WATTAGE='1/10W',
 TOLERANCE='5.0%',
 SEC_TYPE='0603',
 MATERIAL='CHIP',
 BOM_COST='NT_GBE_BASE',
 PHYS_PAGE='236',
 XY='(8050,2325)',
 ROT='0',
 VER='1',
 VALUE='0',
 PACK_TYPE='0603',
 PART_NUMBER='G22178-002',
 LOCATION='RT46',
 ROOM='NIC_SPRV',
 SEC='1',
 CDS_LIB='mstr_discrete',
 CDS_PART_NAME='RES_0603-0,5.0%,1/10W,CHIP,G22A',
 PRIM_FILE='./archive_libs/mstr_discrete/res/chips/chips.prt';

PART_NAME
 RT47 'RES_0603-0,5.0%,1/10W,CHIP,G22A':
 ROOM='NIC_SPRV';

SECTION_NUMBER 1
 '@BASEBOARD_FAB2_LIB.BASEBOARD_FAB2(SCH_1):PAGE212_I120@MSTR_DISCRETE.RES(CHIPS)':
 C_PATH='@baseboard_fab2_lib.baseboard_fab2(sch_1):page212_i120@mstr_discrete.re~
s(chips)',
 P_PATH='@baseboard_fab2_lib.baseboard_fab2(sch_1):page212_i120@mstr_discrete.re~
s(chips)',
 PATH='I120',
 DRAWING='@BASEBOARD_FAB2_LIB.BASEBOARD_FAB2(SCH_1):PAGE212',
 WATTAGE='1/10W',
 TOLERANCE='5.0%',
 SEC_TYPE='0603',
 MATERIAL='CHIP',
 BOM_COST='NT_GBE_BASE',
 PHYS_PAGE='212',
 XY='(-475,3750)',
 ROT='0',
 VER='1',
 VALUE='0',
 PACK_TYPE='0603',
 PART_NUMBER='G22178-002',
 LOCATION='RT47',
 ROOM='NIC_SPRV',
 SEC='1',
 CDS_LIB='mstr_discrete',
 CDS_PART_NAME='RES_0603-0,5.0%,1/10W,CHIP,G22A',
 PRIM_FILE='./archive_libs/mstr_discrete/res/chips/chips.prt';

PART_NAME
 RT48 '1R3F-GP_RCL_GP-1R3F-GP,64.1R00A':;

SECTION_NUMBER 1
 '@BASEBOARD_FAB2_LIB.BASEBOARD_FAB2(SCH_1):PAGE212_I144@W_HDL.1R3F-GP(CHIPS)':
 C_PATH='@baseboard_fab2_lib.baseboard_fab2(sch_1):page212_i144@w_hdl.\1r3f-gp\(~
chips)',
 P_PATH='@baseboard_fab2_lib.baseboard_fab2(sch_1):page212_i144@w_hdl.\1r3f-gp\(~
chips)',
 PATH='I144',
 DRAWING='@BASEBOARD_FAB2_LIB.BASEBOARD_FAB2(SCH_1):PAGE212',
 PACK_SIZE='0603',
 RATED='1/10W',
 ATTRIBUTE='1 OHM',
 POP='NOPOP',
 TOLERANCE='1%',
 SEC_TYPE='RCL_GP',
 PHYS_PAGE='212',
 XY='(2625,3100)',
 ROT='0',
 VER='1',
 VALUE='1R3F-GP',
 PACK_TYPE='RCL_GP',
 PART_NUMBER='64.1R005.55L',
 LOCATION='RT48',
 SEC='1',
 CDS_LIB='w_hdl',
 CDS_PART_NAME='1R3F-GP_RCL_GP-1R3F-GP,64.1R00A',
 PRIM_FILE='C:/<user>/w_hdl/1r3f#2dgp/chips/chips.prt';

PART_NAME
 S8E1 'SWITCH_D90553001_SMLF-IC,D9055A':
 ROOM='MIO_CHASSIS';

SECTION_NUMBER 1
 '@BASEBOARD_FAB2_LIB.BASEBOARD_FAB2(SCH_1):PAGE157_I351@MSTR_MISC.SWITCH_D90553001(CHIPS)':
 C_PATH='@baseboard_fab2_lib.baseboard_fab2(sch_1):page157_i351@mstr_misc.switch~
_d90553001(chips)',
 P_PATH='@baseboard_fab2_lib.baseboard_fab2(sch_1):page157_i351@mstr_misc.switch~
_d90553001(chips)',
 PATH='I351',
 DRAWING='@BASEBOARD_FAB2_LIB.BASEBOARD_FAB2(SCH_1):PAGE157',
 SEC_TYPE='SMLF',
 MATERIAL='IC',
 BOM_COST='MIO_CHASSIS',
 PHYS_PAGE='157',
 XY='(-4525,2675)',
 ROT='0',
 VER='1',
 PACK_TYPE='SMLF',
 PART_NAME='SWITCH_D90553001',
 PART_NUMBER='D90553-001',
 LOCATION='S8E1',
 ROOM='MIO_CHASSIS',
 SEC='1',
 CDS_LIB='mstr_misc',
 CDS_PART_NAME='SWITCH_D90553001_SMLF-IC,D9055A',
 PRIM_FILE='./archive_libs/mstr_misc/switch_d90553001/chips/chips.prt';

PART_NAME
 S9A1 'SWITCH_D37771002_SM-IC,D37771-A':
 ROOM='MIO_CHASSIS';

SECTION_NUMBER 1
 '@BASEBOARD_FAB2_LIB.BASEBOARD_FAB2(SCH_1):PAGE175_I78@MSTR_MISC.SWITCH_D37771002(CHIPS)':
 C_PATH='@baseboard_fab2_lib.baseboard_fab2(sch_1):page175_i78@mstr_misc.switch_~
d37771002(chips)',
 P_PATH='@baseboard_fab2_lib.baseboard_fab2(sch_1):page175_i78@mstr_misc.switch_~
d37771002(chips)',
 PATH='I78',
 DRAWING='@BASEBOARD_FAB2_LIB.BASEBOARD_FAB2(SCH_1):PAGE175',
 SEC_TYPE='SM',
 MATERIAL='IC',
 BOM_COST='MIO_CHASSIS',
 PHYS_PAGE='175',
 XY='(-7075,2675)',
 ROT='3',
 VER='1',
 PACK_TYPE='SM',
 PART_NUMBER='D37771-002',
 LOCATION='S9A1',
 ROOM='MIO_CHASSIS',
 SEC='1',
 CDS_LIB='mstr_misc',
 CDS_PART_NAME='SWITCH_D37771002_SM-IC,D37771-A',
 PRIM_FILE='./archive_libs/mstr_misc/switch_d37771002/chips/chips.prt';

PART_NAME
 S9A2 'SWITCH_D37771002_SM-IC,D37771-A':
 ROOM='MIO_CHASSIS';

SECTION_NUMBER 1
 '@BASEBOARD_FAB2_LIB.BASEBOARD_FAB2(SCH_1):PAGE175_I92@MSTR_MISC.SWITCH_D37771002(CHIPS)':
 C_PATH='@baseboard_fab2_lib.baseboard_fab2(sch_1):page175_i92@mstr_misc.switch_~
d37771002(chips)',
 P_PATH='@baseboard_fab2_lib.baseboard_fab2(sch_1):page175_i92@mstr_misc.switch_~
d37771002(chips)',
 PATH='I92',
 DRAWING='@BASEBOARD_FAB2_LIB.BASEBOARD_FAB2(SCH_1):PAGE175',
 SEC_TYPE='SM',
 MATERIAL='IC',
 BOM_COST='MIO_CHASSIS',
 PHYS_PAGE='175',
 XY='(-7200,4150)',
 ROT='2',
 VER='1',
 PACK_TYPE='SM',
 PART_NUMBER='D37771-002',
 LOCATION='S9A2',
 ROOM='MIO_CHASSIS',
 SEC='1',
 CDS_LIB='mstr_misc',
 CDS_PART_NAME='SWITCH_D37771002_SM-IC,D37771-A',
 PRIM_FILE='./archive_libs/mstr_misc/switch_d37771002/chips/chips.prt';

PART_NAME
 S9W1 'SW-SLIDE75-GP_DISCRET-G6-SW-SLA':;

SECTION_NUMBER 1
 '@BASEBOARD_FAB2_LIB.BASEBOARD_FAB2(SCH_1):PAGE268_I63@W_HDL.SW-SLIDE75-GP(CHIPS)':
 C_PATH='@baseboard_fab2_lib.baseboard_fab2(sch_1):page268_i63@w_hdl.\sw-slide75~
-gp\(chips)',
 P_PATH='@baseboard_fab2_lib.baseboard_fab2(sch_1):page255_i63@w_hdl.\sw-slide75~
-gp\(chips)',
 PATH='I63',
 DRAWING='@BASEBOARD_FAB2_LIB.BASEBOARD_FAB2(SCH_1):PAGE268',
 SEC_TYPE='DISCRET-G6',
 PHYS_PAGE='255',
 XY='(-2050,3325)',
 ROT='2',
 VER='1',
 VALUE='SW-SLIDE75-GP',
 PACK_TYPE='DISCRET-G6',
 PART_NUMBER='62.40018.461',
 LOCATION='S9W1',
 SEC='1',
 CDS_LIB='w_hdl',
 CDS_PART_NAME='SW-SLIDE75-GP_DISCRET-G6-SW-SLA',
 PRIM_FILE='C:/<user>/w_hdl/sw#2dslide75#2dgp/chips/chips.prt';

PART_NAME
 SH3D1 'SHUNT_SH0201-EMPTY,N_A':;

SECTION_NUMBER 1
 '@BASEBOARD_FAB2_LIB.BASEBOARD_FAB2(SCH_1):PAGE214_I130@MSTR_MISC.SHUNT(CHIPS)':
 C_PATH='@baseboard_fab2_lib.baseboard_fab2(sch_1):page214_i130@mstr_misc.shunt(~
chips)',
 P_PATH='@baseboard_fab2_lib.baseboard_fab2(sch_1):page214_i130@mstr_misc.shunt(~
chips)',
 PATH='I130',
 DRAWING='@BASEBOARD_FAB2_LIB.BASEBOARD_FAB2(SCH_1):PAGE214',
 PIN_SHORT='A:B',
 SEC_TYPE='SH0201',
 MATERIAL='EMPTY',
 PHYS_PAGE='214',
 XY='(-1250,1300)',
 ROT='0',
 VER='1',
 PACK_TYPE='SH0201',
 PART_NUMBER='N_A',
 LOCATION='SH3D1',
 SEC='1',
 CDS_LIB='mstr_misc',
 CDS_PART_NAME='SHUNT_SH0201-EMPTY,N_A',
 PRIM_FILE='./archive_libs/mstr_misc/shunt/chips/chips.prt';

PART_NAME
 SH3D2 'SHUNT_SH0201-EMPTY,N_A':;

SECTION_NUMBER 1
 '@BASEBOARD_FAB2_LIB.BASEBOARD_FAB2(SCH_1):PAGE214_I129@MSTR_MISC.SHUNT(CHIPS)':
 C_PATH='@baseboard_fab2_lib.baseboard_fab2(sch_1):page214_i129@mstr_misc.shunt(~
chips)',
 P_PATH='@baseboard_fab2_lib.baseboard_fab2(sch_1):page214_i129@mstr_misc.shunt(~
chips)',
 PATH='I129',
 DRAWING='@BASEBOARD_FAB2_LIB.BASEBOARD_FAB2(SCH_1):PAGE214',
 PIN_SHORT='A:B',
 SEC_TYPE='SH0201',
 MATERIAL='EMPTY',
 PHYS_PAGE='214',
 XY='(-1250,1750)',
 ROT='0',
 VER='1',
 PACK_TYPE='SH0201',
 PART_NUMBER='N_A',
 LOCATION='SH3D2',
 SEC='1',
 CDS_LIB='mstr_misc',
 CDS_PART_NAME='SHUNT_SH0201-EMPTY,N_A',
 PRIM_FILE='./archive_libs/mstr_misc/shunt/chips/chips.prt';

PART_NAME
 SH3P1 'SHUNT_SH0201-EMPTY,N_A':;

SECTION_NUMBER 1
 '@BASEBOARD_FAB2_LIB.BASEBOARD_FAB2(SCH_1):PAGE212_I104@MSTR_MISC.SHUNT(CHIPS)':
 C_PATH='@baseboard_fab2_lib.baseboard_fab2(sch_1):page212_i104@mstr_misc.shunt(~
chips)',
 P_PATH='@baseboard_fab2_lib.baseboard_fab2(sch_1):page212_i104@mstr_misc.shunt(~
chips)',
 PATH='I104',
 DRAWING='@BASEBOARD_FAB2_LIB.BASEBOARD_FAB2(SCH_1):PAGE212',
 PIN_SHORT='A:B',
 SEC_TYPE='SH0201',
 MATERIAL='EMPTY',
 PHYS_PAGE='212',
 XY='(-1300,1850)',
 ROT='0',
 VER='1',
 PACK_TYPE='SH0201',
 PART_NUMBER='N_A',
 LOCATION='SH3P1',
 SEC='1',
 CDS_LIB='mstr_misc',
 CDS_PART_NAME='SHUNT_SH0201-EMPTY,N_A',
 PRIM_FILE='./archive_libs/mstr_misc/shunt/chips/chips.prt';

PART_NAME
 SH3P2 'SHUNT_SH0201-EMPTY,N_A':;

SECTION_NUMBER 1
 '@BASEBOARD_FAB2_LIB.BASEBOARD_FAB2(SCH_1):PAGE212_I105@MSTR_MISC.SHUNT(CHIPS)':
 C_PATH='@baseboard_fab2_lib.baseboard_fab2(sch_1):page212_i105@mstr_misc.shunt(~
chips)',
 P_PATH='@baseboard_fab2_lib.baseboard_fab2(sch_1):page212_i105@mstr_misc.shunt(~
chips)',
 PATH='I105',
 DRAWING='@BASEBOARD_FAB2_LIB.BASEBOARD_FAB2(SCH_1):PAGE212',
 PIN_SHORT='A:B',
 SEC_TYPE='SH0201',
 MATERIAL='EMPTY',
 PHYS_PAGE='212',
 XY='(-1300,1400)',
 ROT='0',
 VER='1',
 PACK_TYPE='SH0201',
 PART_NUMBER='N_A',
 LOCATION='SH3P2',
 SEC='1',
 CDS_LIB='mstr_misc',
 CDS_PART_NAME='SHUNT_SH0201-EMPTY,N_A',
 PRIM_FILE='./archive_libs/mstr_misc/shunt/chips/chips.prt';

PART_NAME
 SH4L1 'SHUNT_SH0201-EMPTY,N_A':;

SECTION_NUMBER 1
 '@BASEBOARD_FAB2_LIB.BASEBOARD_FAB2(SCH_1):PAGE220_I240@MSTR_MISC.SHUNT(CHIPS)':
 C_PATH='@baseboard_fab2_lib.baseboard_fab2(sch_1):page220_i240@mstr_misc.shunt(~
chips)',
 P_PATH='@baseboard_fab2_lib.baseboard_fab2(sch_1):page220_i240@mstr_misc.shunt(~
chips)',
 PATH='I240',
 DRAWING='@BASEBOARD_FAB2_LIB.BASEBOARD_FAB2(SCH_1):PAGE220',
 PIN_SHORT='A:B',
 SEC_TYPE='SH0201',
 MATERIAL='EMPTY',
 PHYS_PAGE='220',
 XY='(-325,1625)',
 ROT='0',
 VER='1',
 PACK_TYPE='SH0201',
 PART_NUMBER='N_A',
 LOCATION='SH4L1',
 SEC='1',
 CDS_LIB='mstr_misc',
 CDS_PART_NAME='SHUNT_SH0201-EMPTY,N_A',
 PRIM_FILE='./archive_libs/mstr_misc/shunt/chips/chips.prt';

PART_NAME
 SH4L2 'SHUNT_SH0201-EMPTY,N_A':;

SECTION_NUMBER 1
 '@BASEBOARD_FAB2_LIB.BASEBOARD_FAB2(SCH_1):PAGE220_I239@MSTR_MISC.SHUNT(CHIPS)':
 C_PATH='@baseboard_fab2_lib.baseboard_fab2(sch_1):page220_i239@mstr_misc.shunt(~
chips)',
 P_PATH='@baseboard_fab2_lib.baseboard_fab2(sch_1):page220_i239@mstr_misc.shunt(~
chips)',
 PATH='I239',
 DRAWING='@BASEBOARD_FAB2_LIB.BASEBOARD_FAB2(SCH_1):PAGE220',
 PIN_SHORT='A:B',
 SEC_TYPE='SH0201',
 MATERIAL='EMPTY',
 PHYS_PAGE='220',
 XY='(-300,2075)',
 ROT='0',
 VER='1',
 PACK_TYPE='SH0201',
 PART_NUMBER='N_A',
 LOCATION='SH4L2',
 SEC='1',
 CDS_LIB='mstr_misc',
 CDS_PART_NAME='SHUNT_SH0201-EMPTY,N_A',
 PRIM_FILE='./archive_libs/mstr_misc/shunt/chips/chips.prt';

PART_NAME
 SH4U1 'SHUNT_SH0201-EMPTY,N_A':;

SECTION_NUMBER 1
 '@BASEBOARD_FAB2_LIB.BASEBOARD_FAB2(SCH_1):PAGE217_I259@MSTR_MISC.SHUNT(CHIPS)':
 C_PATH='@baseboard_fab2_lib.baseboard_fab2(sch_1):page217_i259@mstr_misc.shunt(~
chips)',
 P_PATH='@baseboard_fab2_lib.baseboard_fab2(sch_1):page217_i259@mstr_misc.shunt(~
chips)',
 PATH='I259',
 DRAWING='@BASEBOARD_FAB2_LIB.BASEBOARD_FAB2(SCH_1):PAGE217',
 PIN_SHORT='A:B',
 SEC_TYPE='SH0201',
 MATERIAL='EMPTY',
 PHYS_PAGE='217',
 XY='(125,1500)',
 ROT='0',
 VER='1',
 PACK_TYPE='SH0201',
 PART_NUMBER='N_A',
 LOCATION='SH4U1',
 SEC='1',
 CDS_LIB='mstr_misc',
 CDS_PART_NAME='SHUNT_SH0201-EMPTY,N_A',
 PRIM_FILE='./archive_libs/mstr_misc/shunt/chips/chips.prt';

PART_NAME
 SH4U2 'SHUNT_SH0201-EMPTY,N_A':;

SECTION_NUMBER 1
 '@BASEBOARD_FAB2_LIB.BASEBOARD_FAB2(SCH_1):PAGE217_I260@MSTR_MISC.SHUNT(CHIPS)':
 C_PATH='@baseboard_fab2_lib.baseboard_fab2(sch_1):page217_i260@mstr_misc.shunt(~
chips)',
 P_PATH='@baseboard_fab2_lib.baseboard_fab2(sch_1):page217_i260@mstr_misc.shunt(~
chips)',
 PATH='I260',
 DRAWING='@BASEBOARD_FAB2_LIB.BASEBOARD_FAB2(SCH_1):PAGE217',
 PIN_SHORT='A:B',
 SEC_TYPE='SH0201',
 MATERIAL='EMPTY',
 PHYS_PAGE='217',
 XY='(150,1950)',
 ROT='0',
 VER='1',
 PACK_TYPE='SH0201',
 PART_NUMBER='N_A',
 LOCATION='SH4U2',
 SEC='1',
 CDS_LIB='mstr_misc',
 CDS_PART_NAME='SHUNT_SH0201-EMPTY,N_A',
 PRIM_FILE='./archive_libs/mstr_misc/shunt/chips/chips.prt';

PART_NAME
 SH5L1 'SHUNT_SH0201-EMPTY,N_A':;

SECTION_NUMBER 1
 '@BASEBOARD_FAB2_LIB.BASEBOARD_FAB2(SCH_1):PAGE222_I30@MSTR_MISC.SHUNT(CHIPS)':
 C_PATH='@baseboard_fab2_lib.baseboard_fab2(sch_1):page222_i30@mstr_misc.shunt(c~
hips)',
 P_PATH='@baseboard_fab2_lib.baseboard_fab2(sch_1):page222_i30@mstr_misc.shunt(c~
hips)',
 PATH='I30',
 DRAWING='@BASEBOARD_FAB2_LIB.BASEBOARD_FAB2(SCH_1):PAGE222',
 PIN_SHORT='A:B',
 SEC_TYPE='SH0201',
 MATERIAL='EMPTY',
 PHYS_PAGE='222',
 XY='(4175,-425)',
 ROT='0',
 VER='1',
 PACK_TYPE='SH0201',
 PART_NUMBER='N_A',
 LOCATION='SH5L1',
 SEC='1',
 CDS_LIB='mstr_misc',
 CDS_PART_NAME='SHUNT_SH0201-EMPTY,N_A',
 PRIM_FILE='./archive_libs/mstr_misc/shunt/chips/chips.prt';

PART_NAME
 SH5U1 'SHUNT_SH0201-EMPTY,N_A':;

SECTION_NUMBER 1
 '@BASEBOARD_FAB2_LIB.BASEBOARD_FAB2(SCH_1):PAGE221_I9@MSTR_MISC.SHUNT(CHIPS)':
 C_PATH='@baseboard_fab2_lib.baseboard_fab2(sch_1):page221_i9@mstr_misc.shunt(ch~
ips)',
 P_PATH='@baseboard_fab2_lib.baseboard_fab2(sch_1):page221_i9@mstr_misc.shunt(ch~
ips)',
 PATH='I9',
 DRAWING='@BASEBOARD_FAB2_LIB.BASEBOARD_FAB2(SCH_1):PAGE221',
 PIN_SHORT='A:B',
 SEC_TYPE='SH0201',
 MATERIAL='EMPTY',
 PHYS_PAGE='221',
 XY='(4700,-75)',
 ROT='0',
 VER='1',
 PACK_TYPE='SH0201',
 PART_NUMBER='N_A',
 LOCATION='SH5U1',
 SEC='1',
 CDS_LIB='mstr_misc',
 CDS_PART_NAME='SHUNT_SH0201-EMPTY,N_A',
 PRIM_FILE='./archive_libs/mstr_misc/shunt/chips/chips.prt';

PART_NAME
 SH7L1 'SHUNT_SH0201-EMPTY,N_A':;

SECTION_NUMBER 1
 '@BASEBOARD_FAB2_LIB.BASEBOARD_FAB2(SCH_1):PAGE228_I246@MSTR_MISC.SHUNT(CHIPS)':
 C_PATH='@baseboard_fab2_lib.baseboard_fab2(sch_1):page228_i246@mstr_misc.shunt(~
chips)',
 P_PATH='@baseboard_fab2_lib.baseboard_fab2(sch_1):page228_i246@mstr_misc.shunt(~
chips)',
 PATH='I246',
 DRAWING='@BASEBOARD_FAB2_LIB.BASEBOARD_FAB2(SCH_1):PAGE228',
 PIN_SHORT='A:B',
 SEC_TYPE='SH0201',
 MATERIAL='EMPTY',
 PHYS_PAGE='228',
 XY='(75,1725)',
 ROT='0',
 VER='1',
 PACK_TYPE='SH0201',
 PART_NUMBER='N_A',
 LOCATION='SH7L1',
 SEC='1',
 CDS_LIB='mstr_misc',
 CDS_PART_NAME='SHUNT_SH0201-EMPTY,N_A',
 PRIM_FILE='./archive_libs/mstr_misc/shunt/chips/chips.prt';

PART_NAME
 SH7L2 'SHUNT_SH0201-EMPTY,N_A':;

SECTION_NUMBER 1
 '@BASEBOARD_FAB2_LIB.BASEBOARD_FAB2(SCH_1):PAGE228_I245@MSTR_MISC.SHUNT(CHIPS)':
 C_PATH='@baseboard_fab2_lib.baseboard_fab2(sch_1):page228_i245@mstr_misc.shunt(~
chips)',
 P_PATH='@baseboard_fab2_lib.baseboard_fab2(sch_1):page228_i245@mstr_misc.shunt(~
chips)',
 PATH='I245',
 DRAWING='@BASEBOARD_FAB2_LIB.BASEBOARD_FAB2(SCH_1):PAGE228',
 PIN_SHORT='A:B',
 SEC_TYPE='SH0201',
 MATERIAL='EMPTY',
 PHYS_PAGE='228',
 XY='(75,2175)',
 ROT='0',
 VER='1',
 PACK_TYPE='SH0201',
 PART_NUMBER='N_A',
 LOCATION='SH7L2',
 SEC='1',
 CDS_LIB='mstr_misc',
 CDS_PART_NAME='SHUNT_SH0201-EMPTY,N_A',
 PRIM_FILE='./archive_libs/mstr_misc/shunt/chips/chips.prt';

PART_NAME
 SH7U1 'SHUNT_SH0201-EMPTY,N_A':;

SECTION_NUMBER 1
 '@BASEBOARD_FAB2_LIB.BASEBOARD_FAB2(SCH_1):PAGE225_I243@MSTR_MISC.SHUNT(CHIPS)':
 C_PATH='@baseboard_fab2_lib.baseboard_fab2(sch_1):page225_i243@mstr_misc.shunt(~
chips)',
 P_PATH='@baseboard_fab2_lib.baseboard_fab2(sch_1):page225_i243@mstr_misc.shunt(~
chips)',
 PATH='I243',
 DRAWING='@BASEBOARD_FAB2_LIB.BASEBOARD_FAB2(SCH_1):PAGE225',
 PIN_SHORT='A:B',
 SEC_TYPE='SH0201',
 MATERIAL='EMPTY',
 PHYS_PAGE='225',
 XY='(-250,2325)',
 ROT='0',
 VER='1',
 PACK_TYPE='SH0201',
 PART_NUMBER='N_A',
 LOCATION='SH7U1',
 SEC='1',
 CDS_LIB='mstr_misc',
 CDS_PART_NAME='SHUNT_SH0201-EMPTY,N_A',
 PRIM_FILE='./archive_libs/mstr_misc/shunt/chips/chips.prt';

PART_NAME
 SH7U2 'SHUNT_SH0201-EMPTY,N_A':;

SECTION_NUMBER 1
 '@BASEBOARD_FAB2_LIB.BASEBOARD_FAB2(SCH_1):PAGE225_I244@MSTR_MISC.SHUNT(CHIPS)':
 C_PATH='@baseboard_fab2_lib.baseboard_fab2(sch_1):page225_i244@mstr_misc.shunt(~
chips)',
 P_PATH='@baseboard_fab2_lib.baseboard_fab2(sch_1):page225_i244@mstr_misc.shunt(~
chips)',
 PATH='I244',
 DRAWING='@BASEBOARD_FAB2_LIB.BASEBOARD_FAB2(SCH_1):PAGE225',
 PIN_SHORT='A:B',
 SEC_TYPE='SH0201',
 MATERIAL='EMPTY',
 PHYS_PAGE='225',
 XY='(-275,1875)',
 ROT='0',
 VER='1',
 PACK_TYPE='SH0201',
 PART_NUMBER='N_A',
 LOCATION='SH7U2',
 SEC='1',
 CDS_LIB='mstr_misc',
 CDS_PART_NAME='SHUNT_SH0201-EMPTY,N_A',
 PRIM_FILE='./archive_libs/mstr_misc/shunt/chips/chips.prt';

PART_NAME
 SH8L1 'SHUNT_SH0201-EMPTY,N_A':;

SECTION_NUMBER 1
 '@BASEBOARD_FAB2_LIB.BASEBOARD_FAB2(SCH_1):PAGE230_I30@MSTR_MISC.SHUNT(CHIPS)':
 C_PATH='@baseboard_fab2_lib.baseboard_fab2(sch_1):page230_i30@mstr_misc.shunt(c~
hips)',
 P_PATH='@baseboard_fab2_lib.baseboard_fab2(sch_1):page230_i30@mstr_misc.shunt(c~
hips)',
 PATH='I30',
 DRAWING='@BASEBOARD_FAB2_LIB.BASEBOARD_FAB2(SCH_1):PAGE230',
 PIN_SHORT='A:B',
 SEC_TYPE='SH0201',
 MATERIAL='EMPTY',
 PHYS_PAGE='230',
 XY='(3300,-700)',
 ROT='0',
 VER='1',
 PACK_TYPE='SH0201',
 PART_NUMBER='N_A',
 LOCATION='SH8L1',
 SEC='1',
 CDS_LIB='mstr_misc',
 CDS_PART_NAME='SHUNT_SH0201-EMPTY,N_A',
 PRIM_FILE='./archive_libs/mstr_misc/shunt/chips/chips.prt';

PART_NAME
 SH8U1 'SHUNT_SH0201-EMPTY,N_A':;

SECTION_NUMBER 1
 '@BASEBOARD_FAB2_LIB.BASEBOARD_FAB2(SCH_1):PAGE229_I12@MSTR_MISC.SHUNT(CHIPS)':
 C_PATH='@baseboard_fab2_lib.baseboard_fab2(sch_1):page229_i12@mstr_misc.shunt(c~
hips)',
 P_PATH='@baseboard_fab2_lib.baseboard_fab2(sch_1):page229_i12@mstr_misc.shunt(c~
hips)',
 PATH='I12',
 DRAWING='@BASEBOARD_FAB2_LIB.BASEBOARD_FAB2(SCH_1):PAGE229',
 PIN_SHORT='A:B',
 SEC_TYPE='SH0201',
 MATERIAL='EMPTY',
 PHYS_PAGE='229',
 XY='(4850,-150)',
 ROT='0',
 VER='1',
 PACK_TYPE='SH0201',
 PART_NUMBER='N_A',
 LOCATION='SH8U1',
 SEC='1',
 CDS_LIB='mstr_misc',
 CDS_PART_NAME='SHUNT_SH0201-EMPTY,N_A',
 PRIM_FILE='./archive_libs/mstr_misc/shunt/chips/chips.prt';

PART_NAME
 T1D1 'TEST-PAD-12P-1-GP-U_DISCRET-GBA':;

SECTION_NUMBER 1
 '@BASEBOARD_FAB2_LIB.BASEBOARD_FAB2(SCH_1):PAGE270_I1@W_HDL.TEST-PAD-12P-1-GP-U(CHIPS)':
 C_PATH='@baseboard_fab2_lib.baseboard_fab2(sch_1):page270_i1@w_hdl.\test-pad-12~
p-1-gp-u\(chips)',
 P_PATH='@baseboard_fab2_lib.baseboard_fab2(sch_1):page257_i1@w_hdl.\test-pad-12~
p-1-gp-u\(chips)',
 PATH='I1',
 DRAWING='@BASEBOARD_FAB2_LIB.BASEBOARD_FAB2(SCH_1):PAGE270',
 SEC_TYPE='DISCRET-GB1',
 PHYS_PAGE='257',
 XY='(-8825,5975)',
 ROT='0',
 VER='1',
 VALUE='TEST-PAD-12P-1-GP-U',
 PACK_TYPE='DISCRET-GB1',
 PART_NUMBER='ZZ.00PAD.MJ1',
 LOCATION='T1D1',
 SEC='1',
 CDS_LIB='w_hdl',
 CDS_PART_NAME='TEST-PAD-12P-1-GP-U_DISCRET-GBA',
 PRIM_FILE='C:/<user>/w_hdl/test#2dpad#2d12p#2d1#2dgp#2du/chips/chips.prt';

PART_NAME
 T1D2 'TEST-PAD-12P-1-GP-U_DISCRET-GBA':;

SECTION_NUMBER 1
 '@BASEBOARD_FAB2_LIB.BASEBOARD_FAB2(SCH_1):PAGE270_I3@W_HDL.TEST-PAD-12P-1-GP-U(CHIPS)':
 C_PATH='@baseboard_fab2_lib.baseboard_fab2(sch_1):page270_i3@w_hdl.\test-pad-12~
p-1-gp-u\(chips)',
 P_PATH='@baseboard_fab2_lib.baseboard_fab2(sch_1):page257_i3@w_hdl.\test-pad-12~
p-1-gp-u\(chips)',
 PATH='I3',
 DRAWING='@BASEBOARD_FAB2_LIB.BASEBOARD_FAB2(SCH_1):PAGE270',
 SEC_TYPE='DISCRET-GB1',
 PHYS_PAGE='257',
 XY='(-7225,5975)',
 ROT='2',
 VER='1',
 VALUE='TEST-PAD-12P-1-GP-U',
 PACK_TYPE='DISCRET-GB1',
 PART_NUMBER='ZZ.00PAD.MJ1',
 LOCATION='T1D2',
 SEC='1',
 CDS_LIB='w_hdl',
 CDS_PART_NAME='TEST-PAD-12P-1-GP-U_DISCRET-GBA',
 PRIM_FILE='C:/<user>/w_hdl/test#2dpad#2d12p#2d1#2dgp#2du/chips/chips.prt';

PART_NAME
 T1D3 'TEST-PAD-12P-1-GP-U_DISCRET-GBA':;

SECTION_NUMBER 1
 '@BASEBOARD_FAB2_LIB.BASEBOARD_FAB2(SCH_1):PAGE270_I5@W_HDL.TEST-PAD-12P-1-GP-U(CHIPS)':
 C_PATH='@baseboard_fab2_lib.baseboard_fab2(sch_1):page270_i5@w_hdl.\test-pad-12~
p-1-gp-u\(chips)',
 P_PATH='@baseboard_fab2_lib.baseboard_fab2(sch_1):page257_i5@w_hdl.\test-pad-12~
p-1-gp-u\(chips)',
 PATH='I5',
 DRAWING='@BASEBOARD_FAB2_LIB.BASEBOARD_FAB2(SCH_1):PAGE270',
 SEC_TYPE='DISCRET-GB1',
 PHYS_PAGE='257',
 XY='(-8825,5025)',
 ROT='0',
 VER='1',
 VALUE='TEST-PAD-12P-1-GP-U',
 PACK_TYPE='DISCRET-GB1',
 PART_NUMBER='ZZ.00PAD.MJ1',
 LOCATION='T1D3',
 SEC='1',
 CDS_LIB='w_hdl',
 CDS_PART_NAME='TEST-PAD-12P-1-GP-U_DISCRET-GBA',
 PRIM_FILE='C:/<user>/w_hdl/test#2dpad#2d12p#2d1#2dgp#2du/chips/chips.prt';

PART_NAME
 T1D4 'TEST-PAD-12P-1-GP-U_DISCRET-GBA':;

SECTION_NUMBER 1
 '@BASEBOARD_FAB2_LIB.BASEBOARD_FAB2(SCH_1):PAGE270_I6@W_HDL.TEST-PAD-12P-1-GP-U(CHIPS)':
 C_PATH='@baseboard_fab2_lib.baseboard_fab2(sch_1):page270_i6@w_hdl.\test-pad-12~
p-1-gp-u\(chips)',
 P_PATH='@baseboard_fab2_lib.baseboard_fab2(sch_1):page257_i6@w_hdl.\test-pad-12~
p-1-gp-u\(chips)',
 PATH='I6',
 DRAWING='@BASEBOARD_FAB2_LIB.BASEBOARD_FAB2(SCH_1):PAGE270',
 SEC_TYPE='DISCRET-GB1',
 PHYS_PAGE='257',
 XY='(-7225,5025)',
 ROT='2',
 VER='1',
 VALUE='TEST-PAD-12P-1-GP-U',
 PACK_TYPE='DISCRET-GB1',
 PART_NUMBER='ZZ.00PAD.MJ1',
 LOCATION='T1D4',
 SEC='1',
 CDS_LIB='w_hdl',
 CDS_PART_NAME='TEST-PAD-12P-1-GP-U_DISCRET-GBA',
 PRIM_FILE='C:/<user>/w_hdl/test#2dpad#2d12p#2d1#2dgp#2du/chips/chips.prt';

PART_NAME
 T1D5 'TEST-PAD-12P-1-GP-U_DISCRET-GBA':;

SECTION_NUMBER 1
 '@BASEBOARD_FAB2_LIB.BASEBOARD_FAB2(SCH_1):PAGE270_I12@W_HDL.TEST-PAD-12P-1-GP-U(CHIPS)':
 C_PATH='@baseboard_fab2_lib.baseboard_fab2(sch_1):page270_i12@w_hdl.\test-pad-1~
2p-1-gp-u\(chips)',
 P_PATH='@baseboard_fab2_lib.baseboard_fab2(sch_1):page257_i12@w_hdl.\test-pad-1~
2p-1-gp-u\(chips)',
 PATH='I12',
 DRAWING='@BASEBOARD_FAB2_LIB.BASEBOARD_FAB2(SCH_1):PAGE270',
 SEC_TYPE='DISCRET-GB1',
 PHYS_PAGE='257',
 XY='(-8825,4075)',
 ROT='0',
 VER='1',
 VALUE='TEST-PAD-12P-1-GP-U',
 PACK_TYPE='DISCRET-GB1',
 PART_NUMBER='ZZ.00PAD.MJ1',
 LOCATION='T1D5',
 SEC='1',
 CDS_LIB='w_hdl',
 CDS_PART_NAME='TEST-PAD-12P-1-GP-U_DISCRET-GBA',
 PRIM_FILE='C:/<user>/w_hdl/test#2dpad#2d12p#2d1#2dgp#2du/chips/chips.prt';

PART_NAME
 T1D6 'TEST-PAD-12P-1-GP-U_DISCRET-GBA':;

SECTION_NUMBER 1
 '@BASEBOARD_FAB2_LIB.BASEBOARD_FAB2(SCH_1):PAGE270_I9@W_HDL.TEST-PAD-12P-1-GP-U(CHIPS)':
 C_PATH='@baseboard_fab2_lib.baseboard_fab2(sch_1):page270_i9@w_hdl.\test-pad-12~
p-1-gp-u\(chips)',
 P_PATH='@baseboard_fab2_lib.baseboard_fab2(sch_1):page257_i9@w_hdl.\test-pad-12~
p-1-gp-u\(chips)',
 PATH='I9',
 DRAWING='@BASEBOARD_FAB2_LIB.BASEBOARD_FAB2(SCH_1):PAGE270',
 SEC_TYPE='DISCRET-GB1',
 PHYS_PAGE='257',
 XY='(-7225,4075)',
 ROT='2',
 VER='1',
 VALUE='TEST-PAD-12P-1-GP-U',
 PACK_TYPE='DISCRET-GB1',
 PART_NUMBER='ZZ.00PAD.MJ1',
 LOCATION='T1D6',
 SEC='1',
 CDS_LIB='w_hdl',
 CDS_PART_NAME='TEST-PAD-12P-1-GP-U_DISCRET-GBA',
 PRIM_FILE='C:/<user>/w_hdl/test#2dpad#2d12p#2d1#2dgp#2du/chips/chips.prt';

PART_NAME
 T1D7 'TEST-PAD-12P-1-GP-U_DISCRET-GBA':;

SECTION_NUMBER 1
 '@BASEBOARD_FAB2_LIB.BASEBOARD_FAB2(SCH_1):PAGE270_I16@W_HDL.TEST-PAD-12P-1-GP-U(CHIPS)':
 C_PATH='@baseboard_fab2_lib.baseboard_fab2(sch_1):page270_i16@w_hdl.\test-pad-1~
2p-1-gp-u\(chips)',
 P_PATH='@baseboard_fab2_lib.baseboard_fab2(sch_1):page257_i16@w_hdl.\test-pad-1~
2p-1-gp-u\(chips)',
 PATH='I16',
 DRAWING='@BASEBOARD_FAB2_LIB.BASEBOARD_FAB2(SCH_1):PAGE270',
 SEC_TYPE='DISCRET-GB1',
 PHYS_PAGE='257',
 XY='(-6375,6000)',
 ROT='0',
 VER='1',
 VALUE='TEST-PAD-12P-1-GP-U',
 PACK_TYPE='DISCRET-GB1',
 PART_NUMBER='ZZ.00PAD.MJ1',
 LOCATION='T1D7',
 SEC='1',
 CDS_LIB='w_hdl',
 CDS_PART_NAME='TEST-PAD-12P-1-GP-U_DISCRET-GBA',
 PRIM_FILE='C:/<user>/w_hdl/test#2dpad#2d12p#2d1#2dgp#2du/chips/chips.prt';

PART_NAME
 T1D8 'TEST-PAD-12P-1-GP-U_DISCRET-GBA':;

SECTION_NUMBER 1
 '@BASEBOARD_FAB2_LIB.BASEBOARD_FAB2(SCH_1):PAGE270_I13@W_HDL.TEST-PAD-12P-1-GP-U(CHIPS)':
 C_PATH='@baseboard_fab2_lib.baseboard_fab2(sch_1):page270_i13@w_hdl.\test-pad-1~
2p-1-gp-u\(chips)',
 P_PATH='@baseboard_fab2_lib.baseboard_fab2(sch_1):page257_i13@w_hdl.\test-pad-1~
2p-1-gp-u\(chips)',
 PATH='I13',
 DRAWING='@BASEBOARD_FAB2_LIB.BASEBOARD_FAB2(SCH_1):PAGE270',
 SEC_TYPE='DISCRET-GB1',
 PHYS_PAGE='257',
 XY='(-4775,6000)',
 ROT='2',
 VER='1',
 VALUE='TEST-PAD-12P-1-GP-U',
 PACK_TYPE='DISCRET-GB1',
 PART_NUMBER='ZZ.00PAD.MJ1',
 LOCATION='T1D8',
 SEC='1',
 CDS_LIB='w_hdl',
 CDS_PART_NAME='TEST-PAD-12P-1-GP-U_DISCRET-GBA',
 PRIM_FILE='C:/<user>/w_hdl/test#2dpad#2d12p#2d1#2dgp#2du/chips/chips.prt';

PART_NAME
 T1D9 'TEST-PAD-12P-1-GP-U_DISCRET-GBA':;

SECTION_NUMBER 1
 '@BASEBOARD_FAB2_LIB.BASEBOARD_FAB2(SCH_1):PAGE270_I18@W_HDL.TEST-PAD-12P-1-GP-U(CHIPS)':
 C_PATH='@baseboard_fab2_lib.baseboard_fab2(sch_1):page270_i18@w_hdl.\test-pad-1~
2p-1-gp-u\(chips)',
 P_PATH='@baseboard_fab2_lib.baseboard_fab2(sch_1):page257_i18@w_hdl.\test-pad-1~
2p-1-gp-u\(chips)',
 PATH='I18',
 DRAWING='@BASEBOARD_FAB2_LIB.BASEBOARD_FAB2(SCH_1):PAGE270',
 SEC_TYPE='DISCRET-GB1',
 PHYS_PAGE='257',
 XY='(-6375,5050)',
 ROT='0',
 VER='1',
 VALUE='TEST-PAD-12P-1-GP-U',
 PACK_TYPE='DISCRET-GB1',
 PART_NUMBER='ZZ.00PAD.MJ1',
 LOCATION='T1D9',
 SEC='1',
 CDS_LIB='w_hdl',
 CDS_PART_NAME='TEST-PAD-12P-1-GP-U_DISCRET-GBA',
 PRIM_FILE='C:/<user>/w_hdl/test#2dpad#2d12p#2d1#2dgp#2du/chips/chips.prt';

PART_NAME
 T1D10 'TEST-PAD-12P-1-GP-U_DISCRET-GBA':;

SECTION_NUMBER 1
 '@BASEBOARD_FAB2_LIB.BASEBOARD_FAB2(SCH_1):PAGE270_I17@W_HDL.TEST-PAD-12P-1-GP-U(CHIPS)':
 C_PATH='@baseboard_fab2_lib.baseboard_fab2(sch_1):page270_i17@w_hdl.\test-pad-1~
2p-1-gp-u\(chips)',
 P_PATH='@baseboard_fab2_lib.baseboard_fab2(sch_1):page257_i17@w_hdl.\test-pad-1~
2p-1-gp-u\(chips)',
 PATH='I17',
 DRAWING='@BASEBOARD_FAB2_LIB.BASEBOARD_FAB2(SCH_1):PAGE270',
 SEC_TYPE='DISCRET-GB1',
 PHYS_PAGE='257',
 XY='(-4775,5050)',
 ROT='2',
 VER='1',
 VALUE='TEST-PAD-12P-1-GP-U',
 PACK_TYPE='DISCRET-GB1',
 PART_NUMBER='ZZ.00PAD.MJ1',
 LOCATION='T1D10',
 SEC='1',
 CDS_LIB='w_hdl',
 CDS_PART_NAME='TEST-PAD-12P-1-GP-U_DISCRET-GBA',
 PRIM_FILE='C:/<user>/w_hdl/test#2dpad#2d12p#2d1#2dgp#2du/chips/chips.prt';

PART_NAME
 T1D11 'TEST-PAD-12P-1-GP-U_DISCRET-GBA':;

SECTION_NUMBER 1
 '@BASEBOARD_FAB2_LIB.BASEBOARD_FAB2(SCH_1):PAGE270_I24@W_HDL.TEST-PAD-12P-1-GP-U(CHIPS)':
 C_PATH='@baseboard_fab2_lib.baseboard_fab2(sch_1):page270_i24@w_hdl.\test-pad-1~
2p-1-gp-u\(chips)',
 P_PATH='@baseboard_fab2_lib.baseboard_fab2(sch_1):page257_i24@w_hdl.\test-pad-1~
2p-1-gp-u\(chips)',
 PATH='I24',
 DRAWING='@BASEBOARD_FAB2_LIB.BASEBOARD_FAB2(SCH_1):PAGE270',
 SEC_TYPE='DISCRET-GB1',
 PHYS_PAGE='257',
 XY='(-6375,4100)',
 ROT='0',
 VER='1',
 VALUE='TEST-PAD-12P-1-GP-U',
 PACK_TYPE='DISCRET-GB1',
 PART_NUMBER='ZZ.00PAD.MJ1',
 LOCATION='T1D11',
 SEC='1',
 CDS_LIB='w_hdl',
 CDS_PART_NAME='TEST-PAD-12P-1-GP-U_DISCRET-GBA',
 PRIM_FILE='C:/<user>/w_hdl/test#2dpad#2d12p#2d1#2dgp#2du/chips/chips.prt';

PART_NAME
 T1D12 'TEST-PAD-12P-1-GP-U_DISCRET-GBA':;

SECTION_NUMBER 1
 '@BASEBOARD_FAB2_LIB.BASEBOARD_FAB2(SCH_1):PAGE270_I21@W_HDL.TEST-PAD-12P-1-GP-U(CHIPS)':
 C_PATH='@baseboard_fab2_lib.baseboard_fab2(sch_1):page270_i21@w_hdl.\test-pad-1~
2p-1-gp-u\(chips)',
 P_PATH='@baseboard_fab2_lib.baseboard_fab2(sch_1):page257_i21@w_hdl.\test-pad-1~
2p-1-gp-u\(chips)',
 PATH='I21',
 DRAWING='@BASEBOARD_FAB2_LIB.BASEBOARD_FAB2(SCH_1):PAGE270',
 SEC_TYPE='DISCRET-GB1',
 PHYS_PAGE='257',
 XY='(-4775,4100)',
 ROT='2',
 VER='1',
 VALUE='TEST-PAD-12P-1-GP-U',
 PACK_TYPE='DISCRET-GB1',
 PART_NUMBER='ZZ.00PAD.MJ1',
 LOCATION='T1D12',
 SEC='1',
 CDS_LIB='w_hdl',
 CDS_PART_NAME='TEST-PAD-12P-1-GP-U_DISCRET-GBA',
 PRIM_FILE='C:/<user>/w_hdl/test#2dpad#2d12p#2d1#2dgp#2du/chips/chips.prt';

PART_NAME
 T1D13 'TEST-PAD-12P-1-GP-U_DISCRET-GBA':;

SECTION_NUMBER 1
 '@BASEBOARD_FAB2_LIB.BASEBOARD_FAB2(SCH_1):PAGE272_I5@W_HDL.TEST-PAD-12P-1-GP-U(CHIPS)':
 C_PATH='@baseboard_fab2_lib.baseboard_fab2(sch_1):page272_i5@w_hdl.\test-pad-12~
p-1-gp-u\(chips)',
 P_PATH='@baseboard_fab2_lib.baseboard_fab2(sch_1):page258_i5@w_hdl.\test-pad-12~
p-1-gp-u\(chips)',
 PATH='I5',
 DRAWING='@BASEBOARD_FAB2_LIB.BASEBOARD_FAB2(SCH_1):PAGE272',
 SEC_TYPE='DISCRET-GB1',
 PHYS_PAGE='258',
 XY='(-7600,5325)',
 ROT='0',
 VER='1',
 VALUE='TEST-PAD-12P-1-GP-U',
 PACK_TYPE='DISCRET-GB1',
 PART_NUMBER='ZZ.00PAD.MJ1',
 LOCATION='T1D13',
 SEC='1',
 CDS_LIB='w_hdl',
 CDS_PART_NAME='TEST-PAD-12P-1-GP-U_DISCRET-GBA',
 PRIM_FILE='C:/<user>/w_hdl/test#2dpad#2d12p#2d1#2dgp#2du/chips/chips.prt';

PART_NAME
 T1D14 'TEST-PAD-12P-1-GP-U_DISCRET-GBA':;

SECTION_NUMBER 1
 '@BASEBOARD_FAB2_LIB.BASEBOARD_FAB2(SCH_1):PAGE272_I22@W_HDL.TEST-PAD-12P-1-GP-U(CHIPS)':
 C_PATH='@baseboard_fab2_lib.baseboard_fab2(sch_1):page272_i22@w_hdl.\test-pad-1~
2p-1-gp-u\(chips)',
 P_PATH='@baseboard_fab2_lib.baseboard_fab2(sch_1):page258_i22@w_hdl.\test-pad-1~
2p-1-gp-u\(chips)',
 PATH='I22',
 DRAWING='@BASEBOARD_FAB2_LIB.BASEBOARD_FAB2(SCH_1):PAGE272',
 SEC_TYPE='DISCRET-GB1',
 PHYS_PAGE='258',
 XY='(-6000,5325)',
 ROT='2',
 VER='1',
 VALUE='TEST-PAD-12P-1-GP-U',
 PACK_TYPE='DISCRET-GB1',
 PART_NUMBER='ZZ.00PAD.MJ1',
 LOCATION='T1D14',
 SEC='1',
 CDS_LIB='w_hdl',
 CDS_PART_NAME='TEST-PAD-12P-1-GP-U_DISCRET-GBA',
 PRIM_FILE='C:/<user>/w_hdl/test#2dpad#2d12p#2d1#2dgp#2du/chips/chips.prt';

PART_NAME
 T1D15 'TEST-PAD-12P-1-GP-U_DISCRET-GBA':;

SECTION_NUMBER 1
 '@BASEBOARD_FAB2_LIB.BASEBOARD_FAB2(SCH_1):PAGE272_I3@W_HDL.TEST-PAD-12P-1-GP-U(CHIPS)':
 C_PATH='@baseboard_fab2_lib.baseboard_fab2(sch_1):page272_i3@w_hdl.\test-pad-12~
p-1-gp-u\(chips)',
 P_PATH='@baseboard_fab2_lib.baseboard_fab2(sch_1):page258_i3@w_hdl.\test-pad-12~
p-1-gp-u\(chips)',
 PATH='I3',
 DRAWING='@BASEBOARD_FAB2_LIB.BASEBOARD_FAB2(SCH_1):PAGE272',
 SEC_TYPE='DISCRET-GB1',
 PHYS_PAGE='258',
 XY='(-7600,4375)',
 ROT='0',
 VER='1',
 VALUE='TEST-PAD-12P-1-GP-U',
 PACK_TYPE='DISCRET-GB1',
 PART_NUMBER='ZZ.00PAD.MJ1',
 LOCATION='T1D15',
 SEC='1',
 CDS_LIB='w_hdl',
 CDS_PART_NAME='TEST-PAD-12P-1-GP-U_DISCRET-GBA',
 PRIM_FILE='C:/<user>/w_hdl/test#2dpad#2d12p#2d1#2dgp#2du/chips/chips.prt';

PART_NAME
 T1D16 'TEST-PAD-12P-1-GP-U_DISCRET-GBA':;

SECTION_NUMBER 1
 '@BASEBOARD_FAB2_LIB.BASEBOARD_FAB2(SCH_1):PAGE272_I14@W_HDL.TEST-PAD-12P-1-GP-U(CHIPS)':
 C_PATH='@baseboard_fab2_lib.baseboard_fab2(sch_1):page272_i14@w_hdl.\test-pad-1~
2p-1-gp-u\(chips)',
 P_PATH='@baseboard_fab2_lib.baseboard_fab2(sch_1):page258_i14@w_hdl.\test-pad-1~
2p-1-gp-u\(chips)',
 PATH='I14',
 DRAWING='@BASEBOARD_FAB2_LIB.BASEBOARD_FAB2(SCH_1):PAGE272',
 SEC_TYPE='DISCRET-GB1',
 PHYS_PAGE='258',
 XY='(-6000,4375)',
 ROT='2',
 VER='1',
 VALUE='TEST-PAD-12P-1-GP-U',
 PACK_TYPE='DISCRET-GB1',
 PART_NUMBER='ZZ.00PAD.MJ1',
 LOCATION='T1D16',
 SEC='1',
 CDS_LIB='w_hdl',
 CDS_PART_NAME='TEST-PAD-12P-1-GP-U_DISCRET-GBA',
 PRIM_FILE='C:/<user>/w_hdl/test#2dpad#2d12p#2d1#2dgp#2du/chips/chips.prt';

PART_NAME
 T1D17 'TEST-PAD-12P-1-GP-U_DISCRET-GBA':;

SECTION_NUMBER 1
 '@BASEBOARD_FAB2_LIB.BASEBOARD_FAB2(SCH_1):PAGE272_I1@W_HDL.TEST-PAD-12P-1-GP-U(CHIPS)':
 C_PATH='@baseboard_fab2_lib.baseboard_fab2(sch_1):page272_i1@w_hdl.\test-pad-12~
p-1-gp-u\(chips)',
 P_PATH='@baseboard_fab2_lib.baseboard_fab2(sch_1):page258_i1@w_hdl.\test-pad-12~
p-1-gp-u\(chips)',
 PATH='I1',
 DRAWING='@BASEBOARD_FAB2_LIB.BASEBOARD_FAB2(SCH_1):PAGE272',
 SEC_TYPE='DISCRET-GB1',
 PHYS_PAGE='258',
 XY='(-7600,3425)',
 ROT='0',
 VER='1',
 VALUE='TEST-PAD-12P-1-GP-U',
 PACK_TYPE='DISCRET-GB1',
 PART_NUMBER='ZZ.00PAD.MJ1',
 LOCATION='T1D17',
 SEC='1',
 CDS_LIB='w_hdl',
 CDS_PART_NAME='TEST-PAD-12P-1-GP-U_DISCRET-GBA',
 PRIM_FILE='C:/<user>/w_hdl/test#2dpad#2d12p#2d1#2dgp#2du/chips/chips.prt';

PART_NAME
 T1D18 'TEST-PAD-12P-1-GP-U_DISCRET-GBA':;

SECTION_NUMBER 1
 '@BASEBOARD_FAB2_LIB.BASEBOARD_FAB2(SCH_1):PAGE272_I8@W_HDL.TEST-PAD-12P-1-GP-U(CHIPS)':
 C_PATH='@baseboard_fab2_lib.baseboard_fab2(sch_1):page272_i8@w_hdl.\test-pad-12~
p-1-gp-u\(chips)',
 P_PATH='@baseboard_fab2_lib.baseboard_fab2(sch_1):page258_i8@w_hdl.\test-pad-12~
p-1-gp-u\(chips)',
 PATH='I8',
 DRAWING='@BASEBOARD_FAB2_LIB.BASEBOARD_FAB2(SCH_1):PAGE272',
 SEC_TYPE='DISCRET-GB1',
 PHYS_PAGE='258',
 XY='(-6000,3425)',
 ROT='2',
 VER='1',
 VALUE='TEST-PAD-12P-1-GP-U',
 PACK_TYPE='DISCRET-GB1',
 PART_NUMBER='ZZ.00PAD.MJ1',
 LOCATION='T1D18',
 SEC='1',
 CDS_LIB='w_hdl',
 CDS_PART_NAME='TEST-PAD-12P-1-GP-U_DISCRET-GBA',
 PRIM_FILE='C:/<user>/w_hdl/test#2dpad#2d12p#2d1#2dgp#2du/chips/chips.prt';

PART_NAME
 T1D19 'TEST-PAD-12P-1-GP-U_DISCRET-GBA':;

SECTION_NUMBER 1
 '@BASEBOARD_FAB2_LIB.BASEBOARD_FAB2(SCH_1):PAGE272_I23@W_HDL.TEST-PAD-12P-1-GP-U(CHIPS)':
 C_PATH='@baseboard_fab2_lib.baseboard_fab2(sch_1):page272_i23@w_hdl.\test-pad-1~
2p-1-gp-u\(chips)',
 P_PATH='@baseboard_fab2_lib.baseboard_fab2(sch_1):page258_i23@w_hdl.\test-pad-1~
2p-1-gp-u\(chips)',
 PATH='I23',
 DRAWING='@BASEBOARD_FAB2_LIB.BASEBOARD_FAB2(SCH_1):PAGE272',
 SEC_TYPE='DISCRET-GB1',
 PHYS_PAGE='258',
 XY='(-5150,5350)',
 ROT='0',
 VER='1',
 VALUE='TEST-PAD-12P-1-GP-U',
 PACK_TYPE='DISCRET-GB1',
 PART_NUMBER='ZZ.00PAD.MJ1',
 LOCATION='T1D19',
 SEC='1',
 CDS_LIB='w_hdl',
 CDS_PART_NAME='TEST-PAD-12P-1-GP-U_DISCRET-GBA',
 PRIM_FILE='C:/<user>/w_hdl/test#2dpad#2d12p#2d1#2dgp#2du/chips/chips.prt';

PART_NAME
 T1D20 'TEST-PAD-12P-1-GP-U_DISCRET-GBA':;

SECTION_NUMBER 1
 '@BASEBOARD_FAB2_LIB.BASEBOARD_FAB2(SCH_1):PAGE272_I24@W_HDL.TEST-PAD-12P-1-GP-U(CHIPS)':
 C_PATH='@baseboard_fab2_lib.baseboard_fab2(sch_1):page272_i24@w_hdl.\test-pad-1~
2p-1-gp-u\(chips)',
 P_PATH='@baseboard_fab2_lib.baseboard_fab2(sch_1):page258_i24@w_hdl.\test-pad-1~
2p-1-gp-u\(chips)',
 PATH='I24',
 DRAWING='@BASEBOARD_FAB2_LIB.BASEBOARD_FAB2(SCH_1):PAGE272',
 SEC_TYPE='DISCRET-GB1',
 PHYS_PAGE='258',
 XY='(-3550,5350)',
 ROT='2',
 VER='1',
 VALUE='TEST-PAD-12P-1-GP-U',
 PACK_TYPE='DISCRET-GB1',
 PART_NUMBER='ZZ.00PAD.MJ1',
 LOCATION='T1D20',
 SEC='1',
 CDS_LIB='w_hdl',
 CDS_PART_NAME='TEST-PAD-12P-1-GP-U_DISCRET-GBA',
 PRIM_FILE='C:/<user>/w_hdl/test#2dpad#2d12p#2d1#2dgp#2du/chips/chips.prt';

PART_NAME
 T1D21 'TEST-PAD-12P-1-GP-U_DISCRET-GBA':;

SECTION_NUMBER 1
 '@BASEBOARD_FAB2_LIB.BASEBOARD_FAB2(SCH_1):PAGE272_I16@W_HDL.TEST-PAD-12P-1-GP-U(CHIPS)':
 C_PATH='@baseboard_fab2_lib.baseboard_fab2(sch_1):page272_i16@w_hdl.\test-pad-1~
2p-1-gp-u\(chips)',
 P_PATH='@baseboard_fab2_lib.baseboard_fab2(sch_1):page258_i16@w_hdl.\test-pad-1~
2p-1-gp-u\(chips)',
 PATH='I16',
 DRAWING='@BASEBOARD_FAB2_LIB.BASEBOARD_FAB2(SCH_1):PAGE272',
 SEC_TYPE='DISCRET-GB1',
 PHYS_PAGE='258',
 XY='(-5150,4400)',
 ROT='0',
 VER='1',
 VALUE='TEST-PAD-12P-1-GP-U',
 PACK_TYPE='DISCRET-GB1',
 PART_NUMBER='ZZ.00PAD.MJ1',
 LOCATION='T1D21',
 SEC='1',
 CDS_LIB='w_hdl',
 CDS_PART_NAME='TEST-PAD-12P-1-GP-U_DISCRET-GBA',
 PRIM_FILE='C:/<user>/w_hdl/test#2dpad#2d12p#2d1#2dgp#2du/chips/chips.prt';

PART_NAME
 T1D22 'TEST-PAD-12P-1-GP-U_DISCRET-GBA':;

SECTION_NUMBER 1
 '@BASEBOARD_FAB2_LIB.BASEBOARD_FAB2(SCH_1):PAGE272_I21@W_HDL.TEST-PAD-12P-1-GP-U(CHIPS)':
 C_PATH='@baseboard_fab2_lib.baseboard_fab2(sch_1):page272_i21@w_hdl.\test-pad-1~
2p-1-gp-u\(chips)',
 P_PATH='@baseboard_fab2_lib.baseboard_fab2(sch_1):page258_i21@w_hdl.\test-pad-1~
2p-1-gp-u\(chips)',
 PATH='I21',
 DRAWING='@BASEBOARD_FAB2_LIB.BASEBOARD_FAB2(SCH_1):PAGE272',
 SEC_TYPE='DISCRET-GB1',
 PHYS_PAGE='258',
 XY='(-3550,4400)',
 ROT='2',
 VER='1',
 VALUE='TEST-PAD-12P-1-GP-U',
 PACK_TYPE='DISCRET-GB1',
 PART_NUMBER='ZZ.00PAD.MJ1',
 LOCATION='T1D22',
 SEC='1',
 CDS_LIB='w_hdl',
 CDS_PART_NAME='TEST-PAD-12P-1-GP-U_DISCRET-GBA',
 PRIM_FILE='C:/<user>/w_hdl/test#2dpad#2d12p#2d1#2dgp#2du/chips/chips.prt';

PART_NAME
 T1D23 'TEST-PAD-12P-1-GP-U_DISCRET-GBA':;

SECTION_NUMBER 1
 '@BASEBOARD_FAB2_LIB.BASEBOARD_FAB2(SCH_1):PAGE272_I9@W_HDL.TEST-PAD-12P-1-GP-U(CHIPS)':
 C_PATH='@baseboard_fab2_lib.baseboard_fab2(sch_1):page272_i9@w_hdl.\test-pad-12~
p-1-gp-u\(chips)',
 P_PATH='@baseboard_fab2_lib.baseboard_fab2(sch_1):page258_i9@w_hdl.\test-pad-12~
p-1-gp-u\(chips)',
 PATH='I9',
 DRAWING='@BASEBOARD_FAB2_LIB.BASEBOARD_FAB2(SCH_1):PAGE272',
 SEC_TYPE='DISCRET-GB1',
 PHYS_PAGE='258',
 XY='(-5150,3450)',
 ROT='0',
 VER='1',
 VALUE='TEST-PAD-12P-1-GP-U',
 PACK_TYPE='DISCRET-GB1',
 PART_NUMBER='ZZ.00PAD.MJ1',
 LOCATION='T1D23',
 SEC='1',
 CDS_LIB='w_hdl',
 CDS_PART_NAME='TEST-PAD-12P-1-GP-U_DISCRET-GBA',
 PRIM_FILE='C:/<user>/w_hdl/test#2dpad#2d12p#2d1#2dgp#2du/chips/chips.prt';

PART_NAME
 T1D24 'TEST-PAD-12P-1-GP-U_DISCRET-GBA':;

SECTION_NUMBER 1
 '@BASEBOARD_FAB2_LIB.BASEBOARD_FAB2(SCH_1):PAGE272_I12@W_HDL.TEST-PAD-12P-1-GP-U(CHIPS)':
 C_PATH='@baseboard_fab2_lib.baseboard_fab2(sch_1):page272_i12@w_hdl.\test-pad-1~
2p-1-gp-u\(chips)',
 P_PATH='@baseboard_fab2_lib.baseboard_fab2(sch_1):page258_i12@w_hdl.\test-pad-1~
2p-1-gp-u\(chips)',
 PATH='I12',
 DRAWING='@BASEBOARD_FAB2_LIB.BASEBOARD_FAB2(SCH_1):PAGE272',
 SEC_TYPE='DISCRET-GB1',
 PHYS_PAGE='258',
 XY='(-3550,3450)',
 ROT='2',
 VER='1',
 VALUE='TEST-PAD-12P-1-GP-U',
 PACK_TYPE='DISCRET-GB1',
 PART_NUMBER='ZZ.00PAD.MJ1',
 LOCATION='T1D24',
 SEC='1',
 CDS_LIB='w_hdl',
 CDS_PART_NAME='TEST-PAD-12P-1-GP-U_DISCRET-GBA',
 PRIM_FILE='C:/<user>/w_hdl/test#2dpad#2d12p#2d1#2dgp#2du/chips/chips.prt';

PART_NAME
 T1P1 'TPAD-DIFF-4P-GP_DISCRET-GB3-TPA':;

SECTION_NUMBER 1
 '@BASEBOARD_FAB2_LIB.BASEBOARD_FAB2(SCH_1):PAGE271_I3@W_HDL.TPAD-DIFF-4P-GP(CHIPS)':
 C_PATH='@baseboard_fab2_lib.baseboard_fab2(sch_1):page271_i3@w_hdl.\tpad-diff-4~
p-gp\(chips)',
 P_PATH='@baseboard_fab2_lib.baseboard_fab2(sch_1):page256_i3@w_hdl.\tpad-diff-4~
p-gp\(chips)',
 PATH='I3',
 DRAWING='@BASEBOARD_FAB2_LIB.BASEBOARD_FAB2(SCH_1):PAGE271',
 SEC_TYPE='DISCRET-GB3',
 PHYS_PAGE='256',
 XY='(-7975,6100)',
 ROT='0',
 VER='1',
 VALUE='TPAD-DIFF-4P-GP',
 PACK_TYPE='DISCRET-GB3',
 PART_NUMBER='ZZ.00PAD.NW1',
 LOCATION='T1P1',
 SEC='1',
 CDS_LIB='w_hdl',
 CDS_PART_NAME='TPAD-DIFF-4P-GP_DISCRET-GB3-TPA',
 PRIM_FILE='C:/<user>/w_hdl/tpad#2ddiff#2d4p#2dgp/chips/chips.prt';

PART_NAME
 T1P2 'TPAD-DIFF-4P-GP_DISCRET-GB3-TPA':;

SECTION_NUMBER 1
 '@BASEBOARD_FAB2_LIB.BASEBOARD_FAB2(SCH_1):PAGE271_I5@W_HDL.TPAD-DIFF-4P-GP(CHIPS)':
 C_PATH='@baseboard_fab2_lib.baseboard_fab2(sch_1):page271_i5@w_hdl.\tpad-diff-4~
p-gp\(chips)',
 P_PATH='@baseboard_fab2_lib.baseboard_fab2(sch_1):page256_i5@w_hdl.\tpad-diff-4~
p-gp\(chips)',
 PATH='I5',
 DRAWING='@BASEBOARD_FAB2_LIB.BASEBOARD_FAB2(SCH_1):PAGE271',
 SEC_TYPE='DISCRET-GB3',
 PHYS_PAGE='256',
 XY='(-7975,5700)',
 ROT='0',
 VER='1',
 VALUE='TPAD-DIFF-4P-GP',
 PACK_TYPE='DISCRET-GB3',
 PART_NUMBER='ZZ.00PAD.NW1',
 LOCATION='T1P2',
 SEC='1',
 CDS_LIB='w_hdl',
 CDS_PART_NAME='TPAD-DIFF-4P-GP_DISCRET-GB3-TPA',
 PRIM_FILE='C:/<user>/w_hdl/tpad#2ddiff#2d4p#2dgp/chips/chips.prt';

PART_NAME
 T1P3 'TPAD-DIFF-4P-GP_DISCRET-GB3-TPA':;

SECTION_NUMBER 1
 '@BASEBOARD_FAB2_LIB.BASEBOARD_FAB2(SCH_1):PAGE271_I8@W_HDL.TPAD-DIFF-4P-GP(CHIPS)':
 C_PATH='@baseboard_fab2_lib.baseboard_fab2(sch_1):page271_i8@w_hdl.\tpad-diff-4~
p-gp\(chips)',
 P_PATH='@baseboard_fab2_lib.baseboard_fab2(sch_1):page256_i8@w_hdl.\tpad-diff-4~
p-gp\(chips)',
 PATH='I8',
 DRAWING='@BASEBOARD_FAB2_LIB.BASEBOARD_FAB2(SCH_1):PAGE271',
 SEC_TYPE='DISCRET-GB3',
 PHYS_PAGE='256',
 XY='(-7975,5325)',
 ROT='0',
 VER='1',
 VALUE='TPAD-DIFF-4P-GP',
 PACK_TYPE='DISCRET-GB3',
 PART_NUMBER='ZZ.00PAD.NW1',
 LOCATION='T1P3',
 SEC='1',
 CDS_LIB='w_hdl',
 CDS_PART_NAME='TPAD-DIFF-4P-GP_DISCRET-GB3-TPA',
 PRIM_FILE='C:/<user>/w_hdl/tpad#2ddiff#2d4p#2dgp/chips/chips.prt';

PART_NAME
 T1P4 'TPAD-DIFF-4P-GP_DISCRET-GB3-TPA':;

SECTION_NUMBER 1
 '@BASEBOARD_FAB2_LIB.BASEBOARD_FAB2(SCH_1):PAGE271_I7@W_HDL.TPAD-DIFF-4P-GP(CHIPS)':
 C_PATH='@baseboard_fab2_lib.baseboard_fab2(sch_1):page271_i7@w_hdl.\tpad-diff-4~
p-gp\(chips)',
 P_PATH='@baseboard_fab2_lib.baseboard_fab2(sch_1):page256_i7@w_hdl.\tpad-diff-4~
p-gp\(chips)',
 PATH='I7',
 DRAWING='@BASEBOARD_FAB2_LIB.BASEBOARD_FAB2(SCH_1):PAGE271',
 SEC_TYPE='DISCRET-GB3',
 PHYS_PAGE='256',
 XY='(-7975,4925)',
 ROT='0',
 VER='1',
 VALUE='TPAD-DIFF-4P-GP',
 PACK_TYPE='DISCRET-GB3',
 PART_NUMBER='ZZ.00PAD.NW1',
 LOCATION='T1P4',
 SEC='1',
 CDS_LIB='w_hdl',
 CDS_PART_NAME='TPAD-DIFF-4P-GP_DISCRET-GB3-TPA',
 PRIM_FILE='C:/<user>/w_hdl/tpad#2ddiff#2d4p#2dgp/chips/chips.prt';

PART_NAME
 T1P5 'TPAD-DIFF-4P-GP_DISCRET-GB3-TPA':;

SECTION_NUMBER 1
 '@BASEBOARD_FAB2_LIB.BASEBOARD_FAB2(SCH_1):PAGE271_I11@W_HDL.TPAD-DIFF-4P-GP(CHIPS)':
 C_PATH='@baseboard_fab2_lib.baseboard_fab2(sch_1):page271_i11@w_hdl.\tpad-diff-~
4p-gp\(chips)',
 P_PATH='@baseboard_fab2_lib.baseboard_fab2(sch_1):page256_i11@w_hdl.\tpad-diff-~
4p-gp\(chips)',
 PATH='I11',
 DRAWING='@BASEBOARD_FAB2_LIB.BASEBOARD_FAB2(SCH_1):PAGE271',
 SEC_TYPE='DISCRET-GB3',
 PHYS_PAGE='256',
 XY='(-7950,4575)',
 ROT='0',
 VER='1',
 VALUE='TPAD-DIFF-4P-GP',
 PACK_TYPE='DISCRET-GB3',
 PART_NUMBER='ZZ.00PAD.NW1',
 LOCATION='T1P5',
 SEC='1',
 CDS_LIB='w_hdl',
 CDS_PART_NAME='TPAD-DIFF-4P-GP_DISCRET-GB3-TPA',
 PRIM_FILE='C:/<user>/w_hdl/tpad#2ddiff#2d4p#2dgp/chips/chips.prt';

PART_NAME
 T1P6 'TPAD-DIFF-4P-GP_DISCRET-GB3-TPA':;

SECTION_NUMBER 1
 '@BASEBOARD_FAB2_LIB.BASEBOARD_FAB2(SCH_1):PAGE271_I13@W_HDL.TPAD-DIFF-4P-GP(CHIPS)':
 C_PATH='@baseboard_fab2_lib.baseboard_fab2(sch_1):page271_i13@w_hdl.\tpad-diff-~
4p-gp\(chips)',
 P_PATH='@baseboard_fab2_lib.baseboard_fab2(sch_1):page256_i13@w_hdl.\tpad-diff-~
4p-gp\(chips)',
 PATH='I13',
 DRAWING='@BASEBOARD_FAB2_LIB.BASEBOARD_FAB2(SCH_1):PAGE271',
 SEC_TYPE='DISCRET-GB3',
 PHYS_PAGE='256',
 XY='(-7950,4175)',
 ROT='0',
 VER='1',
 VALUE='TPAD-DIFF-4P-GP',
 PACK_TYPE='DISCRET-GB3',
 PART_NUMBER='ZZ.00PAD.NW1',
 LOCATION='T1P6',
 SEC='1',
 CDS_LIB='w_hdl',
 CDS_PART_NAME='TPAD-DIFF-4P-GP_DISCRET-GB3-TPA',
 PRIM_FILE='C:/<user>/w_hdl/tpad#2ddiff#2d4p#2dgp/chips/chips.prt';

PART_NAME
 T1P7 'TPAD-DIFF-4P-GP_DISCRET-GB3-TPA':;

SECTION_NUMBER 1
 '@BASEBOARD_FAB2_LIB.BASEBOARD_FAB2(SCH_1):PAGE271_I17@W_HDL.TPAD-DIFF-4P-GP(CHIPS)':
 C_PATH='@baseboard_fab2_lib.baseboard_fab2(sch_1):page271_i17@w_hdl.\tpad-diff-~
4p-gp\(chips)',
 P_PATH='@baseboard_fab2_lib.baseboard_fab2(sch_1):page256_i17@w_hdl.\tpad-diff-~
4p-gp\(chips)',
 PATH='I17',
 DRAWING='@BASEBOARD_FAB2_LIB.BASEBOARD_FAB2(SCH_1):PAGE271',
 SEC_TYPE='DISCRET-GB3',
 PHYS_PAGE='256',
 XY='(-6000,6075)',
 ROT='0',
 VER='1',
 VALUE='TPAD-DIFF-4P-GP',
 PACK_TYPE='DISCRET-GB3',
 PART_NUMBER='ZZ.00PAD.NW1',
 LOCATION='T1P7',
 SEC='1',
 CDS_LIB='w_hdl',
 CDS_PART_NAME='TPAD-DIFF-4P-GP_DISCRET-GB3-TPA',
 PRIM_FILE='C:/<user>/w_hdl/tpad#2ddiff#2d4p#2dgp/chips/chips.prt';

PART_NAME
 T1P8 'TPAD-DIFF-4P-GP_DISCRET-GB3-TPA':;

SECTION_NUMBER 1
 '@BASEBOARD_FAB2_LIB.BASEBOARD_FAB2(SCH_1):PAGE271_I16@W_HDL.TPAD-DIFF-4P-GP(CHIPS)':
 C_PATH='@baseboard_fab2_lib.baseboard_fab2(sch_1):page271_i16@w_hdl.\tpad-diff-~
4p-gp\(chips)',
 P_PATH='@baseboard_fab2_lib.baseboard_fab2(sch_1):page256_i16@w_hdl.\tpad-diff-~
4p-gp\(chips)',
 PATH='I16',
 DRAWING='@BASEBOARD_FAB2_LIB.BASEBOARD_FAB2(SCH_1):PAGE271',
 SEC_TYPE='DISCRET-GB3',
 PHYS_PAGE='256',
 XY='(-6000,5675)',
 ROT='0',
 VER='1',
 VALUE='TPAD-DIFF-4P-GP',
 PACK_TYPE='DISCRET-GB3',
 PART_NUMBER='ZZ.00PAD.NW1',
 LOCATION='T1P8',
 SEC='1',
 CDS_LIB='w_hdl',
 CDS_PART_NAME='TPAD-DIFF-4P-GP_DISCRET-GB3-TPA',
 PRIM_FILE='C:/<user>/w_hdl/tpad#2ddiff#2d4p#2dgp/chips/chips.prt';

PART_NAME
 T1P9 'TPAD-DIFF-4P-GP_DISCRET-GB3-TPA':;

SECTION_NUMBER 1
 '@BASEBOARD_FAB2_LIB.BASEBOARD_FAB2(SCH_1):PAGE271_I19@W_HDL.TPAD-DIFF-4P-GP(CHIPS)':
 C_PATH='@baseboard_fab2_lib.baseboard_fab2(sch_1):page271_i19@w_hdl.\tpad-diff-~
4p-gp\(chips)',
 P_PATH='@baseboard_fab2_lib.baseboard_fab2(sch_1):page256_i19@w_hdl.\tpad-diff-~
4p-gp\(chips)',
 PATH='I19',
 DRAWING='@BASEBOARD_FAB2_LIB.BASEBOARD_FAB2(SCH_1):PAGE271',
 SEC_TYPE='DISCRET-GB3',
 PHYS_PAGE='256',
 XY='(-6000,5300)',
 ROT='0',
 VER='1',
 VALUE='TPAD-DIFF-4P-GP',
 PACK_TYPE='DISCRET-GB3',
 PART_NUMBER='ZZ.00PAD.NW1',
 LOCATION='T1P9',
 SEC='1',
 CDS_LIB='w_hdl',
 CDS_PART_NAME='TPAD-DIFF-4P-GP_DISCRET-GB3-TPA',
 PRIM_FILE='C:/<user>/w_hdl/tpad#2ddiff#2d4p#2dgp/chips/chips.prt';

PART_NAME
 T1P10 'TPAD-DIFF-4P-GP_DISCRET-GB3-TPA':;

SECTION_NUMBER 1
 '@BASEBOARD_FAB2_LIB.BASEBOARD_FAB2(SCH_1):PAGE271_I15@W_HDL.TPAD-DIFF-4P-GP(CHIPS)':
 C_PATH='@baseboard_fab2_lib.baseboard_fab2(sch_1):page271_i15@w_hdl.\tpad-diff-~
4p-gp\(chips)',
 P_PATH='@baseboard_fab2_lib.baseboard_fab2(sch_1):page256_i15@w_hdl.\tpad-diff-~
4p-gp\(chips)',
 PATH='I15',
 DRAWING='@BASEBOARD_FAB2_LIB.BASEBOARD_FAB2(SCH_1):PAGE271',
 SEC_TYPE='DISCRET-GB3',
 PHYS_PAGE='256',
 XY='(-6000,4900)',
 ROT='0',
 VER='1',
 VALUE='TPAD-DIFF-4P-GP',
 PACK_TYPE='DISCRET-GB3',
 PART_NUMBER='ZZ.00PAD.NW1',
 LOCATION='T1P10',
 SEC='1',
 CDS_LIB='w_hdl',
 CDS_PART_NAME='TPAD-DIFF-4P-GP_DISCRET-GB3-TPA',
 PRIM_FILE='C:/<user>/w_hdl/tpad#2ddiff#2d4p#2dgp/chips/chips.prt';

PART_NAME
 T1P11 'TPAD-DIFF-4P-GP_DISCRET-GB3-TPA':;

SECTION_NUMBER 1
 '@BASEBOARD_FAB2_LIB.BASEBOARD_FAB2(SCH_1):PAGE271_I23@W_HDL.TPAD-DIFF-4P-GP(CHIPS)':
 C_PATH='@baseboard_fab2_lib.baseboard_fab2(sch_1):page271_i23@w_hdl.\tpad-diff-~
4p-gp\(chips)',
 P_PATH='@baseboard_fab2_lib.baseboard_fab2(sch_1):page256_i23@w_hdl.\tpad-diff-~
4p-gp\(chips)',
 PATH='I23',
 DRAWING='@BASEBOARD_FAB2_LIB.BASEBOARD_FAB2(SCH_1):PAGE271',
 SEC_TYPE='DISCRET-GB3',
 PHYS_PAGE='256',
 XY='(-5975,4550)',
 ROT='0',
 VER='1',
 VALUE='TPAD-DIFF-4P-GP',
 PACK_TYPE='DISCRET-GB3',
 PART_NUMBER='ZZ.00PAD.NW1',
 LOCATION='T1P11',
 SEC='1',
 CDS_LIB='w_hdl',
 CDS_PART_NAME='TPAD-DIFF-4P-GP_DISCRET-GB3-TPA',
 PRIM_FILE='C:/<user>/w_hdl/tpad#2ddiff#2d4p#2dgp/chips/chips.prt';

PART_NAME
 T1P12 'TPAD-DIFF-4P-GP_DISCRET-GB3-TPA':;

SECTION_NUMBER 1
 '@BASEBOARD_FAB2_LIB.BASEBOARD_FAB2(SCH_1):PAGE271_I24@W_HDL.TPAD-DIFF-4P-GP(CHIPS)':
 C_PATH='@baseboard_fab2_lib.baseboard_fab2(sch_1):page271_i24@w_hdl.\tpad-diff-~
4p-gp\(chips)',
 P_PATH='@baseboard_fab2_lib.baseboard_fab2(sch_1):page256_i24@w_hdl.\tpad-diff-~
4p-gp\(chips)',
 PATH='I24',
 DRAWING='@BASEBOARD_FAB2_LIB.BASEBOARD_FAB2(SCH_1):PAGE271',
 SEC_TYPE='DISCRET-GB3',
 PHYS_PAGE='256',
 XY='(-5975,4150)',
 ROT='0',
 VER='1',
 VALUE='TPAD-DIFF-4P-GP',
 PACK_TYPE='DISCRET-GB3',
 PART_NUMBER='ZZ.00PAD.NW1',
 LOCATION='T1P12',
 SEC='1',
 CDS_LIB='w_hdl',
 CDS_PART_NAME='TPAD-DIFF-4P-GP_DISCRET-GB3-TPA',
 PRIM_FILE='C:/<user>/w_hdl/tpad#2ddiff#2d4p#2dgp/chips/chips.prt';

PART_NAME
 T1P14 'TPAD-DIFF-4P-GP_DISCRET-GB3-TPA':;

SECTION_NUMBER 1
 '@BASEBOARD_FAB2_LIB.BASEBOARD_FAB2(SCH_1):PAGE271_I30@W_HDL.TPAD-DIFF-4P-GP(CHIPS)':
 C_PATH='@baseboard_fab2_lib.baseboard_fab2(sch_1):page271_i30@w_hdl.\tpad-diff-~
4p-gp\(chips)',
 P_PATH='@baseboard_fab2_lib.baseboard_fab2(sch_1):page256_i30@w_hdl.\tpad-diff-~
4p-gp\(chips)',
 PATH='I30',
 DRAWING='@BASEBOARD_FAB2_LIB.BASEBOARD_FAB2(SCH_1):PAGE271',
 SEC_TYPE='DISCRET-GB3',
 PHYS_PAGE='256',
 XY='(-4200,5675)',
 ROT='0',
 VER='1',
 VALUE='TPAD-DIFF-4P-GP',
 PACK_TYPE='DISCRET-GB3',
 PART_NUMBER='ZZ.00PAD.NW1',
 LOCATION='T1P14',
 SEC='1',
 CDS_LIB='w_hdl',
 CDS_PART_NAME='TPAD-DIFF-4P-GP_DISCRET-GB3-TPA',
 PRIM_FILE='C:/<user>/w_hdl/tpad#2ddiff#2d4p#2dgp/chips/chips.prt';

PART_NAME
 T1P17 'TPAD-DIFF-4P-GP_DISCRET-GB3-TPA':;

SECTION_NUMBER 1
 '@BASEBOARD_FAB2_LIB.BASEBOARD_FAB2(SCH_1):PAGE271_I36@W_HDL.TPAD-DIFF-4P-GP(CHIPS)':
 C_PATH='@baseboard_fab2_lib.baseboard_fab2(sch_1):page271_i36@w_hdl.\tpad-diff-~
4p-gp\(chips)',
 P_PATH='@baseboard_fab2_lib.baseboard_fab2(sch_1):page256_i36@w_hdl.\tpad-diff-~
4p-gp\(chips)',
 PATH='I36',
 DRAWING='@BASEBOARD_FAB2_LIB.BASEBOARD_FAB2(SCH_1):PAGE271',
 SEC_TYPE='DISCRET-GB3',
 PHYS_PAGE='256',
 XY='(-4175,4550)',
 ROT='0',
 VER='1',
 VALUE='TPAD-DIFF-4P-GP',
 PACK_TYPE='DISCRET-GB3',
 PART_NUMBER='ZZ.00PAD.NW1',
 LOCATION='T1P17',
 SEC='1',
 CDS_LIB='w_hdl',
 CDS_PART_NAME='TPAD-DIFF-4P-GP_DISCRET-GB3-TPA',
 PRIM_FILE='C:/<user>/w_hdl/tpad#2ddiff#2d4p#2dgp/chips/chips.prt';

PART_NAME
 T1P19 'TPAD-DIFF-4P-GP_DISCRET-GB3-TPA':;

SECTION_NUMBER 1
 '@BASEBOARD_FAB2_LIB.BASEBOARD_FAB2(SCH_1):PAGE271_I39@W_HDL.TPAD-DIFF-4P-GP(CHIPS)':
 C_PATH='@baseboard_fab2_lib.baseboard_fab2(sch_1):page271_i39@w_hdl.\tpad-diff-~
4p-gp\(chips)',
 P_PATH='@baseboard_fab2_lib.baseboard_fab2(sch_1):page256_i39@w_hdl.\tpad-diff-~
4p-gp\(chips)',
 PATH='I39',
 DRAWING='@BASEBOARD_FAB2_LIB.BASEBOARD_FAB2(SCH_1):PAGE271',
 SEC_TYPE='DISCRET-GB3',
 PHYS_PAGE='256',
 XY='(-2400,6125)',
 ROT='0',
 VER='1',
 VALUE='TPAD-DIFF-4P-GP',
 PACK_TYPE='DISCRET-GB3',
 PART_NUMBER='ZZ.00PAD.NW1',
 LOCATION='T1P19',
 SEC='1',
 CDS_LIB='w_hdl',
 CDS_PART_NAME='TPAD-DIFF-4P-GP_DISCRET-GB3-TPA',
 PRIM_FILE='C:/<user>/w_hdl/tpad#2ddiff#2d4p#2dgp/chips/chips.prt';

PART_NAME
 T1P22 'TPAD-DIFF-4P-GP_DISCRET-GB3-TPA':;

SECTION_NUMBER 1
 '@BASEBOARD_FAB2_LIB.BASEBOARD_FAB2(SCH_1):PAGE271_I45@W_HDL.TPAD-DIFF-4P-GP(CHIPS)':
 C_PATH='@baseboard_fab2_lib.baseboard_fab2(sch_1):page271_i45@w_hdl.\tpad-diff-~
4p-gp\(chips)',
 P_PATH='@baseboard_fab2_lib.baseboard_fab2(sch_1):page256_i45@w_hdl.\tpad-diff-~
4p-gp\(chips)',
 PATH='I45',
 DRAWING='@BASEBOARD_FAB2_LIB.BASEBOARD_FAB2(SCH_1):PAGE271',
 SEC_TYPE='DISCRET-GB3',
 PHYS_PAGE='256',
 XY='(-2400,4950)',
 ROT='0',
 VER='1',
 VALUE='TPAD-DIFF-4P-GP',
 PACK_TYPE='DISCRET-GB3',
 PART_NUMBER='ZZ.00PAD.NW1',
 LOCATION='T1P22',
 SEC='1',
 CDS_LIB='w_hdl',
 CDS_PART_NAME='TPAD-DIFF-4P-GP_DISCRET-GB3-TPA',
 PRIM_FILE='C:/<user>/w_hdl/tpad#2ddiff#2d4p#2dgp/chips/chips.prt';

PART_NAME
 T1P23 'TPAD-DIFF-4P-GP_DISCRET-GB3-TPA':;

SECTION_NUMBER 1
 '@BASEBOARD_FAB2_LIB.BASEBOARD_FAB2(SCH_1):PAGE271_I47@W_HDL.TPAD-DIFF-4P-GP(CHIPS)':
 C_PATH='@baseboard_fab2_lib.baseboard_fab2(sch_1):page271_i47@w_hdl.\tpad-diff-~
4p-gp\(chips)',
 P_PATH='@baseboard_fab2_lib.baseboard_fab2(sch_1):page256_i47@w_hdl.\tpad-diff-~
4p-gp\(chips)',
 PATH='I47',
 DRAWING='@BASEBOARD_FAB2_LIB.BASEBOARD_FAB2(SCH_1):PAGE271',
 SEC_TYPE='DISCRET-GB3',
 PHYS_PAGE='256',
 XY='(-2375,4600)',
 ROT='0',
 VER='1',
 VALUE='TPAD-DIFF-4P-GP',
 PACK_TYPE='DISCRET-GB3',
 PART_NUMBER='ZZ.00PAD.NW1',
 LOCATION='T1P23',
 SEC='1',
 CDS_LIB='w_hdl',
 CDS_PART_NAME='TPAD-DIFF-4P-GP_DISCRET-GB3-TPA',
 PRIM_FILE='C:/<user>/w_hdl/tpad#2ddiff#2d4p#2dgp/chips/chips.prt';

PART_NAME
 T1P24 'TPAD-DIFF-4P-GP_DISCRET-GB3-TPA':;

SECTION_NUMBER 1
 '@BASEBOARD_FAB2_LIB.BASEBOARD_FAB2(SCH_1):PAGE271_I38@W_HDL.TPAD-DIFF-4P-GP(CHIPS)':
 C_PATH='@baseboard_fab2_lib.baseboard_fab2(sch_1):page271_i38@w_hdl.\tpad-diff-~
4p-gp\(chips)',
 P_PATH='@baseboard_fab2_lib.baseboard_fab2(sch_1):page256_i38@w_hdl.\tpad-diff-~
4p-gp\(chips)',
 PATH='I38',
 DRAWING='@BASEBOARD_FAB2_LIB.BASEBOARD_FAB2(SCH_1):PAGE271',
 SEC_TYPE='DISCRET-GB3',
 PHYS_PAGE='256',
 XY='(-2375,4200)',
 ROT='0',
 VER='1',
 VALUE='TPAD-DIFF-4P-GP',
 PACK_TYPE='DISCRET-GB3',
 PART_NUMBER='ZZ.00PAD.NW1',
 LOCATION='T1P24',
 SEC='1',
 CDS_LIB='w_hdl',
 CDS_PART_NAME='TPAD-DIFF-4P-GP_DISCRET-GB3-TPA',
 PRIM_FILE='C:/<user>/w_hdl/tpad#2ddiff#2d4p#2dgp/chips/chips.prt';

PART_NAME
 T1P25 'TPAD-SE-2P-GP_DISCRET-GA1-TPADA':;

SECTION_NUMBER 1
 '@BASEBOARD_FAB2_LIB.BASEBOARD_FAB2(SCH_1):PAGE271_I50@W_HDL.TPAD-SE-2P-GP(CHIPS)':
 C_PATH='@baseboard_fab2_lib.baseboard_fab2(sch_1):page271_i50@w_hdl.\tpad-se-2p~
-gp\(chips)',
 P_PATH='@baseboard_fab2_lib.baseboard_fab2(sch_1):page256_i50@w_hdl.\tpad-se-2p~
-gp\(chips)',
 PATH='I50',
 DRAWING='@BASEBOARD_FAB2_LIB.BASEBOARD_FAB2(SCH_1):PAGE271',
 PHYS_PAGE='256',
 XY='(-8300,3500)',
 ROT='2',
 VER='1',
 VALUE='TPAD-SE-2P-GP',
 PACK_TYPE='DISCRET-GA1',
 PART_NUMBER='ZZ.00PAD.NU1',
 LOCATION='T1P25',
 CDS_LIB='w_hdl',
 CDS_PART_NAME='TPAD-SE-2P-GP_DISCRET-GA1-TPADA',
 PRIM_FILE='C:/<user>/w_hdl/tpad#2dse#2d2p#2dgp/chips/chips.prt';

PART_NAME
 T1P26 'TPAD-SE-2P-GP_DISCRET-GA1-TPADA':;

SECTION_NUMBER 1
 '@BASEBOARD_FAB2_LIB.BASEBOARD_FAB2(SCH_1):PAGE271_I52@W_HDL.TPAD-SE-2P-GP(CHIPS)':
 C_PATH='@baseboard_fab2_lib.baseboard_fab2(sch_1):page271_i52@w_hdl.\tpad-se-2p~
-gp\(chips)',
 P_PATH='@baseboard_fab2_lib.baseboard_fab2(sch_1):page256_i52@w_hdl.\tpad-se-2p~
-gp\(chips)',
 PATH='I52',
 DRAWING='@BASEBOARD_FAB2_LIB.BASEBOARD_FAB2(SCH_1):PAGE271',
 PHYS_PAGE='256',
 XY='(-8300,3100)',
 ROT='2',
 VER='1',
 VALUE='TPAD-SE-2P-GP',
 PACK_TYPE='DISCRET-GA1',
 PART_NUMBER='ZZ.00PAD.NU1',
 LOCATION='T1P26',
 CDS_LIB='w_hdl',
 CDS_PART_NAME='TPAD-SE-2P-GP_DISCRET-GA1-TPADA',
 PRIM_FILE='C:/<user>/w_hdl/tpad#2dse#2d2p#2dgp/chips/chips.prt';

PART_NAME
 T1P27 'TPAD-SE-2P-GP_DISCRET-GA1-TPADA':;

SECTION_NUMBER 1
 '@BASEBOARD_FAB2_LIB.BASEBOARD_FAB2(SCH_1):PAGE271_I54@W_HDL.TPAD-SE-2P-GP(CHIPS)':
 C_PATH='@baseboard_fab2_lib.baseboard_fab2(sch_1):page271_i54@w_hdl.\tpad-se-2p~
-gp\(chips)',
 P_PATH='@baseboard_fab2_lib.baseboard_fab2(sch_1):page256_i54@w_hdl.\tpad-se-2p~
-gp\(chips)',
 PATH='I54',
 DRAWING='@BASEBOARD_FAB2_LIB.BASEBOARD_FAB2(SCH_1):PAGE271',
 PHYS_PAGE='256',
 XY='(-8300,2625)',
 ROT='2',
 VER='1',
 VALUE='TPAD-SE-2P-GP',
 PACK_TYPE='DISCRET-GA1',
 PART_NUMBER='ZZ.00PAD.NU1',
 LOCATION='T1P27',
 CDS_LIB='w_hdl',
 CDS_PART_NAME='TPAD-SE-2P-GP_DISCRET-GA1-TPADA',
 PRIM_FILE='C:/<user>/w_hdl/tpad#2dse#2d2p#2dgp/chips/chips.prt';

PART_NAME
 T1P28 'TPAD-SE-2P-GP_DISCRET-GA1-TPADA':;

SECTION_NUMBER 1
 '@BASEBOARD_FAB2_LIB.BASEBOARD_FAB2(SCH_1):PAGE271_I60@W_HDL.TPAD-SE-2P-GP(CHIPS)':
 C_PATH='@baseboard_fab2_lib.baseboard_fab2(sch_1):page271_i60@w_hdl.\tpad-se-2p~
-gp\(chips)',
 P_PATH='@baseboard_fab2_lib.baseboard_fab2(sch_1):page256_i60@w_hdl.\tpad-se-2p~
-gp\(chips)',
 PATH='I60',
 DRAWING='@BASEBOARD_FAB2_LIB.BASEBOARD_FAB2(SCH_1):PAGE271',
 PHYS_PAGE='256',
 XY='(-6525,3475)',
 ROT='2',
 VER='1',
 VALUE='TPAD-SE-2P-GP',
 PACK_TYPE='DISCRET-GA1',
 PART_NUMBER='ZZ.00PAD.NU1',
 LOCATION='T1P28',
 CDS_LIB='w_hdl',
 CDS_PART_NAME='TPAD-SE-2P-GP_DISCRET-GA1-TPADA',
 PRIM_FILE='C:/<user>/w_hdl/tpad#2dse#2d2p#2dgp/chips/chips.prt';

PART_NAME
 T1P29 'TPAD-SE-2P-GP_DISCRET-GA1-TPADA':;

SECTION_NUMBER 1
 '@BASEBOARD_FAB2_LIB.BASEBOARD_FAB2(SCH_1):PAGE271_I56@W_HDL.TPAD-SE-2P-GP(CHIPS)':
 C_PATH='@baseboard_fab2_lib.baseboard_fab2(sch_1):page271_i56@w_hdl.\tpad-se-2p~
-gp\(chips)',
 P_PATH='@baseboard_fab2_lib.baseboard_fab2(sch_1):page256_i56@w_hdl.\tpad-se-2p~
-gp\(chips)',
 PATH='I56',
 DRAWING='@BASEBOARD_FAB2_LIB.BASEBOARD_FAB2(SCH_1):PAGE271',
 PHYS_PAGE='256',
 XY='(-6525,3075)',
 ROT='2',
 VER='1',
 VALUE='TPAD-SE-2P-GP',
 PACK_TYPE='DISCRET-GA1',
 PART_NUMBER='ZZ.00PAD.NU1',
 LOCATION='T1P29',
 CDS_LIB='w_hdl',
 CDS_PART_NAME='TPAD-SE-2P-GP_DISCRET-GA1-TPADA',
 PRIM_FILE='C:/<user>/w_hdl/tpad#2dse#2d2p#2dgp/chips/chips.prt';

PART_NAME
 T1P30 'TPAD-SE-2P-GP_DISCRET-GA1-TPADA':;

SECTION_NUMBER 1
 '@BASEBOARD_FAB2_LIB.BASEBOARD_FAB2(SCH_1):PAGE271_I61@W_HDL.TPAD-SE-2P-GP(CHIPS)':
 C_PATH='@baseboard_fab2_lib.baseboard_fab2(sch_1):page271_i61@w_hdl.\tpad-se-2p~
-gp\(chips)',
 P_PATH='@baseboard_fab2_lib.baseboard_fab2(sch_1):page256_i61@w_hdl.\tpad-se-2p~
-gp\(chips)',
 PATH='I61',
 DRAWING='@BASEBOARD_FAB2_LIB.BASEBOARD_FAB2(SCH_1):PAGE271',
 PHYS_PAGE='256',
 XY='(-6525,2600)',
 ROT='2',
 VER='1',
 VALUE='TPAD-SE-2P-GP',
 PACK_TYPE='DISCRET-GA1',
 PART_NUMBER='ZZ.00PAD.NU1',
 LOCATION='T1P30',
 CDS_LIB='w_hdl',
 CDS_PART_NAME='TPAD-SE-2P-GP_DISCRET-GA1-TPADA',
 PRIM_FILE='C:/<user>/w_hdl/tpad#2dse#2d2p#2dgp/chips/chips.prt';

PART_NAME
 T1P31 'TPAD-SE-2P-GP_DISCRET-GA1-TPADA':;

SECTION_NUMBER 1
 '@BASEBOARD_FAB2_LIB.BASEBOARD_FAB2(SCH_1):PAGE271_I71@W_HDL.TPAD-SE-2P-GP(CHIPS)':
 C_PATH='@baseboard_fab2_lib.baseboard_fab2(sch_1):page271_i71@w_hdl.\tpad-se-2p~
-gp\(chips)',
 P_PATH='@baseboard_fab2_lib.baseboard_fab2(sch_1):page256_i71@w_hdl.\tpad-se-2p~
-gp\(chips)',
 PATH='I71',
 DRAWING='@BASEBOARD_FAB2_LIB.BASEBOARD_FAB2(SCH_1):PAGE271',
 PHYS_PAGE='256',
 XY='(-4525,3475)',
 ROT='2',
 VER='1',
 VALUE='TPAD-SE-2P-GP',
 PACK_TYPE='DISCRET-GA1',
 PART_NUMBER='ZZ.00PAD.NU1',
 LOCATION='T1P31',
 CDS_LIB='w_hdl',
 CDS_PART_NAME='TPAD-SE-2P-GP_DISCRET-GA1-TPADA',
 PRIM_FILE='C:/<user>/w_hdl/tpad#2dse#2d2p#2dgp/chips/chips.prt';

PART_NAME
 T1P32 'TPAD-SE-2P-GP_DISCRET-GA1-TPADA':;

SECTION_NUMBER 1
 '@BASEBOARD_FAB2_LIB.BASEBOARD_FAB2(SCH_1):PAGE271_I72@W_HDL.TPAD-SE-2P-GP(CHIPS)':
 C_PATH='@baseboard_fab2_lib.baseboard_fab2(sch_1):page271_i72@w_hdl.\tpad-se-2p~
-gp\(chips)',
 P_PATH='@baseboard_fab2_lib.baseboard_fab2(sch_1):page256_i72@w_hdl.\tpad-se-2p~
-gp\(chips)',
 PATH='I72',
 DRAWING='@BASEBOARD_FAB2_LIB.BASEBOARD_FAB2(SCH_1):PAGE271',
 PHYS_PAGE='256',
 XY='(-4525,3075)',
 ROT='2',
 VER='1',
 VALUE='TPAD-SE-2P-GP',
 PACK_TYPE='DISCRET-GA1',
 PART_NUMBER='ZZ.00PAD.NU1',
 LOCATION='T1P32',
 CDS_LIB='w_hdl',
 CDS_PART_NAME='TPAD-SE-2P-GP_DISCRET-GA1-TPADA',
 PRIM_FILE='C:/<user>/w_hdl/tpad#2dse#2d2p#2dgp/chips/chips.prt';

PART_NAME
 T1P33 'TPAD-SE-2P-GP_DISCRET-GA1-TPADA':;

SECTION_NUMBER 1
 '@BASEBOARD_FAB2_LIB.BASEBOARD_FAB2(SCH_1):PAGE271_I73@W_HDL.TPAD-SE-2P-GP(CHIPS)':
 C_PATH='@baseboard_fab2_lib.baseboard_fab2(sch_1):page271_i73@w_hdl.\tpad-se-2p~
-gp\(chips)',
 P_PATH='@baseboard_fab2_lib.baseboard_fab2(sch_1):page256_i73@w_hdl.\tpad-se-2p~
-gp\(chips)',
 PATH='I73',
 DRAWING='@BASEBOARD_FAB2_LIB.BASEBOARD_FAB2(SCH_1):PAGE271',
 PHYS_PAGE='256',
 XY='(-4525,2600)',
 ROT='2',
 VER='1',
 VALUE='TPAD-SE-2P-GP',
 PACK_TYPE='DISCRET-GA1',
 PART_NUMBER='ZZ.00PAD.NU1',
 LOCATION='T1P33',
 CDS_LIB='w_hdl',
 CDS_PART_NAME='TPAD-SE-2P-GP_DISCRET-GA1-TPADA',
 PRIM_FILE='C:/<user>/w_hdl/tpad#2dse#2d2p#2dgp/chips/chips.prt';

PART_NAME
 T1P34 'TPAD-SE-2P-GP_DISCRET-GA1-TPADA':;

SECTION_NUMBER 1
 '@BASEBOARD_FAB2_LIB.BASEBOARD_FAB2(SCH_1):PAGE271_I62@W_HDL.TPAD-SE-2P-GP(CHIPS)':
 C_PATH='@baseboard_fab2_lib.baseboard_fab2(sch_1):page271_i62@w_hdl.\tpad-se-2p~
-gp\(chips)',
 P_PATH='@baseboard_fab2_lib.baseboard_fab2(sch_1):page256_i62@w_hdl.\tpad-se-2p~
-gp\(chips)',
 PATH='I62',
 DRAWING='@BASEBOARD_FAB2_LIB.BASEBOARD_FAB2(SCH_1):PAGE271',
 PHYS_PAGE='256',
 XY='(-2750,3450)',
 ROT='2',
 VER='1',
 VALUE='TPAD-SE-2P-GP',
 PACK_TYPE='DISCRET-GA1',
 PART_NUMBER='ZZ.00PAD.NU1',
 LOCATION='T1P34',
 CDS_LIB='w_hdl',
 CDS_PART_NAME='TPAD-SE-2P-GP_DISCRET-GA1-TPADA',
 PRIM_FILE='C:/<user>/w_hdl/tpad#2dse#2d2p#2dgp/chips/chips.prt';

PART_NAME
 T1P35 'TPAD-SE-2P-GP_DISCRET-GA1-TPADA':;

SECTION_NUMBER 1
 '@BASEBOARD_FAB2_LIB.BASEBOARD_FAB2(SCH_1):PAGE271_I67@W_HDL.TPAD-SE-2P-GP(CHIPS)':
 C_PATH='@baseboard_fab2_lib.baseboard_fab2(sch_1):page271_i67@w_hdl.\tpad-se-2p~
-gp\(chips)',
 P_PATH='@baseboard_fab2_lib.baseboard_fab2(sch_1):page256_i67@w_hdl.\tpad-se-2p~
-gp\(chips)',
 PATH='I67',
 DRAWING='@BASEBOARD_FAB2_LIB.BASEBOARD_FAB2(SCH_1):PAGE271',
 PHYS_PAGE='256',
 XY='(-2750,3050)',
 ROT='2',
 VER='1',
 VALUE='TPAD-SE-2P-GP',
 PACK_TYPE='DISCRET-GA1',
 PART_NUMBER='ZZ.00PAD.NU1',
 LOCATION='T1P35',
 CDS_LIB='w_hdl',
 CDS_PART_NAME='TPAD-SE-2P-GP_DISCRET-GA1-TPADA',
 PRIM_FILE='C:/<user>/w_hdl/tpad#2dse#2d2p#2dgp/chips/chips.prt';

PART_NAME
 T1P36 'TPAD-SE-2P-GP_DISCRET-GA1-TPADA':;

SECTION_NUMBER 1
 '@BASEBOARD_FAB2_LIB.BASEBOARD_FAB2(SCH_1):PAGE271_I63@W_HDL.TPAD-SE-2P-GP(CHIPS)':
 C_PATH='@baseboard_fab2_lib.baseboard_fab2(sch_1):page271_i63@w_hdl.\tpad-se-2p~
-gp\(chips)',
 P_PATH='@baseboard_fab2_lib.baseboard_fab2(sch_1):page256_i63@w_hdl.\tpad-se-2p~
-gp\(chips)',
 PATH='I63',
 DRAWING='@BASEBOARD_FAB2_LIB.BASEBOARD_FAB2(SCH_1):PAGE271',
 PHYS_PAGE='256',
 XY='(-2750,2575)',
 ROT='2',
 VER='1',
 VALUE='TPAD-SE-2P-GP',
 PACK_TYPE='DISCRET-GA1',
 PART_NUMBER='ZZ.00PAD.NU1',
 LOCATION='T1P36',
 CDS_LIB='w_hdl',
 CDS_PART_NAME='TPAD-SE-2P-GP_DISCRET-GA1-TPADA',
 PRIM_FILE='C:/<user>/w_hdl/tpad#2dse#2d2p#2dgp/chips/chips.prt';

PART_NAME
 TH1A1 'MTG_KEYHOLE_TH-EMPTY,NA':
 ROOM='MOUNTING_HOLES';

SECTION_NUMBER 1
 '@BASEBOARD_FAB2_LIB.BASEBOARD_FAB2(SCH_1):PAGE195_I56@MSTR_MISC.MTG_KEYHOLE(CHIPS)':
 C_PATH='@baseboard_fab2_lib.baseboard_fab2(sch_1):page195_i56@mstr_misc.mtg_key~
hole(chips)',
 P_PATH='@baseboard_fab2_lib.baseboard_fab2(sch_1):page195_i56@mstr_misc.mtg_key~
hole(chips)',
 PATH='I56',
 DRAWING='@BASEBOARD_FAB2_LIB.BASEBOARD_FAB2(SCH_1):PAGE195',
 MATERIAL='EMPTY',
 BOM_COST='TEST_MFG',
 PHYS_PAGE='195',
 XY='(-5525,4725)',
 ROT='0',
 VER='1',
 PACK_TYPE='TH',
 PART_NUMBER='NA',
 LOCATION='TH1A1',
 ROOM='MOUNTING_HOLES',
 CDS_LIB='mstr_misc',
 CDS_PART_NAME='MTG_KEYHOLE_TH-EMPTY,NA',
 PRIM_FILE='./archive_libs/mstr_misc/mtg_keyhole/chips/chips.prt';

PART_NAME
 TH4A1 'MTG_KEYHOLE_TH-EMPTY,NA':
 ROOM='MOUNTING_HOLES';

SECTION_NUMBER 1
 '@BASEBOARD_FAB2_LIB.BASEBOARD_FAB2(SCH_1):PAGE195_I62@MSTR_MISC.MTG_KEYHOLE(CHIPS)':
 C_PATH='@baseboard_fab2_lib.baseboard_fab2(sch_1):page195_i62@mstr_misc.mtg_key~
hole(chips)',
 P_PATH='@baseboard_fab2_lib.baseboard_fab2(sch_1):page195_i62@mstr_misc.mtg_key~
hole(chips)',
 PATH='I62',
 DRAWING='@BASEBOARD_FAB2_LIB.BASEBOARD_FAB2(SCH_1):PAGE195',
 MATERIAL='EMPTY',
 BOM_COST='TEST_MFG',
 PHYS_PAGE='195',
 XY='(-7350,4125)',
 ROT='0',
 VER='1',
 PACK_TYPE='TH',
 PART_NUMBER='NA',
 LOCATION='TH4A1',
 ROOM='MOUNTING_HOLES',
 CDS_LIB='mstr_misc',
 CDS_PART_NAME='MTG_KEYHOLE_TH-EMPTY,NA',
 PRIM_FILE='./archive_libs/mstr_misc/mtg_keyhole/chips/chips.prt';

PART_NAME
 TH4G1 'MTG_KEYHOLE_TH-EMPTY,NA':
 ROOM='MOUNTING_HOLES';

SECTION_NUMBER 1
 '@BASEBOARD_FAB2_LIB.BASEBOARD_FAB2(SCH_1):PAGE195_I49@MSTR_MISC.MTG_KEYHOLE(CHIPS)':
 C_PATH='@baseboard_fab2_lib.baseboard_fab2(sch_1):page195_i49@mstr_misc.mtg_key~
hole(chips)',
 P_PATH='@baseboard_fab2_lib.baseboard_fab2(sch_1):page195_i49@mstr_misc.mtg_key~
hole(chips)',
 PATH='I49',
 DRAWING='@BASEBOARD_FAB2_LIB.BASEBOARD_FAB2(SCH_1):PAGE195',
 MATERIAL='EMPTY',
 BOM_COST='TEST_MFG',
 PHYS_PAGE='195',
 XY='(-6475,4725)',
 ROT='0',
 VER='1',
 PACK_TYPE='TH',
 PART_NUMBER='NA',
 LOCATION='TH4G1',
 ROOM='MOUNTING_HOLES',
 CDS_LIB='mstr_misc',
 CDS_PART_NAME='MTG_KEYHOLE_TH-EMPTY,NA',
 PRIM_FILE='./archive_libs/mstr_misc/mtg_keyhole/chips/chips.prt';

PART_NAME
 TH7A1 'MTG_KEYHOLE_TH-EMPTY,NA':
 ROOM='MOUNTING_HOLES';

SECTION_NUMBER 1
 '@BASEBOARD_FAB2_LIB.BASEBOARD_FAB2(SCH_1):PAGE195_I65@MSTR_MISC.MTG_KEYHOLE(CHIPS)':
 C_PATH='@baseboard_fab2_lib.baseboard_fab2(sch_1):page195_i65@mstr_misc.mtg_key~
hole(chips)',
 P_PATH='@baseboard_fab2_lib.baseboard_fab2(sch_1):page195_i65@mstr_misc.mtg_key~
hole(chips)',
 PATH='I65',
 DRAWING='@BASEBOARD_FAB2_LIB.BASEBOARD_FAB2(SCH_1):PAGE195',
 MATERIAL='EMPTY',
 BOM_COST='TEST_MFG',
 PHYS_PAGE='195',
 XY='(-5525,4150)',
 ROT='0',
 VER='1',
 PACK_TYPE='TH',
 PART_NUMBER='NA',
 LOCATION='TH7A1',
 ROOM='MOUNTING_HOLES',
 CDS_LIB='mstr_misc',
 CDS_PART_NAME='MTG_KEYHOLE_TH-EMPTY,NA',
 PRIM_FILE='./archive_libs/mstr_misc/mtg_keyhole/chips/chips.prt';

PART_NAME
 TH7G1 'MTG_KEYHOLE_TH-EMPTY,NA':
 ROOM='MOUNTING_HOLES';

SECTION_NUMBER 1
 '@BASEBOARD_FAB2_LIB.BASEBOARD_FAB2(SCH_1):PAGE195_I67@MSTR_MISC.MTG_KEYHOLE(CHIPS)':
 C_PATH='@baseboard_fab2_lib.baseboard_fab2(sch_1):page195_i67@mstr_misc.mtg_key~
hole(chips)',
 P_PATH='@baseboard_fab2_lib.baseboard_fab2(sch_1):page195_i67@mstr_misc.mtg_key~
hole(chips)',
 PATH='I67',
 DRAWING='@BASEBOARD_FAB2_LIB.BASEBOARD_FAB2(SCH_1):PAGE195',
 MATERIAL='EMPTY',
 BOM_COST='TEST_MFG',
 PHYS_PAGE='195',
 XY='(-4600,4150)',
 ROT='0',
 VER='1',
 PACK_TYPE='TH',
 PART_NUMBER='NA',
 LOCATION='TH7G1',
 ROOM='MOUNTING_HOLES',
 CDS_LIB='mstr_misc',
 CDS_PART_NAME='MTG_KEYHOLE_TH-EMPTY,NA',
 PRIM_FILE='./archive_libs/mstr_misc/mtg_keyhole/chips/chips.prt';

PART_NAME
 TH9A1 'MTG_KEYHOLE_TH-EMPTY,NA':
 ROOM='MOUNTING_HOLES';

SECTION_NUMBER 1
 '@BASEBOARD_FAB2_LIB.BASEBOARD_FAB2(SCH_1):PAGE195_I54@MSTR_MISC.MTG_KEYHOLE(CHIPS)':
 C_PATH='@baseboard_fab2_lib.baseboard_fab2(sch_1):page195_i54@mstr_misc.mtg_key~
hole(chips)',
 P_PATH='@baseboard_fab2_lib.baseboard_fab2(sch_1):page195_i54@mstr_misc.mtg_key~
hole(chips)',
 PATH='I54',
 DRAWING='@BASEBOARD_FAB2_LIB.BASEBOARD_FAB2(SCH_1):PAGE195',
 MATERIAL='EMPTY',
 BOM_COST='TEST_MFG',
 PHYS_PAGE='195',
 XY='(-4600,4725)',
 ROT='0',
 VER='1',
 PACK_TYPE='TH',
 PART_NUMBER='NA',
 LOCATION='TH9A1',
 ROOM='MOUNTING_HOLES',
 CDS_LIB='mstr_misc',
 CDS_PART_NAME='MTG_KEYHOLE_TH-EMPTY,NA',
 PRIM_FILE='./archive_libs/mstr_misc/mtg_keyhole/chips/chips.prt';

PART_NAME
 TH9G1 'MTG_KEYHOLE_TH-EMPTY,NA':
 ROOM='MOUNTING_HOLES';

SECTION_NUMBER 1
 '@BASEBOARD_FAB2_LIB.BASEBOARD_FAB2(SCH_1):PAGE195_I52@MSTR_MISC.MTG_KEYHOLE(CHIPS)':
 C_PATH='@baseboard_fab2_lib.baseboard_fab2(sch_1):page195_i52@mstr_misc.mtg_key~
hole(chips)',
 P_PATH='@baseboard_fab2_lib.baseboard_fab2(sch_1):page195_i52@mstr_misc.mtg_key~
hole(chips)',
 PATH='I52',
 DRAWING='@BASEBOARD_FAB2_LIB.BASEBOARD_FAB2(SCH_1):PAGE195',
 MATERIAL='EMPTY',
 BOM_COST='TEST_MFG',
 PHYS_PAGE='195',
 XY='(-6425,4125)',
 ROT='0',
 VER='1',
 PACK_TYPE='TH',
 PART_NUMBER='NA',
 LOCATION='TH9G1',
 ROOM='MOUNTING_HOLES',
 CDS_LIB='mstr_misc',
 CDS_PART_NAME='MTG_KEYHOLE_TH-EMPTY,NA',
 PRIM_FILE='./archive_libs/mstr_misc/mtg_keyhole/chips/chips.prt';

PART_NAME
 U1B2 'TCA9517DGKR-GP_DISCRET-G8-TCA9A':;

SECTION_NUMBER 1
 '@BASEBOARD_FAB2_LIB.BASEBOARD_FAB2(SCH_1):PAGE163_I28@W_HDL.TCA9517DGKR-GP(CHIPS)':
 C_PATH='@baseboard_fab2_lib.baseboard_fab2(sch_1):page163_i28@w_hdl.\tca9517dgk~
r-gp\(chips)',
 P_PATH='@baseboard_fab2_lib.baseboard_fab2(sch_1):page163_i28@w_hdl.\tca9517dgk~
r-gp\(chips)',
 PATH='I28',
 DRAWING='@BASEBOARD_FAB2_LIB.BASEBOARD_FAB2(SCH_1):PAGE163',
 SEC_TYPE='DISCRET-G8',
 PHYS_PAGE='163',
 XY='(-1475,3275)',
 ROT='0',
 VER='1',
 VALUE='TCA9517DGKR-GP',
 PACK_TYPE='DISCRET-G8',
 PART_NUMBER='071.09517.0009',
 LOCATION='U1B2',
 SEC='1',
 CDS_LIB='w_hdl',
 CDS_PART_NAME='TCA9517DGKR-GP_DISCRET-G8-TCA9A',
 PRIM_FILE='C:/<user>/w_hdl/tca9517dgkr#2dgp/chips/chips.prt';

PART_NAME
 U1D1 'TTL1G126_A_SOT-74HC1G126,IC,A7B':
 ROOM='HOT_SWAP';

SECTION_NUMBER 1
 '@BASEBOARD_FAB2_LIB.BASEBOARD_FAB2(SCH_1):PAGE200_I103@MSTR_TTL.TTL1G126_A(CHIPS)':
 C_PATH='@baseboard_fab2_lib.baseboard_fab2(sch_1):page200_i103@mstr_ttl.ttl1g12~
6_a(chips)',
 P_PATH='@baseboard_fab2_lib.baseboard_fab2(sch_1):page200_i103@mstr_ttl.ttl1g12~
6_a(chips)',
 PATH='I103',
 DRAWING='@BASEBOARD_FAB2_LIB.BASEBOARD_FAB2(SCH_1):PAGE200',
 POWER_GROUP='GND=GND;VCC=P3V3_STBY',
 SEC_TYPE='SOT',
 MATERIAL='IC',
 PHYS_PAGE='200',
 XY='(-2900,2225)',
 ROT='0',
 VER='1',
 VALUE='74HC1G126',
 PACK_TYPE='SOT',
 PART_NUMBER='A79322-001',
 LOCATION='U1D1',
 ROOM='HOT_SWAP',
 SEC='1',
 CDS_LIB='mstr_ttl',
 CDS_PART_NAME='TTL1G126_A_SOT-74HC1G126,IC,A7B',
 PRIM_FILE='./archive_libs/mstr_ttl/ttl1g126_a/chips/chips.prt';

PART_NAME
 U1D2 'TPS3700_SM-IC,H69492-001':;

SECTION_NUMBER 1
 '@BASEBOARD_FAB2_LIB.BASEBOARD_FAB2(SCH_1):PAGE200_I170@MSTR_VREG.TPS3700(CHIPS)':
 C_PATH='@baseboard_fab2_lib.baseboard_fab2(sch_1):page200_i170@mstr_vreg.tps370~
0(chips)',
 P_PATH='@baseboard_fab2_lib.baseboard_fab2(sch_1):page200_i170@mstr_vreg.tps370~
0(chips)',
 PATH='I170',
 DRAWING='@BASEBOARD_FAB2_LIB.BASEBOARD_FAB2(SCH_1):PAGE200',
 SEC_TYPE='SM',
 MATERIAL='IC',
 PHYS_PAGE='200',
 XY='(-3100,3125)',
 ROT='0',
 VER='1',
 PACK_TYPE='SM',
 PART_NUMBER='H69492-001',
 LOCATION='U1D2',
 SEC='1',
 CDS_LIB='mstr_vreg',
 CDS_PART_NAME='TPS3700_SM-IC,H69492-001',
 PRIM_FILE='./archive_libs/mstr_vreg/tps3700/chips/chips.prt';

PART_NAME
 U1E1 'TMP421_TSSOP-IC,G62962-001':
 ROOM='TEMP_SENSORS';

SECTION_NUMBER 1
 '@BASEBOARD_FAB2_LIB.BASEBOARD_FAB2(SCH_1):PAGE167_I30@MSTR_ANALOG.TMP421(CHIPS)':
 C_PATH='@baseboard_fab2_lib.baseboard_fab2(sch_1):page167_i30@mstr_analog.tmp42~
1(chips)',
 P_PATH='@baseboard_fab2_lib.baseboard_fab2(sch_1):page167_i30@mstr_analog.tmp42~
1(chips)',
 PATH='I30',
 DRAWING='@BASEBOARD_FAB2_LIB.BASEBOARD_FAB2(SCH_1):PAGE167',
 SEC_TYPE='TSSOP',
 MATERIAL='IC',
 BOM_COST='SM_THERM',
 PHYS_PAGE='167',
 XY='(-3825,3000)',
 ROT='0',
 VER='1',
 PACK_TYPE='TSSOP',
 PART_NUMBER='G62962-001',
 LOCATION='U1E1',
 ROOM='TEMP_SENSORS',
 SEC='1',
 CDS_LIB='mstr_analog',
 CDS_PART_NAME='TMP421_TSSOP-IC,G62962-001',
 PRIM_FILE='./archive_libs/mstr_analog/tmp421/chips/chips.prt';

PART_NAME
 U1E2 'TTL1G08_SOTLF-NC7SZ08,IC,D1032B':
 ROOM='CPU_FANS';

SECTION_NUMBER 1
 '@BASEBOARD_FAB2_LIB.BASEBOARD_FAB2(SCH_1):PAGE161_I121@MSTR_TTL.TTL1G08(CHIPS)':
 C_PATH='@baseboard_fab2_lib.baseboard_fab2(sch_1):page161_i121@mstr_ttl.ttl1g08~
(chips)',
 P_PATH='@baseboard_fab2_lib.baseboard_fab2(sch_1):page161_i121@mstr_ttl.ttl1g08~
(chips)',
 PATH='I121',
 DRAWING='@BASEBOARD_FAB2_LIB.BASEBOARD_FAB2(SCH_1):PAGE161',
 SIZE='1',
 POWER_GROUP='GND=GND;VCC=P3V3_STBY',
 SEC_TYPE='SOTLF',
 MATERIAL='IC',
 BOM_COST='SM_THERM',
 PHYS_PAGE='161',
 XY='(-6250,2575)',
 ROT='0',
 VER='1',
 VALUE='NC7SZ08',
 PACK_TYPE='SOTLF',
 PART_NUMBER='D10321-001',
 LOCATION='U1E2',
 ROOM='CPU_FANS',
 SEC='1',
 CDS_LIB='mstr_ttl',
 CDS_PART_NAME='TTL1G08_SOTLF-NC7SZ08,IC,D1032B',
 PRIM_FILE='./archive_libs/mstr_ttl/ttl1g08/chips/chips.prt';

PART_NAME
 U1L1 'TTL3126_QFNLF-74CBTLV3126,IC,DB':
 ROOM='DEBUG';

SECTION_NUMBER 1
 '@BASEBOARD_FAB2_LIB.BASEBOARD_FAB2(SCH_1):PAGE112_I108@MSTR_TTL.TTL3126(CHIPS)'(3):
 C_PATH='@baseboard_fab2_lib.baseboard_fab2(sch_1):page112_i108(3)@mstr_ttl.ttl3~
126(chips)',
 P_PATH='@baseboard_fab2_lib.baseboard_fab2(sch_1):page112_i108(3)@mstr_ttl.ttl3~
126(chips)',
 PATH='I108',
 DRAWING='@BASEBOARD_FAB2_LIB.BASEBOARD_FAB2(SCH_1):PAGE112',
 SIZE='4',
 POWER_GROUP='GND=GND;VCC=P3V3_STBY',
 MATERIAL='IC',
 PHYS_PAGE='112',
 XY='(-2200,2425)',
 ROT='0',
 VER='3',
 VALUE='74CBTLV3126',
 PACK_TYPE='QFNLF',
 PART_NUMBER='D18317-001',
 LOCATION='U1L1',
 HAS_FIXED_SIZE='4',
 ROOM='DEBUG',
 CDS_LIB='mstr_ttl',
 CDS_PART_NAME='TTL3126_QFNLF-74CBTLV3126,IC,DB',
 PRIM_FILE='./archive_libs/mstr_ttl/ttl3126/chips/chips.prt';

SECTION_NUMBER 2
 '@BASEBOARD_FAB2_LIB.BASEBOARD_FAB2(SCH_1):PAGE112_I108@MSTR_TTL.TTL3126(CHIPS)'(2):
 C_PATH='@baseboard_fab2_lib.baseboard_fab2(sch_1):page112_i108(2)@mstr_ttl.ttl3~
126(chips)',
 P_PATH='@baseboard_fab2_lib.baseboard_fab2(sch_1):page112_i108(2)@mstr_ttl.ttl3~
126(chips)',
 PATH='I108',
 DRAWING='@BASEBOARD_FAB2_LIB.BASEBOARD_FAB2(SCH_1):PAGE112',
 SIZE='4',
 POWER_GROUP='GND=GND;VCC=P3V3_STBY',
 MATERIAL='IC',
 PHYS_PAGE='112',
 XY='(-2200,2425)',
 ROT='0',
 VER='3',
 VALUE='74CBTLV3126',
 PACK_TYPE='QFNLF',
 PART_NUMBER='D18317-001',
 LOCATION='U1L1',
 HAS_FIXED_SIZE='4',
 ROOM='DEBUG',
 CDS_LIB='mstr_ttl',
 CDS_PART_NAME='TTL3126_QFNLF-74CBTLV3126,IC,DB',
 PRIM_FILE='./archive_libs/mstr_ttl/ttl3126/chips/chips.prt';

SECTION_NUMBER 3
 '@BASEBOARD_FAB2_LIB.BASEBOARD_FAB2(SCH_1):PAGE112_I108@MSTR_TTL.TTL3126(CHIPS)'(1):
 C_PATH='@baseboard_fab2_lib.baseboard_fab2(sch_1):page112_i108(1)@mstr_ttl.ttl3~
126(chips)',
 P_PATH='@baseboard_fab2_lib.baseboard_fab2(sch_1):page112_i108(1)@mstr_ttl.ttl3~
126(chips)',
 PATH='I108',
 DRAWING='@BASEBOARD_FAB2_LIB.BASEBOARD_FAB2(SCH_1):PAGE112',
 SIZE='4',
 POWER_GROUP='GND=GND;VCC=P3V3_STBY',
 MATERIAL='IC',
 PHYS_PAGE='112',
 XY='(-2200,2425)',
 ROT='0',
 VER='3',
 VALUE='74CBTLV3126',
 PACK_TYPE='QFNLF',
 PART_NUMBER='D18317-001',
 LOCATION='U1L1',
 HAS_FIXED_SIZE='4',
 ROOM='DEBUG',
 CDS_LIB='mstr_ttl',
 CDS_PART_NAME='TTL3126_QFNLF-74CBTLV3126,IC,DB',
 PRIM_FILE='./archive_libs/mstr_ttl/ttl3126/chips/chips.prt';

SECTION_NUMBER 4
 '@BASEBOARD_FAB2_LIB.BASEBOARD_FAB2(SCH_1):PAGE112_I108@MSTR_TTL.TTL3126(CHIPS)'(0):
 C_PATH='@baseboard_fab2_lib.baseboard_fab2(sch_1):page112_i108(0)@mstr_ttl.ttl3~
126(chips)',
 P_PATH='@baseboard_fab2_lib.baseboard_fab2(sch_1):page112_i108(0)@mstr_ttl.ttl3~
126(chips)',
 PATH='I108',
 DRAWING='@BASEBOARD_FAB2_LIB.BASEBOARD_FAB2(SCH_1):PAGE112',
 SIZE='4',
 POWER_GROUP='GND=GND;VCC=P3V3_STBY',
 MATERIAL='IC',
 PHYS_PAGE='112',
 XY='(-2200,2425)',
 ROT='0',
 VER='3',
 VALUE='74CBTLV3126',
 PACK_TYPE='QFNLF',
 PART_NUMBER='D18317-001',
 LOCATION='U1L1',
 HAS_FIXED_SIZE='4',
 ROOM='DEBUG',
 CDS_LIB='mstr_ttl',
 CDS_PART_NAME='TTL3126_QFNLF-74CBTLV3126,IC,DB',
 PRIM_FILE='./archive_libs/mstr_ttl/ttl3126/chips/chips.prt';

PART_NAME
 U1L2 'TTL1G86_SOTLF-74AHCT1G86,IC,D3B':
 ROOM='MIO_CHASSIS';

SECTION_NUMBER 1
 '@BASEBOARD_FAB2_LIB.BASEBOARD_FAB2(SCH_1):PAGE175_I57@MSTR_TTL.TTL1G86(CHIPS)':
 C_PATH='@baseboard_fab2_lib.baseboard_fab2(sch_1):page175_i57@mstr_ttl.ttl1g86(~
chips)',
 P_PATH='@baseboard_fab2_lib.baseboard_fab2(sch_1):page175_i57@mstr_ttl.ttl1g86(~
chips)',
 PATH='I57',
 DRAWING='@BASEBOARD_FAB2_LIB.BASEBOARD_FAB2(SCH_1):PAGE175',
 POWER_GROUP='GND=GND;VCC=P5V_STBY',
 MATERIAL='IC',
 BOM_COST='MIO_CHASSIS',
 PHYS_PAGE='175',
 XY='(-2750,1025)',
 ROT='0',
 VER='1',
 VALUE='74AHCT1G86',
 PACK_TYPE='SOTLF',
 PART_NUMBER='D39848-001',
 LOCATION='U1L2',
 ROOM='MIO_CHASSIS',
 CDS_LIB='mstr_ttl',
 CDS_PART_NAME='TTL1G86_SOTLF-74AHCT1G86,IC,D3B',
 PRIM_FILE='./archive_libs/mstr_ttl/ttl1g86/chips/chips.prt';

PART_NAME
 U1L3 'ADM809_SMLF-IC,D23047-001-GND=A':
 ROOM='V_SUPER';

SECTION_NUMBER 1
 '@BASEBOARD_FAB2_LIB.BASEBOARD_FAB2(SCH_1):PAGE196_I80@MSTR_ANALOG.ADM809(CHIPS)':
 C_PATH='@baseboard_fab2_lib.baseboard_fab2(sch_1):page196_i80@mstr_analog.adm80~
9(chips)',
 P_PATH='@baseboard_fab2_lib.baseboard_fab2(sch_1):page196_i80@mstr_analog.adm80~
9(chips)',
 PATH='I80',
 DRAWING='@BASEBOARD_FAB2_LIB.BASEBOARD_FAB2(SCH_1):PAGE196',
 POWER_GROUP='GND=GND',
 MATERIAL='IC',
 PHYS_PAGE='196',
 XY='(200,1350)',
 ROT='0',
 VER='1',
 PACK_TYPE='SMLF',
 PART_NUMBER='D23047-001',
 LOCATION='U1L3',
 ROOM='V_SUPER',
 CDS_LIB='mstr_analog',
 CDS_PART_NAME='ADM809_SMLF-IC,D23047-001',
 PRIM_FILE='./archive_libs/mstr_analog/adm809/chips/chips.prt';

PART_NAME
 U1L4 'TTL1G07_A_SOP-74LVC1G07,IC,C88B':
 ROOM='M-SATA';

SECTION_NUMBER 1
 '@BASEBOARD_FAB2_LIB.BASEBOARD_FAB2(SCH_1):PAGE111_I85@MSTR_TTL.TTL1G07_A(CHIPS)':
 C_PATH='@baseboard_fab2_lib.baseboard_fab2(sch_1):page111_i85@mstr_ttl.ttl1g07_~
a(chips)',
 P_PATH='@baseboard_fab2_lib.baseboard_fab2(sch_1):page111_i85@mstr_ttl.ttl1g07_~
a(chips)',
 PATH='I85',
 DRAWING='@BASEBOARD_FAB2_LIB.BASEBOARD_FAB2(SCH_1):PAGE111',
 POWER_GROUP='GND=GND;VCC=P3V3_STBY',
 SEC_TYPE='SOP',
 MATERIAL='IC',
 BOM_COST='M-SATA',
 PHYS_PAGE='111',
 XY='(1775,2600)',
 ROT='0',
 VER='1',
 VALUE='74LVC1G07',
 PACK_TYPE='SOP',
 PART_NUMBER='C88419-001',
 LOCATION='U1L4',
 ROOM='M-SATA',
 SEC='1',
 CDS_LIB='mstr_ttl',
 CDS_PART_NAME='TTL1G07_A_SOP-74LVC1G07,IC,C88B',
 PRIM_FILE='./archive_libs/mstr_ttl/ttl1g07_a/chips/chips.prt';

PART_NAME
 U1L5 'TTL3126_QFNLF-74CBTLV3126,IC,DB':
 ROOM='DEBUG';

SECTION_NUMBER 1
 '@BASEBOARD_FAB2_LIB.BASEBOARD_FAB2(SCH_1):PAGE112_I109@MSTR_TTL.TTL3126(CHIPS)'(3):
 C_PATH='@baseboard_fab2_lib.baseboard_fab2(sch_1):page112_i109(3)@mstr_ttl.ttl3~
126(chips)',
 P_PATH='@baseboard_fab2_lib.baseboard_fab2(sch_1):page112_i109(3)@mstr_ttl.ttl3~
126(chips)',
 PATH='I109',
 DRAWING='@BASEBOARD_FAB2_LIB.BASEBOARD_FAB2(SCH_1):PAGE112',
 SIZE='4',
 POWER_GROUP='GND=GND;VCC=P3V3_STBY',
 MATERIAL='IC',
 PHYS_PAGE='112',
 XY='(-2200,1200)',
 ROT='0',
 VER='3',
 VALUE='74CBTLV3126',
 PACK_TYPE='QFNLF',
 PART_NUMBER='D18317-001',
 LOCATION='U1L5',
 HAS_FIXED_SIZE='4',
 ROOM='DEBUG',
 CDS_LIB='mstr_ttl',
 CDS_PART_NAME='TTL3126_QFNLF-74CBTLV3126,IC,DB',
 PRIM_FILE='./archive_libs/mstr_ttl/ttl3126/chips/chips.prt';

SECTION_NUMBER 2
 '@BASEBOARD_FAB2_LIB.BASEBOARD_FAB2(SCH_1):PAGE112_I109@MSTR_TTL.TTL3126(CHIPS)'(2):
 C_PATH='@baseboard_fab2_lib.baseboard_fab2(sch_1):page112_i109(2)@mstr_ttl.ttl3~
126(chips)',
 P_PATH='@baseboard_fab2_lib.baseboard_fab2(sch_1):page112_i109(2)@mstr_ttl.ttl3~
126(chips)',
 PATH='I109',
 DRAWING='@BASEBOARD_FAB2_LIB.BASEBOARD_FAB2(SCH_1):PAGE112',
 SIZE='4',
 POWER_GROUP='GND=GND;VCC=P3V3_STBY',
 MATERIAL='IC',
 PHYS_PAGE='112',
 XY='(-2200,1200)',
 ROT='0',
 VER='3',
 VALUE='74CBTLV3126',
 PACK_TYPE='QFNLF',
 PART_NUMBER='D18317-001',
 LOCATION='U1L5',
 HAS_FIXED_SIZE='4',
 ROOM='DEBUG',
 CDS_LIB='mstr_ttl',
 CDS_PART_NAME='TTL3126_QFNLF-74CBTLV3126,IC,DB',
 PRIM_FILE='./archive_libs/mstr_ttl/ttl3126/chips/chips.prt';

SECTION_NUMBER 3
 '@BASEBOARD_FAB2_LIB.BASEBOARD_FAB2(SCH_1):PAGE112_I109@MSTR_TTL.TTL3126(CHIPS)'(1):
 C_PATH='@baseboard_fab2_lib.baseboard_fab2(sch_1):page112_i109(1)@mstr_ttl.ttl3~
126(chips)',
 P_PATH='@baseboard_fab2_lib.baseboard_fab2(sch_1):page112_i109(1)@mstr_ttl.ttl3~
126(chips)',
 PATH='I109',
 DRAWING='@BASEBOARD_FAB2_LIB.BASEBOARD_FAB2(SCH_1):PAGE112',
 SIZE='4',
 POWER_GROUP='GND=GND;VCC=P3V3_STBY',
 MATERIAL='IC',
 PHYS_PAGE='112',
 XY='(-2200,1200)',
 ROT='0',
 VER='3',
 VALUE='74CBTLV3126',
 PACK_TYPE='QFNLF',
 PART_NUMBER='D18317-001',
 LOCATION='U1L5',
 HAS_FIXED_SIZE='4',
 ROOM='DEBUG',
 CDS_LIB='mstr_ttl',
 CDS_PART_NAME='TTL3126_QFNLF-74CBTLV3126,IC,DB',
 PRIM_FILE='./archive_libs/mstr_ttl/ttl3126/chips/chips.prt';

SECTION_NUMBER 4
 '@BASEBOARD_FAB2_LIB.BASEBOARD_FAB2(SCH_1):PAGE112_I109@MSTR_TTL.TTL3126(CHIPS)'(0):
 C_PATH='@baseboard_fab2_lib.baseboard_fab2(sch_1):page112_i109(0)@mstr_ttl.ttl3~
126(chips)',
 P_PATH='@baseboard_fab2_lib.baseboard_fab2(sch_1):page112_i109(0)@mstr_ttl.ttl3~
126(chips)',
 PATH='I109',
 DRAWING='@BASEBOARD_FAB2_LIB.BASEBOARD_FAB2(SCH_1):PAGE112',
 SIZE='4',
 POWER_GROUP='GND=GND;VCC=P3V3_STBY',
 MATERIAL='IC',
 PHYS_PAGE='112',
 XY='(-2200,1200)',
 ROT='0',
 VER='3',
 VALUE='74CBTLV3126',
 PACK_TYPE='QFNLF',
 PART_NUMBER='D18317-001',
 LOCATION='U1L5',
 HAS_FIXED_SIZE='4',
 ROOM='DEBUG',
 CDS_LIB='mstr_ttl',
 CDS_PART_NAME='TTL3126_QFNLF-74CBTLV3126,IC,DB',
 PRIM_FILE='./archive_libs/mstr_ttl/ttl3126/chips/chips.prt';

PART_NAME
 U1L10 'TTL3126_QFNLF-74CBTLV3126,IC,DB':
 ROOM='DEBUG';

SECTION_NUMBER 1
 '@BASEBOARD_FAB2_LIB.BASEBOARD_FAB2(SCH_1):PAGE189_I67@MSTR_TTL.TTL3126(CHIPS)'(3):
 C_PATH='@baseboard_fab2_lib.baseboard_fab2(sch_1):page189_i67(3)@mstr_ttl.ttl31~
26(chips)',
 P_PATH='@baseboard_fab2_lib.baseboard_fab2(sch_1):page189_i67(3)@mstr_ttl.ttl31~
26(chips)',
 PATH='I67',
 DRAWING='@BASEBOARD_FAB2_LIB.BASEBOARD_FAB2(SCH_1):PAGE189',
 SIZE='4',
 POWER_GROUP='GND=GND;VCC=P3V3_STBY',
 MATERIAL='IC',
 PHYS_PAGE='189',
 XY='(800,4300)',
 ROT='0',
 VER='3',
 VALUE='74CBTLV3126',
 PACK_TYPE='QFNLF',
 PART_NUMBER='D18317-001',
 LOCATION='U1L10',
 HAS_FIXED_SIZE='4',
 ROOM='DEBUG',
 CDS_LIB='mstr_ttl',
 CDS_PART_NAME='TTL3126_QFNLF-74CBTLV3126,IC,DB',
 PRIM_FILE='./archive_libs/mstr_ttl/ttl3126/chips/chips.prt';

SECTION_NUMBER 2
 '@BASEBOARD_FAB2_LIB.BASEBOARD_FAB2(SCH_1):PAGE189_I67@MSTR_TTL.TTL3126(CHIPS)'(2):
 C_PATH='@baseboard_fab2_lib.baseboard_fab2(sch_1):page189_i67(2)@mstr_ttl.ttl31~
26(chips)',
 P_PATH='@baseboard_fab2_lib.baseboard_fab2(sch_1):page189_i67(2)@mstr_ttl.ttl31~
26(chips)',
 PATH='I67',
 DRAWING='@BASEBOARD_FAB2_LIB.BASEBOARD_FAB2(SCH_1):PAGE189',
 SIZE='4',
 POWER_GROUP='GND=GND;VCC=P3V3_STBY',
 MATERIAL='IC',
 PHYS_PAGE='189',
 XY='(800,4300)',
 ROT='0',
 VER='3',
 VALUE='74CBTLV3126',
 PACK_TYPE='QFNLF',
 PART_NUMBER='D18317-001',
 LOCATION='U1L10',
 HAS_FIXED_SIZE='4',
 ROOM='DEBUG',
 CDS_LIB='mstr_ttl',
 CDS_PART_NAME='TTL3126_QFNLF-74CBTLV3126,IC,DB',
 PRIM_FILE='./archive_libs/mstr_ttl/ttl3126/chips/chips.prt';

SECTION_NUMBER 3
 '@BASEBOARD_FAB2_LIB.BASEBOARD_FAB2(SCH_1):PAGE189_I67@MSTR_TTL.TTL3126(CHIPS)'(1):
 C_PATH='@baseboard_fab2_lib.baseboard_fab2(sch_1):page189_i67(1)@mstr_ttl.ttl31~
26(chips)',
 P_PATH='@baseboard_fab2_lib.baseboard_fab2(sch_1):page189_i67(1)@mstr_ttl.ttl31~
26(chips)',
 PATH='I67',
 DRAWING='@BASEBOARD_FAB2_LIB.BASEBOARD_FAB2(SCH_1):PAGE189',
 SIZE='4',
 POWER_GROUP='GND=GND;VCC=P3V3_STBY',
 MATERIAL='IC',
 PHYS_PAGE='189',
 XY='(800,4300)',
 ROT='0',
 VER='3',
 VALUE='74CBTLV3126',
 PACK_TYPE='QFNLF',
 PART_NUMBER='D18317-001',
 LOCATION='U1L10',
 HAS_FIXED_SIZE='4',
 ROOM='DEBUG',
 CDS_LIB='mstr_ttl',
 CDS_PART_NAME='TTL3126_QFNLF-74CBTLV3126,IC,DB',
 PRIM_FILE='./archive_libs/mstr_ttl/ttl3126/chips/chips.prt';

SECTION_NUMBER 4
 '@BASEBOARD_FAB2_LIB.BASEBOARD_FAB2(SCH_1):PAGE189_I67@MSTR_TTL.TTL3126(CHIPS)'(0):
 C_PATH='@baseboard_fab2_lib.baseboard_fab2(sch_1):page189_i67(0)@mstr_ttl.ttl31~
26(chips)',
 P_PATH='@baseboard_fab2_lib.baseboard_fab2(sch_1):page189_i67(0)@mstr_ttl.ttl31~
26(chips)',
 PATH='I67',
 DRAWING='@BASEBOARD_FAB2_LIB.BASEBOARD_FAB2(SCH_1):PAGE189',
 SIZE='4',
 POWER_GROUP='GND=GND;VCC=P3V3_STBY',
 MATERIAL='IC',
 PHYS_PAGE='189',
 XY='(800,4300)',
 ROT='0',
 VER='3',
 VALUE='74CBTLV3126',
 PACK_TYPE='QFNLF',
 PART_NUMBER='D18317-001',
 LOCATION='U1L10',
 HAS_FIXED_SIZE='4',
 ROOM='DEBUG',
 CDS_LIB='mstr_ttl',
 CDS_PART_NAME='TTL3126_QFNLF-74CBTLV3126,IC,DB',
 PRIM_FILE='./archive_libs/mstr_ttl/ttl3126/chips/chips.prt';

PART_NAME
 U1M1 'TTL1G08_SOTLF-NC7SZ08,IC,D1032C':
 ROOM='MIO_CHASSIS';

SECTION_NUMBER 1
 '@BASEBOARD_FAB2_LIB.BASEBOARD_FAB2(SCH_1):PAGE177_I70@MSTR_TTL.TTL1G08(CHIPS)':
 C_PATH='@baseboard_fab2_lib.baseboard_fab2(sch_1):page177_i70@mstr_ttl.ttl1g08(~
chips)',
 P_PATH='@baseboard_fab2_lib.baseboard_fab2(sch_1):page177_i70@mstr_ttl.ttl1g08(~
chips)',
 PATH='I70',
 DRAWING='@BASEBOARD_FAB2_LIB.BASEBOARD_FAB2(SCH_1):PAGE177',
 SIZE='1',
 POWER_GROUP='GND=GND;VCC=P3V3',
 SEC_TYPE='SOTLF',
 MATERIAL='IC',
 BOM_COST='MIO_CHASSIS',
 PHYS_PAGE='177',
 XY='(-6550,6275)',
 ROT='0',
 VER='1',
 VALUE='NC7SZ08',
 PACK_TYPE='SOTLF',
 PART_NUMBER='D10321-001',
 LOCATION='U1M1',
 ROOM='MIO_CHASSIS',
 SEC='1',
 CDS_LIB='mstr_ttl',
 CDS_PART_NAME='TTL1G08_SOTLF-NC7SZ08,IC,D1032C',
 PRIM_FILE='./archive_libs/mstr_ttl/ttl1g08/chips/chips.prt';

PART_NAME
 U1M2 'NC7SB3157_SMLF-IC,C99406-001':
 GROUP='MCP',
 ROOM='DEBUG';

SECTION_NUMBER 1
 '@BASEBOARD_FAB2_LIB.BASEBOARD_FAB2(SCH_1):PAGE113_I107@MSTR_ANALOG.NC7SB3157(CHIPS)':
 C_PATH='@baseboard_fab2_lib.baseboard_fab2(sch_1):page113_i107@mstr_analog.nc7s~
b3157(chips)',
 P_PATH='@baseboard_fab2_lib.baseboard_fab2(sch_1):page113_i107@mstr_analog.nc7s~
b3157(chips)',
 PATH='I107',
 DRAWING='@BASEBOARD_FAB2_LIB.BASEBOARD_FAB2(SCH_1):PAGE113',
 SEC_TYPE='SMLF',
 MATERIAL='IC',
 BOM_COST='DEBUG',
 PHYS_PAGE='113',
 XY='(-2075,3525)',
 ROT='2',
 VER='1',
 PACK_TYPE='SMLF',
 PART_NUMBER='C99406-001',
 LOCATION='U1M2',
 ROOM='DEBUG',
 GROUP='MCP',
 SEC='1',
 CDS_LIB='mstr_analog',
 CDS_PART_NAME='NC7SB3157_SMLF-IC,C99406-001',
 PRIM_FILE='./archive_libs/mstr_analog/nc7sb3157/chips/chips.prt';

PART_NAME
 U1M3 'TPS2061_SM-IC,H66405-001':
 ROOM='USB_REAR';

SECTION_NUMBER 1
 '@BASEBOARD_FAB2_LIB.BASEBOARD_FAB2(SCH_1):PAGE176_I100@MSTR_VREG.TPS2061(CHIPS)':
 C_PATH='@baseboard_fab2_lib.baseboard_fab2(sch_1):page176_i100@mstr_vreg.tps206~
1(chips)',
 P_PATH='@baseboard_fab2_lib.baseboard_fab2(sch_1):page176_i100@mstr_vreg.tps206~
1(chips)',
 PATH='I100',
 DRAWING='@BASEBOARD_FAB2_LIB.BASEBOARD_FAB2(SCH_1):PAGE176',
 SEC_TYPE='SM',
 MATERIAL='IC',
 BOM_COST='MIO_USB',
 PHYS_PAGE='176',
 XY='(-4125,3325)',
 ROT='0',
 VER='1',
 PACK_TYPE='SM',
 PART_NUMBER='H66405-001',
 LOCATION='U1M3',
 ROOM='USB_REAR',
 SEC='1',
 CDS_LIB='mstr_vreg',
 CDS_PART_NAME='TPS2061_SM-IC,H66405-001',
 PRIM_FILE='./archive_libs/mstr_vreg/tps2061/chips/chips.prt';

PART_NAME
 U1M4 '74CBTLV1G125_SMLF-IC,C88177-00A':
 ROOM='DEBUG';

SECTION_NUMBER 1
 '@BASEBOARD_FAB2_LIB.BASEBOARD_FAB2(SCH_1):PAGE112_I127@MSTR_TTL.74CBTLV1G125(CHIPS)':
 C_PATH='@baseboard_fab2_lib.baseboard_fab2(sch_1):page112_i127@mstr_ttl.\74cbtl~
v1g125\(chips)',
 P_PATH='@baseboard_fab2_lib.baseboard_fab2(sch_1):page112_i127@mstr_ttl.\74cbtl~
v1g125\(chips)',
 PATH='I127',
 DRAWING='@BASEBOARD_FAB2_LIB.BASEBOARD_FAB2(SCH_1):PAGE112',
 POWER_GROUP='GND=GND;VCC=P3V3_STBY',
 SEC_TYPE='SMLF',
 MATERIAL='IC',
 BOM_COST='DEBUG',
 PHYS_PAGE='112',
 XY='(3075,3425)',
 ROT='0',
 VER='1',
 PACK_TYPE='SMLF',
 PART_NUMBER='C88177-001',
 LOCATION='U1M4',
 ROOM='DEBUG',
 SEC='1',
 CDS_LIB='mstr_ttl',
 CDS_PART_NAME='74CBTLV1G125_SMLF-IC,C88177-00A',
 PRIM_FILE='./archive_libs/mstr_ttl/74cbtlv1g125/chips/chips.prt';

PART_NAME
 U1M5 '74CBTLV1G125_SMLF-IC,C88177-00A':
 ROOM='DEBUG';

SECTION_NUMBER 1
 '@BASEBOARD_FAB2_LIB.BASEBOARD_FAB2(SCH_1):PAGE113_I196@MSTR_TTL.74CBTLV1G125(CHIPS)':
 C_PATH='@baseboard_fab2_lib.baseboard_fab2(sch_1):page113_i196@mstr_ttl.\74cbtl~
v1g125\(chips)',
 P_PATH='@baseboard_fab2_lib.baseboard_fab2(sch_1):page113_i196@mstr_ttl.\74cbtl~
v1g125\(chips)',
 PATH='I196',
 DRAWING='@BASEBOARD_FAB2_LIB.BASEBOARD_FAB2(SCH_1):PAGE113',
 POWER_GROUP='GND=GND;VCC=P3V3_STBY',
 POP='NOPOP',
 SEC_TYPE='SMLF',
 MATERIAL='IC',
 BOM_COST='DEBUG',
 PHYS_PAGE='113',
 XY='(1600,2825)',
 ROT='0',
 VER='1',
 PACK_TYPE='SMLF',
 PART_NUMBER='C88177-001',
 LOCATION='U1M5',
 ROOM='DEBUG',
 SEC='1',
 CDS_LIB='mstr_ttl',
 CDS_PART_NAME='74CBTLV1G125_SMLF-IC,C88177-00A',
 PRIM_FILE='./archive_libs/mstr_ttl/74cbtlv1g125/chips/chips.prt';

PART_NAME
 U1M6 '74CBTLV1G125_SMLF-IC,C88177-00A':
 GROUP='MCP',
 ROOM='DEBUG';

SECTION_NUMBER 1
 '@BASEBOARD_FAB2_LIB.BASEBOARD_FAB2(SCH_1):PAGE113_I127@MSTR_TTL.74CBTLV1G125(CHIPS)':
 C_PATH='@baseboard_fab2_lib.baseboard_fab2(sch_1):page113_i127@mstr_ttl.\74cbtl~
v1g125\(chips)',
 P_PATH='@baseboard_fab2_lib.baseboard_fab2(sch_1):page113_i127@mstr_ttl.\74cbtl~
v1g125\(chips)',
 PATH='I127',
 DRAWING='@BASEBOARD_FAB2_LIB.BASEBOARD_FAB2(SCH_1):PAGE113',
 POWER_GROUP='GND=GND;VCC=P3V3_STBY',
 SEC_TYPE='SMLF',
 MATERIAL='IC',
 BOM_COST='DEBUG',
 PHYS_PAGE='113',
 XY='(-1500,850)',
 ROT='0',
 VER='1',
 PACK_TYPE='SMLF',
 PART_NUMBER='C88177-001',
 LOCATION='U1M6',
 ROOM='DEBUG',
 GROUP='MCP',
 SEC='1',
 CDS_LIB='mstr_ttl',
 CDS_PART_NAME='74CBTLV1G125_SMLF-IC,C88177-00A',
 PRIM_FILE='./archive_libs/mstr_ttl/74cbtlv1g125/chips/chips.prt';

PART_NAME
 U1M7 'NC7SB3157_SMLF-IC,C99406-001':
 ROOM='DEBUG';

SECTION_NUMBER 1
 '@BASEBOARD_FAB2_LIB.BASEBOARD_FAB2(SCH_1):PAGE112_I40@MSTR_ANALOG.NC7SB3157(CHIPS)':
 C_PATH='@baseboard_fab2_lib.baseboard_fab2(sch_1):page112_i40@mstr_analog.nc7sb~
3157(chips)',
 P_PATH='@baseboard_fab2_lib.baseboard_fab2(sch_1):page112_i40@mstr_analog.nc7sb~
3157(chips)',
 PATH='I40',
 DRAWING='@BASEBOARD_FAB2_LIB.BASEBOARD_FAB2(SCH_1):PAGE112',
 MATERIAL='IC',
 BOM_COST='DEBUG',
 PHYS_PAGE='112',
 XY='(2600,4675)',
 ROT='2',
 VER='1',
 PACK_TYPE='SMLF',
 PART_NUMBER='C99406-001',
 LOCATION='U1M7',
 ROOM='DEBUG',
 CDS_LIB='mstr_analog',
 CDS_PART_NAME='NC7SB3157_SMLF-IC,C99406-001',
 PRIM_FILE='./archive_libs/mstr_analog/nc7sb3157/chips/chips.prt';

PART_NAME
 U1R1 'TTL1G07_A_SOP-74LVC1G07,IC,C88B':
 ROOM='FAST_PROCHOT';

SECTION_NUMBER 1
 '@BASEBOARD_FAB2_LIB.BASEBOARD_FAB2(SCH_1):PAGE170_I46@MSTR_TTL.TTL1G07_A(CHIPS)':
 C_PATH='@baseboard_fab2_lib.baseboard_fab2(sch_1):page170_i46@mstr_ttl.ttl1g07_~
a(chips)',
 P_PATH='@baseboard_fab2_lib.baseboard_fab2(sch_1):page170_i46@mstr_ttl.ttl1g07_~
a(chips)',
 PATH='I46',
 DRAWING='@BASEBOARD_FAB2_LIB.BASEBOARD_FAB2(SCH_1):PAGE170',
 POWER_GROUP='GND=GND;VCC=P3V3_STBY',
 SEC_TYPE='SOP',
 MATERIAL='IC',
 BOM_COST='FAST_PROCHOT',
 PHYS_PAGE='170',
 XY='(-1225,2525)',
 ROT='0',
 VER='1',
 VALUE='74LVC1G07',
 PACK_TYPE='SOP',
 PART_NUMBER='C88419-001',
 LOCATION='U1R1',
 ROOM='FAST_PROCHOT',
 SEC='1',
 CDS_LIB='mstr_ttl',
 CDS_PART_NAME='TTL1G07_A_SOP-74LVC1G07,IC,C88B',
 PRIM_FILE='./archive_libs/mstr_ttl/ttl1g07_a/chips/chips.prt';

PART_NAME
 U1R2 'TTL1G126_A_SOT-74HC1G126,IC,A7B':
 ROOM='FAST_PROCHOT';

SECTION_NUMBER 1
 '@BASEBOARD_FAB2_LIB.BASEBOARD_FAB2(SCH_1):PAGE170_I20@MSTR_TTL.TTL1G126_A(CHIPS)':
 C_PATH='@baseboard_fab2_lib.baseboard_fab2(sch_1):page170_i20@mstr_ttl.ttl1g126~
_a(chips)',
 P_PATH='@baseboard_fab2_lib.baseboard_fab2(sch_1):page170_i20@mstr_ttl.ttl1g126~
_a(chips)',
 PATH='I20',
 DRAWING='@BASEBOARD_FAB2_LIB.BASEBOARD_FAB2(SCH_1):PAGE170',
 POWER_GROUP='GND=GND;VCC=P3V3_STBY',
 SEC_TYPE='SOT',
 MATERIAL='IC',
 BOM_COST='FAST_PROCHOT',
 PHYS_PAGE='170',
 XY='(-2525,2525)',
 ROT='0',
 VER='1',
 VALUE='74HC1G126',
 PACK_TYPE='SOT',
 PART_NUMBER='A79322-001',
 LOCATION='U1R2',
 ROOM='FAST_PROCHOT',
 SEC='1',
 CDS_LIB='mstr_ttl',
 CDS_PART_NAME='TTL1G126_A_SOT-74HC1G126,IC,A7B',
 PRIM_FILE='./archive_libs/mstr_ttl/ttl1g126_a/chips/chips.prt';

PART_NAME
 U1W2 'TCA9517DGKR-GP_DISCRET-G8-TCA9A':;

SECTION_NUMBER 1
 '@BASEBOARD_FAB2_LIB.BASEBOARD_FAB2(SCH_1):PAGE248_I49@W_HDL.TCA9517DGKR-GP(CHIPS)':
 C_PATH='@baseboard_fab2_lib.baseboard_fab2(sch_1):page248_i49@w_hdl.\tca9517dgk~
r-gp\(chips)',
 P_PATH='@baseboard_fab2_lib.baseboard_fab2(sch_1):page248_i49@w_hdl.\tca9517dgk~
r-gp\(chips)',
 PATH='I49',
 DRAWING='@BASEBOARD_FAB2_LIB.BASEBOARD_FAB2(SCH_1):PAGE248',
 SEC_TYPE='DISCRET-G8',
 PHYS_PAGE='248',
 XY='(-3925,3500)',
 ROT='0',
 VER='1',
 VALUE='TCA9517DGKR-GP',
 PACK_TYPE='DISCRET-G8',
 PART_NUMBER='071.09517.0009',
 LOCATION='U1W2',
 SEC='1',
 CDS_LIB='w_hdl',
 CDS_PART_NAME='TCA9517DGKR-GP_DISCRET-G8-TCA9A',
 PRIM_FILE='C:/<user>/w_hdl/tca9517dgkr#2dgp/chips/chips.prt';

PART_NAME
 U1W3 'PCA9617_SSOP-IC,G81764-001-GNDA':
 ROOM='MEM';

SECTION_NUMBER 1
 '@BASEBOARD_FAB2_LIB.BASEBOARD_FAB2(SCH_1):PAGE176_I162@MSTR_DIGITAL.PCA9617(CHIPS)':
 C_PATH='@baseboard_fab2_lib.baseboard_fab2(sch_1):page176_i162@mstr_digital.pca~
9617(chips)',
 P_PATH='@baseboard_fab2_lib.baseboard_fab2(sch_1):page176_i162@mstr_digital.pca~
9617(chips)',
 PATH='I162',
 DRAWING='@BASEBOARD_FAB2_LIB.BASEBOARD_FAB2(SCH_1):PAGE176',
 POWER_GROUP='GND=GND',
 MATERIAL='IC',
 BOM_COST='SM_CONTROLLER',
 PHYS_PAGE='176',
 XY='(-4900,2000)',
 ROT='0',
 VER='1',
 PACK_TYPE='SSOP',
 PART_NUMBER='G81764-001',
 LOCATION='U1W3',
 ROOM='MEM',
 CDS_LIB='mstr_digital',
 CDS_PART_NAME='PCA9617_SSOP-IC,G81764-001',
 PRIM_FILE='./archive_libs/mstr_digital/pca9617/chips/chips.prt';

PART_NAME
 U2D1 'SKX_EXT_B_BGA1-IC,TBD':
 ROOM='CPU1';

SECTION_NUMBER 1
 '@BASEBOARD_FAB2_LIB.BASEBOARD_FAB2(SCH_1):PAGE55_I172@CHPSET_LIB.SKX_EXT_B(CHIPS)':
 C_PATH='@baseboard_fab2_lib.baseboard_fab2(sch_1):page55_i172@chpset_lib.skx_ex~
t_b(chips)',
 P_PATH='@baseboard_fab2_lib.baseboard_fab2(sch_1):page55_i172@chpset_lib.skx_ex~
t_b(chips)',
 PATH='I172',
 DRAWING='@BASEBOARD_FAB2_LIB.BASEBOARD_FAB2(SCH_1):PAGE55',
 SEC_TYPE='BGA1',
 MATERIAL='IC',
 PHYS_PAGE='55',
 XY='(10225,2500)',
 ROT='0',
 VER='1',
 PACK_TYPE='BGA1',
 PART_NUMBER='TBD',
 LOCATION='U2D1',
 ROOM='CPU1',
 SEC='1',
 CDS_LIB='chpset_lib',
 CDS_PART_NAME='SKX_EXT_B_BGA1-IC,TBD',
 PRIM_FILE='./archive_libs/logical/skx_ext_b/chips/chips.prt';

SECTION_NUMBER 2
 '@BASEBOARD_FAB2_LIB.BASEBOARD_FAB2(SCH_1):PAGE56_I169@CHPSET_LIB.SKX_EXT_B(CHIPS)':
 C_PATH='@baseboard_fab2_lib.baseboard_fab2(sch_1):page56_i169@chpset_lib.skx_ex~
t_b(chips)',
 P_PATH='@baseboard_fab2_lib.baseboard_fab2(sch_1):page56_i169@chpset_lib.skx_ex~
t_b(chips)',
 PATH='I169',
 DRAWING='@BASEBOARD_FAB2_LIB.BASEBOARD_FAB2(SCH_1):PAGE56',
 SEC_TYPE='BGA1',
 MATERIAL='IC',
 PHYS_PAGE='56',
 XY='(-4025,2550)',
 ROT='0',
 VER='2',
 PACK_TYPE='BGA1',
 PART_NUMBER='TBD',
 LOCATION='U2D1',
 SEC='2',
 CDS_LIB='chpset_lib',
 CDS_PART_NAME='SKX_EXT_B_BGA1-IC,TBD',
 PRIM_FILE='./archive_libs/logical/skx_ext_b/chips/chips.prt';

SECTION_NUMBER 3
 '@BASEBOARD_FAB2_LIB.BASEBOARD_FAB2(SCH_1):PAGE57_I172@CHPSET_LIB.SKX_EXT_B(CHIPS)':
 C_PATH='@baseboard_fab2_lib.baseboard_fab2(sch_1):page57_i172@chpset_lib.skx_ex~
t_b(chips)',
 P_PATH='@baseboard_fab2_lib.baseboard_fab2(sch_1):page57_i172@chpset_lib.skx_ex~
t_b(chips)',
 PATH='I172',
 DRAWING='@BASEBOARD_FAB2_LIB.BASEBOARD_FAB2(SCH_1):PAGE57',
 SEC_TYPE='BGA1',
 MATERIAL='IC',
 PHYS_PAGE='57',
 XY='(-4175,2575)',
 ROT='0',
 VER='3',
 PACK_TYPE='BGA1',
 PART_NUMBER='TBD',
 LOCATION='U2D1',
 SEC='3',
 CDS_LIB='chpset_lib',
 CDS_PART_NAME='SKX_EXT_B_BGA1-IC,TBD',
 PRIM_FILE='./archive_libs/logical/skx_ext_b/chips/chips.prt';

SECTION_NUMBER 4
 '@BASEBOARD_FAB2_LIB.BASEBOARD_FAB2(SCH_1):PAGE58_I172@CHPSET_LIB.SKX_EXT_B(CHIPS)':
 C_PATH='@baseboard_fab2_lib.baseboard_fab2(sch_1):page58_i172@chpset_lib.skx_ex~
t_b(chips)',
 P_PATH='@baseboard_fab2_lib.baseboard_fab2(sch_1):page58_i172@chpset_lib.skx_ex~
t_b(chips)',
 PATH='I172',
 DRAWING='@BASEBOARD_FAB2_LIB.BASEBOARD_FAB2(SCH_1):PAGE58',
 SEC_TYPE='BGA1',
 MATERIAL='IC',
 PHYS_PAGE='58',
 XY='(-4200,2575)',
 ROT='0',
 VER='4',
 PACK_TYPE='BGA1',
 PART_NUMBER='TBD',
 LOCATION='U2D1',
 SEC='4',
 CDS_LIB='chpset_lib',
 CDS_PART_NAME='SKX_EXT_B_BGA1-IC,TBD',
 PRIM_FILE='./archive_libs/logical/skx_ext_b/chips/chips.prt';

SECTION_NUMBER 5
 '@BASEBOARD_FAB2_LIB.BASEBOARD_FAB2(SCH_1):PAGE59_I172@CHPSET_LIB.SKX_EXT_B(CHIPS)':
 C_PATH='@baseboard_fab2_lib.baseboard_fab2(sch_1):page59_i172@chpset_lib.skx_ex~
t_b(chips)',
 P_PATH='@baseboard_fab2_lib.baseboard_fab2(sch_1):page59_i172@chpset_lib.skx_ex~
t_b(chips)',
 PATH='I172',
 DRAWING='@BASEBOARD_FAB2_LIB.BASEBOARD_FAB2(SCH_1):PAGE59',
 SEC_TYPE='BGA1',
 MATERIAL='IC',
 PHYS_PAGE='59',
 XY='(-4175,2550)',
 ROT='0',
 VER='5',
 PACK_TYPE='BGA1',
 PART_NUMBER='TBD',
 LOCATION='U2D1',
 SEC='5',
 CDS_LIB='chpset_lib',
 CDS_PART_NAME='SKX_EXT_B_BGA1-IC,TBD',
 PRIM_FILE='./archive_libs/logical/skx_ext_b/chips/chips.prt';

SECTION_NUMBER 6
 '@BASEBOARD_FAB2_LIB.BASEBOARD_FAB2(SCH_1):PAGE60_I172@CHPSET_LIB.SKX_EXT_B(CHIPS)':
 C_PATH='@baseboard_fab2_lib.baseboard_fab2(sch_1):page60_i172@chpset_lib.skx_ex~
t_b(chips)',
 P_PATH='@baseboard_fab2_lib.baseboard_fab2(sch_1):page60_i172@chpset_lib.skx_ex~
t_b(chips)',
 PATH='I172',
 DRAWING='@BASEBOARD_FAB2_LIB.BASEBOARD_FAB2(SCH_1):PAGE60',
 SEC_TYPE='BGA1',
 MATERIAL='IC',
 PHYS_PAGE='60',
 XY='(-4175,2575)',
 ROT='0',
 VER='6',
 PACK_TYPE='BGA1',
 PART_NUMBER='TBD',
 LOCATION='U2D1',
 SEC='6',
 CDS_LIB='chpset_lib',
 CDS_PART_NAME='SKX_EXT_B_BGA1-IC,TBD',
 PRIM_FILE='./archive_libs/logical/skx_ext_b/chips/chips.prt';

SECTION_NUMBER 7
 '@BASEBOARD_FAB2_LIB.BASEBOARD_FAB2(SCH_1):PAGE61_I172@CHPSET_LIB.SKX_EXT_B(CHIPS)':
 C_PATH='@baseboard_fab2_lib.baseboard_fab2(sch_1):page61_i172@chpset_lib.skx_ex~
t_b(chips)',
 P_PATH='@baseboard_fab2_lib.baseboard_fab2(sch_1):page61_i172@chpset_lib.skx_ex~
t_b(chips)',
 PATH='I172',
 DRAWING='@BASEBOARD_FAB2_LIB.BASEBOARD_FAB2(SCH_1):PAGE61',
 SEC_TYPE='BGA1',
 MATERIAL='IC',
 PHYS_PAGE='61',
 XY='(-4175,2575)',
 ROT='0',
 VER='7',
 PACK_TYPE='BGA1',
 PART_NUMBER='TBD',
 LOCATION='U2D1',
 SEC='7',
 CDS_LIB='chpset_lib',
 CDS_PART_NAME='SKX_EXT_B_BGA1-IC,TBD',
 PRIM_FILE='./archive_libs/logical/skx_ext_b/chips/chips.prt';

SECTION_NUMBER 8
 '@BASEBOARD_FAB2_LIB.BASEBOARD_FAB2(SCH_1):PAGE62_I172@CHPSET_LIB.SKX_EXT_B(CHIPS)':
 C_PATH='@baseboard_fab2_lib.baseboard_fab2(sch_1):page62_i172@chpset_lib.skx_ex~
t_b(chips)',
 P_PATH='@baseboard_fab2_lib.baseboard_fab2(sch_1):page62_i172@chpset_lib.skx_ex~
t_b(chips)',
 PATH='I172',
 DRAWING='@BASEBOARD_FAB2_LIB.BASEBOARD_FAB2(SCH_1):PAGE62',
 SEC_TYPE='BGA1',
 MATERIAL='IC',
 PHYS_PAGE='62',
 XY='(-4200,2550)',
 ROT='0',
 VER='8',
 PACK_TYPE='BGA1',
 PART_NUMBER='TBD',
 LOCATION='U2D1',
 SEC='8',
 CDS_LIB='chpset_lib',
 CDS_PART_NAME='SKX_EXT_B_BGA1-IC,TBD',
 PRIM_FILE='./archive_libs/logical/skx_ext_b/chips/chips.prt';

SECTION_NUMBER 9
 '@BASEBOARD_FAB2_LIB.BASEBOARD_FAB2(SCH_1):PAGE63_I23@CHPSET_LIB.SKX_EXT_B(CHIPS)':
 C_PATH='@baseboard_fab2_lib.baseboard_fab2(sch_1):page63_i23@chpset_lib.skx_ext~
_b(chips)',
 P_PATH='@baseboard_fab2_lib.baseboard_fab2(sch_1):page63_i23@chpset_lib.skx_ext~
_b(chips)',
 PATH='I23',
 DRAWING='@BASEBOARD_FAB2_LIB.BASEBOARD_FAB2(SCH_1):PAGE63',
 SEC_TYPE='BGA1',
 MATERIAL='IC',
 PHYS_PAGE='63',
 XY='(-4075,2500)',
 ROT='0',
 VER='9',
 PACK_TYPE='BGA1',
 PART_NUMBER='TBD',
 LOCATION='U2D1',
 SEC='9',
 CDS_LIB='chpset_lib',
 CDS_PART_NAME='SKX_EXT_B_BGA1-IC,TBD',
 PRIM_FILE='./archive_libs/logical/skx_ext_b/chips/chips.prt';

SECTION_NUMBER 10
 '@BASEBOARD_FAB2_LIB.BASEBOARD_FAB2(SCH_1):PAGE64_I68@CHPSET_LIB.SKX_EXT_B(CHIPS)':
 C_PATH='@baseboard_fab2_lib.baseboard_fab2(sch_1):page64_i68@chpset_lib.skx_ext~
_b(chips)',
 P_PATH='@baseboard_fab2_lib.baseboard_fab2(sch_1):page64_i68@chpset_lib.skx_ext~
_b(chips)',
 PATH='I68',
 DRAWING='@BASEBOARD_FAB2_LIB.BASEBOARD_FAB2(SCH_1):PAGE64',
 SEC_TYPE='BGA1',
 MATERIAL='IC',
 PHYS_PAGE='64',
 XY='(-4075,2575)',
 ROT='0',
 VER='10',
 PACK_TYPE='BGA1',
 PART_NUMBER='TBD',
 LOCATION='U2D1',
 SEC='10',
 CDS_LIB='chpset_lib',
 CDS_PART_NAME='SKX_EXT_B_BGA1-IC,TBD',
 PRIM_FILE='./archive_libs/logical/skx_ext_b/chips/chips.prt';

SECTION_NUMBER 11
 '@BASEBOARD_FAB2_LIB.BASEBOARD_FAB2(SCH_1):PAGE65_I68@CHPSET_LIB.SKX_EXT_B(CHIPS)':
 C_PATH='@baseboard_fab2_lib.baseboard_fab2(sch_1):page65_i68@chpset_lib.skx_ext~
_b(chips)',
 P_PATH='@baseboard_fab2_lib.baseboard_fab2(sch_1):page65_i68@chpset_lib.skx_ext~
_b(chips)',
 PATH='I68',
 DRAWING='@BASEBOARD_FAB2_LIB.BASEBOARD_FAB2(SCH_1):PAGE65',
 SEC_TYPE='BGA1',
 MATERIAL='IC',
 PHYS_PAGE='65',
 XY='(-4150,2575)',
 ROT='0',
 VER='11',
 PACK_TYPE='BGA1',
 PART_NUMBER='TBD',
 LOCATION='U2D1',
 SEC='11',
 CDS_LIB='chpset_lib',
 CDS_PART_NAME='SKX_EXT_B_BGA1-IC,TBD',
 PRIM_FILE='./archive_libs/logical/skx_ext_b/chips/chips.prt';

SECTION_NUMBER 12
 '@BASEBOARD_FAB2_LIB.BASEBOARD_FAB2(SCH_1):PAGE66_I84@CHPSET_LIB.SKX_EXT_B(CHIPS)':
 C_PATH='@baseboard_fab2_lib.baseboard_fab2(sch_1):page66_i84@chpset_lib.skx_ext~
_b(chips)',
 P_PATH='@baseboard_fab2_lib.baseboard_fab2(sch_1):page66_i84@chpset_lib.skx_ext~
_b(chips)',
 PATH='I84',
 DRAWING='@BASEBOARD_FAB2_LIB.BASEBOARD_FAB2(SCH_1):PAGE66',
 SEC_TYPE='BGA1',
 MATERIAL='IC',
 PHYS_PAGE='66',
 XY='(-4125,2575)',
 ROT='0',
 VER='12',
 PACK_TYPE='BGA1',
 PART_NUMBER='TBD',
 LOCATION='U2D1',
 SEC='12',
 CDS_LIB='chpset_lib',
 CDS_PART_NAME='SKX_EXT_B_BGA1-IC,TBD',
 PRIM_FILE='./archive_libs/logical/skx_ext_b/chips/chips.prt';

SECTION_NUMBER 13
 '@BASEBOARD_FAB2_LIB.BASEBOARD_FAB2(SCH_1):PAGE67_I132@CHPSET_LIB.SKX_EXT_B(CHIPS)':
 C_PATH='@baseboard_fab2_lib.baseboard_fab2(sch_1):page67_i132@chpset_lib.skx_ex~
t_b(chips)',
 P_PATH='@baseboard_fab2_lib.baseboard_fab2(sch_1):page67_i132@chpset_lib.skx_ex~
t_b(chips)',
 PATH='I132',
 DRAWING='@BASEBOARD_FAB2_LIB.BASEBOARD_FAB2(SCH_1):PAGE67',
 SEC_TYPE='BGA1',
 MATERIAL='IC',
 PHYS_PAGE='67',
 XY='(-4050,2575)',
 ROT='0',
 VER='13',
 PACK_TYPE='BGA1',
 PART_NUMBER='TBD',
 LOCATION='U2D1',
 SEC='13',
 CDS_LIB='chpset_lib',
 CDS_PART_NAME='SKX_EXT_B_BGA1-IC,TBD',
 PRIM_FILE='./archive_libs/logical/skx_ext_b/chips/chips.prt';

SECTION_NUMBER 14
 '@BASEBOARD_FAB2_LIB.BASEBOARD_FAB2(SCH_1):PAGE68_I125@CHPSET_LIB.SKX_EXT_B(CHIPS)':
 C_PATH='@baseboard_fab2_lib.baseboard_fab2(sch_1):page68_i125@chpset_lib.skx_ex~
t_b(chips)',
 P_PATH='@baseboard_fab2_lib.baseboard_fab2(sch_1):page68_i125@chpset_lib.skx_ex~
t_b(chips)',
 PATH='I125',
 DRAWING='@BASEBOARD_FAB2_LIB.BASEBOARD_FAB2(SCH_1):PAGE68',
 SEC_TYPE='BGA1',
 MATERIAL='IC',
 PHYS_PAGE='68',
 XY='(-4100,2650)',
 ROT='0',
 VER='14',
 PACK_TYPE='BGA1',
 PART_NUMBER='TBD',
 LOCATION='U2D1',
 SEC='14',
 CDS_LIB='chpset_lib',
 CDS_PART_NAME='SKX_EXT_B_BGA1-IC,TBD',
 PRIM_FILE='./archive_libs/logical/skx_ext_b/chips/chips.prt';

SECTION_NUMBER 15
 '@BASEBOARD_FAB2_LIB.BASEBOARD_FAB2(SCH_1):PAGE69_I1@CHPSET_LIB.SKX_EXT_B(CHIPS)':
 C_PATH='@baseboard_fab2_lib.baseboard_fab2(sch_1):page69_i1@chpset_lib.skx_ext_~
b(chips)',
 P_PATH='@baseboard_fab2_lib.baseboard_fab2(sch_1):page69_i1@chpset_lib.skx_ext_~
b(chips)',
 PATH='I1',
 DRAWING='@BASEBOARD_FAB2_LIB.BASEBOARD_FAB2(SCH_1):PAGE69',
 SEC_TYPE='BGA1',
 MATERIAL='IC',
 PHYS_PAGE='69',
 XY='(-4275,2700)',
 ROT='0',
 VER='15',
 PACK_TYPE='BGA1',
 PART_NUMBER='TBD',
 LOCATION='U2D1',
 SEC='15',
 CDS_LIB='chpset_lib',
 CDS_PART_NAME='SKX_EXT_B_BGA1-IC,TBD',
 PRIM_FILE='./archive_libs/logical/skx_ext_b/chips/chips.prt';

SECTION_NUMBER 16
 '@BASEBOARD_FAB2_LIB.BASEBOARD_FAB2(SCH_1):PAGE70_I9@CHPSET_LIB.SKX_EXT_B(CHIPS)':
 C_PATH='@baseboard_fab2_lib.baseboard_fab2(sch_1):page70_i9@chpset_lib.skx_ext_~
b(chips)',
 P_PATH='@baseboard_fab2_lib.baseboard_fab2(sch_1):page70_i9@chpset_lib.skx_ext_~
b(chips)',
 PATH='I9',
 DRAWING='@BASEBOARD_FAB2_LIB.BASEBOARD_FAB2(SCH_1):PAGE70',
 SEC_TYPE='BGA1',
 MATERIAL='IC',
 PHYS_PAGE='70',
 XY='(-5450,2550)',
 ROT='0',
 VER='16',
 PACK_TYPE='BGA1',
 PART_NUMBER='TBD',
 LOCATION='U2D1',
 SEC='16',
 CDS_LIB='chpset_lib',
 CDS_PART_NAME='SKX_EXT_B_BGA1-IC,TBD',
 PRIM_FILE='./archive_libs/logical/skx_ext_b/chips/chips.prt';

SECTION_NUMBER 17
 '@BASEBOARD_FAB2_LIB.BASEBOARD_FAB2(SCH_1):PAGE70_I10@CHPSET_LIB.SKX_EXT_B(CHIPS)':
 C_PATH='@baseboard_fab2_lib.baseboard_fab2(sch_1):page70_i10@chpset_lib.skx_ext~
_b(chips)',
 P_PATH='@baseboard_fab2_lib.baseboard_fab2(sch_1):page70_i10@chpset_lib.skx_ext~
_b(chips)',
 PATH='I10',
 DRAWING='@BASEBOARD_FAB2_LIB.BASEBOARD_FAB2(SCH_1):PAGE70',
 SEC_TYPE='BGA1',
 MATERIAL='IC',
 PHYS_PAGE='70',
 XY='(-2925,2575)',
 ROT='0',
 VER='17',
 PACK_TYPE='BGA1',
 PART_NUMBER='TBD',
 LOCATION='U2D1',
 SEC='17',
 CDS_LIB='chpset_lib',
 CDS_PART_NAME='SKX_EXT_B_BGA1-IC,TBD',
 PRIM_FILE='./archive_libs/logical/skx_ext_b/chips/chips.prt';

SECTION_NUMBER 18
 '@BASEBOARD_FAB2_LIB.BASEBOARD_FAB2(SCH_1):PAGE71_I50@CHPSET_LIB.SKX_EXT_B(CHIPS)':
 C_PATH='@baseboard_fab2_lib.baseboard_fab2(sch_1):page71_i50@chpset_lib.skx_ext~
_b(chips)',
 P_PATH='@baseboard_fab2_lib.baseboard_fab2(sch_1):page71_i50@chpset_lib.skx_ext~
_b(chips)',
 PATH='I50',
 DRAWING='@BASEBOARD_FAB2_LIB.BASEBOARD_FAB2(SCH_1):PAGE71',
 SEC_TYPE='BGA1',
 MATERIAL='IC',
 PHYS_PAGE='71',
 XY='(-6375,2525)',
 ROT='0',
 VER='18',
 PACK_TYPE='BGA1',
 PART_NUMBER='TBD',
 LOCATION='U2D1',
 SEC='18',
 CDS_LIB='chpset_lib',
 CDS_PART_NAME='SKX_EXT_B_BGA1-IC,TBD',
 PRIM_FILE='./archive_libs/logical/skx_ext_b/chips/chips.prt';

SECTION_NUMBER 19
 '@BASEBOARD_FAB2_LIB.BASEBOARD_FAB2(SCH_1):PAGE71_I51@CHPSET_LIB.SKX_EXT_B(CHIPS)':
 C_PATH='@baseboard_fab2_lib.baseboard_fab2(sch_1):page71_i51@chpset_lib.skx_ext~
_b(chips)',
 P_PATH='@baseboard_fab2_lib.baseboard_fab2(sch_1):page71_i51@chpset_lib.skx_ext~
_b(chips)',
 PATH='I51',
 DRAWING='@BASEBOARD_FAB2_LIB.BASEBOARD_FAB2(SCH_1):PAGE71',
 SEC_TYPE='BGA1',
 MATERIAL='IC',
 PHYS_PAGE='71',
 XY='(-2675,2525)',
 ROT='0',
 VER='19',
 PACK_TYPE='BGA1',
 PART_NUMBER='TBD',
 LOCATION='U2D1',
 SEC='19',
 CDS_LIB='chpset_lib',
 CDS_PART_NAME='SKX_EXT_B_BGA1-IC,TBD',
 PRIM_FILE='./archive_libs/logical/skx_ext_b/chips/chips.prt';

SECTION_NUMBER 20
 '@BASEBOARD_FAB2_LIB.BASEBOARD_FAB2(SCH_1):PAGE72_I32@CHPSET_LIB.SKX_EXT_B(CHIPS)':
 C_PATH='@baseboard_fab2_lib.baseboard_fab2(sch_1):page72_i32@chpset_lib.skx_ext~
_b(chips)',
 P_PATH='@baseboard_fab2_lib.baseboard_fab2(sch_1):page72_i32@chpset_lib.skx_ext~
_b(chips)',
 PATH='I32',
 DRAWING='@BASEBOARD_FAB2_LIB.BASEBOARD_FAB2(SCH_1):PAGE72',
 SEC_TYPE='BGA1',
 MATERIAL='IC',
 PHYS_PAGE='72',
 XY='(-6200,2550)',
 ROT='0',
 VER='20',
 PACK_TYPE='BGA1',
 PART_NUMBER='TBD',
 LOCATION='U2D1',
 SEC='20',
 CDS_LIB='chpset_lib',
 CDS_PART_NAME='SKX_EXT_B_BGA1-IC,TBD',
 PRIM_FILE='./archive_libs/logical/skx_ext_b/chips/chips.prt';

SECTION_NUMBER 21
 '@BASEBOARD_FAB2_LIB.BASEBOARD_FAB2(SCH_1):PAGE72_I33@CHPSET_LIB.SKX_EXT_B(CHIPS)':
 C_PATH='@baseboard_fab2_lib.baseboard_fab2(sch_1):page72_i33@chpset_lib.skx_ext~
_b(chips)',
 P_PATH='@baseboard_fab2_lib.baseboard_fab2(sch_1):page72_i33@chpset_lib.skx_ext~
_b(chips)',
 PATH='I33',
 DRAWING='@BASEBOARD_FAB2_LIB.BASEBOARD_FAB2(SCH_1):PAGE72',
 SEC_TYPE='BGA1',
 MATERIAL='IC',
 PHYS_PAGE='72',
 XY='(-2700,2575)',
 ROT='0',
 VER='21',
 PACK_TYPE='BGA1',
 PART_NUMBER='TBD',
 LOCATION='U2D1',
 SEC='21',
 CDS_LIB='chpset_lib',
 CDS_PART_NAME='SKX_EXT_B_BGA1-IC,TBD',
 PRIM_FILE='./archive_libs/logical/skx_ext_b/chips/chips.prt';

SECTION_NUMBER 22
 '@BASEBOARD_FAB2_LIB.BASEBOARD_FAB2(SCH_1):PAGE73_I107@CHPSET_LIB.SKX_EXT_B(CHIPS)':
 C_PATH='@baseboard_fab2_lib.baseboard_fab2(sch_1):page73_i107@chpset_lib.skx_ex~
t_b(chips)',
 P_PATH='@baseboard_fab2_lib.baseboard_fab2(sch_1):page73_i107@chpset_lib.skx_ex~
t_b(chips)',
 PATH='I107',
 DRAWING='@BASEBOARD_FAB2_LIB.BASEBOARD_FAB2(SCH_1):PAGE73',
 SEC_TYPE='BGA1',
 MATERIAL='IC',
 PHYS_PAGE='73',
 XY='(-4000,2550)',
 ROT='0',
 VER='22',
 PACK_TYPE='BGA1',
 PART_NUMBER='TBD',
 LOCATION='U2D1',
 SEC='22',
 CDS_LIB='chpset_lib',
 CDS_PART_NAME='SKX_EXT_B_BGA1-IC,TBD',
 PRIM_FILE='./archive_libs/logical/skx_ext_b/chips/chips.prt';

SECTION_NUMBER 23
 '@BASEBOARD_FAB2_LIB.BASEBOARD_FAB2(SCH_1):PAGE74_I20@CHPSET_LIB.SKX_EXT_B(CHIPS)':
 C_PATH='@baseboard_fab2_lib.baseboard_fab2(sch_1):page74_i20@chpset_lib.skx_ext~
_b(chips)',
 P_PATH='@baseboard_fab2_lib.baseboard_fab2(sch_1):page74_i20@chpset_lib.skx_ext~
_b(chips)',
 PATH='I20',
 DRAWING='@BASEBOARD_FAB2_LIB.BASEBOARD_FAB2(SCH_1):PAGE74',
 SEC_TYPE='BGA1',
 MATERIAL='IC',
 PHYS_PAGE='74',
 XY='(-6875,2600)',
 ROT='0',
 VER='23',
 PACK_TYPE='BGA1',
 PART_NUMBER='TBD',
 LOCATION='U2D1',
 SEC='23',
 CDS_LIB='chpset_lib',
 CDS_PART_NAME='SKX_EXT_B_BGA1-IC,TBD',
 PRIM_FILE='./archive_libs/logical/skx_ext_b/chips/chips.prt';

SECTION_NUMBER 24
 '@BASEBOARD_FAB2_LIB.BASEBOARD_FAB2(SCH_1):PAGE74_I21@CHPSET_LIB.SKX_EXT_B(CHIPS)':
 C_PATH='@baseboard_fab2_lib.baseboard_fab2(sch_1):page74_i21@chpset_lib.skx_ext~
_b(chips)',
 P_PATH='@baseboard_fab2_lib.baseboard_fab2(sch_1):page74_i21@chpset_lib.skx_ext~
_b(chips)',
 PATH='I21',
 DRAWING='@BASEBOARD_FAB2_LIB.BASEBOARD_FAB2(SCH_1):PAGE74',
 SEC_TYPE='BGA1',
 MATERIAL='IC',
 PHYS_PAGE='74',
 XY='(-5025,2625)',
 ROT='0',
 VER='24',
 PACK_TYPE='BGA1',
 PART_NUMBER='TBD',
 LOCATION='U2D1',
 SEC='24',
 CDS_LIB='chpset_lib',
 CDS_PART_NAME='SKX_EXT_B_BGA1-IC,TBD',
 PRIM_FILE='./archive_libs/logical/skx_ext_b/chips/chips.prt';

SECTION_NUMBER 25
 '@BASEBOARD_FAB2_LIB.BASEBOARD_FAB2(SCH_1):PAGE74_I22@CHPSET_LIB.SKX_EXT_B(CHIPS)':
 C_PATH='@baseboard_fab2_lib.baseboard_fab2(sch_1):page74_i22@chpset_lib.skx_ext~
_b(chips)',
 P_PATH='@baseboard_fab2_lib.baseboard_fab2(sch_1):page74_i22@chpset_lib.skx_ext~
_b(chips)',
 PATH='I22',
 DRAWING='@BASEBOARD_FAB2_LIB.BASEBOARD_FAB2(SCH_1):PAGE74',
 SEC_TYPE='BGA1',
 MATERIAL='IC',
 PHYS_PAGE='74',
 XY='(-3200,2625)',
 ROT='0',
 VER='25',
 PACK_TYPE='BGA1',
 PART_NUMBER='TBD',
 LOCATION='U2D1',
 SEC='25',
 CDS_LIB='chpset_lib',
 CDS_PART_NAME='SKX_EXT_B_BGA1-IC,TBD',
 PRIM_FILE='./archive_libs/logical/skx_ext_b/chips/chips.prt';

SECTION_NUMBER 26
 '@BASEBOARD_FAB2_LIB.BASEBOARD_FAB2(SCH_1):PAGE74_I23@CHPSET_LIB.SKX_EXT_B(CHIPS)':
 C_PATH='@baseboard_fab2_lib.baseboard_fab2(sch_1):page74_i23@chpset_lib.skx_ext~
_b(chips)',
 P_PATH='@baseboard_fab2_lib.baseboard_fab2(sch_1):page74_i23@chpset_lib.skx_ext~
_b(chips)',
 PATH='I23',
 DRAWING='@BASEBOARD_FAB2_LIB.BASEBOARD_FAB2(SCH_1):PAGE74',
 SEC_TYPE='BGA1',
 MATERIAL='IC',
 PHYS_PAGE='74',
 XY='(-1275,2600)',
 ROT='0',
 VER='26',
 PACK_TYPE='BGA1',
 PART_NUMBER='TBD',
 LOCATION='U2D1',
 SEC='26',
 CDS_LIB='chpset_lib',
 CDS_PART_NAME='SKX_EXT_B_BGA1-IC,TBD',
 PRIM_FILE='./archive_libs/logical/skx_ext_b/chips/chips.prt';

SECTION_NUMBER 27
 '@BASEBOARD_FAB2_LIB.BASEBOARD_FAB2(SCH_1):PAGE75_I17@CHPSET_LIB.SKX_EXT_B(CHIPS)':
 C_PATH='@baseboard_fab2_lib.baseboard_fab2(sch_1):page75_i17@chpset_lib.skx_ext~
_b(chips)',
 P_PATH='@baseboard_fab2_lib.baseboard_fab2(sch_1):page75_i17@chpset_lib.skx_ext~
_b(chips)',
 PATH='I17',
 DRAWING='@BASEBOARD_FAB2_LIB.BASEBOARD_FAB2(SCH_1):PAGE75',
 SEC_TYPE='BGA1',
 MATERIAL='IC',
 PHYS_PAGE='75',
 XY='(-6725,2525)',
 ROT='0',
 VER='27',
 PACK_TYPE='BGA1',
 PART_NUMBER='TBD',
 LOCATION='U2D1',
 SEC='27',
 CDS_LIB='chpset_lib',
 CDS_PART_NAME='SKX_EXT_B_BGA1-IC,TBD',
 PRIM_FILE='./archive_libs/logical/skx_ext_b/chips/chips.prt';

SECTION_NUMBER 28
 '@BASEBOARD_FAB2_LIB.BASEBOARD_FAB2(SCH_1):PAGE75_I18@CHPSET_LIB.SKX_EXT_B(CHIPS)':
 C_PATH='@baseboard_fab2_lib.baseboard_fab2(sch_1):page75_i18@chpset_lib.skx_ext~
_b(chips)',
 P_PATH='@baseboard_fab2_lib.baseboard_fab2(sch_1):page75_i18@chpset_lib.skx_ext~
_b(chips)',
 PATH='I18',
 DRAWING='@BASEBOARD_FAB2_LIB.BASEBOARD_FAB2(SCH_1):PAGE75',
 SEC_TYPE='BGA1',
 MATERIAL='IC',
 PHYS_PAGE='75',
 XY='(-4925,2525)',
 ROT='0',
 VER='28',
 PACK_TYPE='BGA1',
 PART_NUMBER='TBD',
 LOCATION='U2D1',
 SEC='28',
 CDS_LIB='chpset_lib',
 CDS_PART_NAME='SKX_EXT_B_BGA1-IC,TBD',
 PRIM_FILE='./archive_libs/logical/skx_ext_b/chips/chips.prt';

SECTION_NUMBER 29
 '@BASEBOARD_FAB2_LIB.BASEBOARD_FAB2(SCH_1):PAGE75_I19@CHPSET_LIB.SKX_EXT_B(CHIPS)':
 C_PATH='@baseboard_fab2_lib.baseboard_fab2(sch_1):page75_i19@chpset_lib.skx_ext~
_b(chips)',
 P_PATH='@baseboard_fab2_lib.baseboard_fab2(sch_1):page75_i19@chpset_lib.skx_ext~
_b(chips)',
 PATH='I19',
 DRAWING='@BASEBOARD_FAB2_LIB.BASEBOARD_FAB2(SCH_1):PAGE75',
 SEC_TYPE='BGA1',
 MATERIAL='IC',
 PHYS_PAGE='75',
 XY='(-3050,2525)',
 ROT='0',
 VER='29',
 PACK_TYPE='BGA1',
 PART_NUMBER='TBD',
 LOCATION='U2D1',
 SEC='29',
 CDS_LIB='chpset_lib',
 CDS_PART_NAME='SKX_EXT_B_BGA1-IC,TBD',
 PRIM_FILE='./archive_libs/logical/skx_ext_b/chips/chips.prt';

SECTION_NUMBER 30
 '@BASEBOARD_FAB2_LIB.BASEBOARD_FAB2(SCH_1):PAGE75_I20@CHPSET_LIB.SKX_EXT_B(CHIPS)':
 C_PATH='@baseboard_fab2_lib.baseboard_fab2(sch_1):page75_i20@chpset_lib.skx_ext~
_b(chips)',
 P_PATH='@baseboard_fab2_lib.baseboard_fab2(sch_1):page75_i20@chpset_lib.skx_ext~
_b(chips)',
 PATH='I20',
 DRAWING='@BASEBOARD_FAB2_LIB.BASEBOARD_FAB2(SCH_1):PAGE75',
 SEC_TYPE='BGA1',
 MATERIAL='IC',
 PHYS_PAGE='75',
 XY='(-1225,2550)',
 ROT='0',
 VER='30',
 PACK_TYPE='BGA1',
 PART_NUMBER='TBD',
 LOCATION='U2D1',
 SEC='30',
 CDS_LIB='chpset_lib',
 CDS_PART_NAME='SKX_EXT_B_BGA1-IC,TBD',
 PRIM_FILE='./archive_libs/logical/skx_ext_b/chips/chips.prt';

PART_NAME
 U2M1 'NC7SB3157_SMLF-IC,C99406-001':
 GROUP='MCP',
 ROOM='DEBUG';

SECTION_NUMBER 1
 '@BASEBOARD_FAB2_LIB.BASEBOARD_FAB2(SCH_1):PAGE113_I255@MSTR_ANALOG.NC7SB3157(CHIPS)':
 C_PATH='@baseboard_fab2_lib.baseboard_fab2(sch_1):page113_i255@mstr_analog.nc7s~
b3157(chips)',
 P_PATH='@baseboard_fab2_lib.baseboard_fab2(sch_1):page113_i255@mstr_analog.nc7s~
b3157(chips)',
 PATH='I255',
 DRAWING='@BASEBOARD_FAB2_LIB.BASEBOARD_FAB2(SCH_1):PAGE113',
 SEC_TYPE='SMLF',
 MATERIAL='IC',
 BOM_COST='DEBUG',
 PHYS_PAGE='113',
 XY='(-2125,2325)',
 ROT='2',
 VER='1',
 PACK_TYPE='SMLF',
 PART_NUMBER='C99406-001',
 LOCATION='U2M1',
 ROOM='DEBUG',
 GROUP='MCP',
 SEC='1',
 CDS_LIB='mstr_analog',
 CDS_PART_NAME='NC7SB3157_SMLF-IC,C99406-001',
 PRIM_FILE='./archive_libs/mstr_analog/nc7sb3157/chips/chips.prt';

PART_NAME
 U2P1 'TTL1G07_A_SOP-74LVC1G07,IC,C88B':
 ROOM='M_2';

SECTION_NUMBER 1
 '@BASEBOARD_FAB2_LIB.BASEBOARD_FAB2(SCH_1):PAGE185_I110@MSTR_TTL.TTL1G07_A(CHIPS)':
 C_PATH='@baseboard_fab2_lib.baseboard_fab2(sch_1):page185_i110@mstr_ttl.ttl1g07~
_a(chips)',
 P_PATH='@baseboard_fab2_lib.baseboard_fab2(sch_1):page185_i110@mstr_ttl.ttl1g07~
_a(chips)',
 PATH='I110',
 DRAWING='@BASEBOARD_FAB2_LIB.BASEBOARD_FAB2(SCH_1):PAGE185',
 POWER_GROUP='GND=GND;VCC=P3V3_STBY',
 SEC_TYPE='SOP',
 MATERIAL='IC',
 BOM_COST='ST_FLASH',
 PHYS_PAGE='185',
 XY='(-5150,2500)',
 ROT='0',
 VER='1',
 VALUE='74LVC1G07',
 PACK_TYPE='SOP',
 PART_NUMBER='C88419-001',
 LOCATION='U2P1',
 ROOM='M_2',
 SEC='1',
 CDS_LIB='mstr_ttl',
 CDS_PART_NAME='TTL1G07_A_SOP-74LVC1G07,IC,C88B',
 PRIM_FILE='./archive_libs/mstr_ttl/ttl1g07_a/chips/chips.prt';

PART_NAME
 U2R1 'TC7PZ14FU-GP_DISCRET-GA1-TC7PZA':;

SECTION_NUMBER 1
 '@BASEBOARD_FAB2_LIB.BASEBOARD_FAB2(SCH_1):PAGE157_I390@W_HDL.TC7PZ14FU-GP(CHIPS)':
 C_PATH='@baseboard_fab2_lib.baseboard_fab2(sch_1):page157_i390@w_hdl.\tc7pz14fu~
-gp\(chips)',
 P_PATH='@baseboard_fab2_lib.baseboard_fab2(sch_1):page157_i390@w_hdl.\tc7pz14fu~
-gp\(chips)',
 PATH='I390',
 DRAWING='@BASEBOARD_FAB2_LIB.BASEBOARD_FAB2(SCH_1):PAGE157',
 SEC_TYPE='DISCRET-GA1',
 PHYS_PAGE='157',
 XY='(-2425,2725)',
 ROT='0',
 VER='1',
 VALUE='TC7PZ14FU-GP',
 PACK_TYPE='DISCRET-GA1',
 PART_NUMBER='073.7PZ14.0007',
 LOCATION='U2R1',
 SEC='1',
 CDS_LIB='w_hdl',
 CDS_PART_NAME='TC7PZ14FU-GP_DISCRET-GA1-TC7PZA',
 PRIM_FILE='C:/<user>/w_hdl/tc7pz14fu#2dgp/chips/chips.prt';

PART_NAME
 U2T1 'PI3B3257A_TSSOPLF-IC,E16801-001':
 ROOM='SB_BMC_SPI_MUX';

SECTION_NUMBER 1
 '@BASEBOARD_FAB2_LIB.BASEBOARD_FAB2(SCH_1):PAGE154_I75@MSTR_DIGITAL.PI3B3257A(CHIPS)':
 C_PATH='@baseboard_fab2_lib.baseboard_fab2(sch_1):page154_i75@mstr_digital.pi3b~
3257a(chips)',
 P_PATH='@baseboard_fab2_lib.baseboard_fab2(sch_1):page154_i75@mstr_digital.pi3b~
3257a(chips)',
 PATH='I75',
 DRAWING='@BASEBOARD_FAB2_LIB.BASEBOARD_FAB2(SCH_1):PAGE154',
 SEC_TYPE='TSSOPLF',
 MATERIAL='IC',
 BOM_COST='MIO_BIOS_MEM',
 PHYS_PAGE='154',
 XY='(-2000,3875)',
 ROT='2',
 VER='1',
 PACK_TYPE='TSSOPLF',
 PART_NUMBER='E16801-001',
 LOCATION='U2T1',
 ROOM='SB_BMC_SPI_MUX',
 SEC='1',
 CDS_LIB='mstr_digital',
 CDS_PART_NAME='PI3B3257A_TSSOPLF-IC,E16801-001',
 PRIM_FILE='./archive_libs/mstr_digital/pi3b3257a/chips/chips.prt';

PART_NAME
 U2T2 'TTL1G32_A_SOT-74LVC1G32,IC,E60B':
 GROUP='NI_BIOS_ROM2',
 ROOM='SB_BMC_SPI_MUX';

SECTION_NUMBER 1
 '@BASEBOARD_FAB2_LIB.BASEBOARD_FAB2(SCH_1):PAGE154_I100@MSTR_TTL.TTL1G32_A(CHIPS)':
 C_PATH='@baseboard_fab2_lib.baseboard_fab2(sch_1):page154_i100@mstr_ttl.ttl1g32~
_a(chips)',
 P_PATH='@baseboard_fab2_lib.baseboard_fab2(sch_1):page154_i100@mstr_ttl.ttl1g32~
_a(chips)',
 PATH='I100',
 DRAWING='@BASEBOARD_FAB2_LIB.BASEBOARD_FAB2(SCH_1):PAGE154',
 POWER_GROUP='GND=GND;VCC=P3V3_STBY',
 SEC_TYPE='SOT',
 MATERIAL='IC',
 BOM_COST='MIO_BIOS_MEM',
 PHYS_PAGE='154',
 XY='(-2275,1150)',
 ROT='0',
 VER='1',
 VALUE='74LVC1G32',
 PACK_TYPE='SOT',
 PART_NUMBER='E60229-001',
 LOCATION='U2T2',
 ROOM='SB_BMC_SPI_MUX',
 GROUP='NI_BIOS_ROM2',
 SEC='1',
 CDS_LIB='mstr_ttl',
 CDS_PART_NAME='TTL1G32_A_SOT-74LVC1G32,IC,E60B',
 PRIM_FILE='./archive_libs/mstr_ttl/ttl1g32_a/chips/chips.prt';

PART_NAME
 U2T3 'TTL1G32_A_SOT-74LVC1G32,IC,E60B':
 GROUP='NI_BIOS_ROM2',
 ROOM='SB_BMC_SPI_MUX';

SECTION_NUMBER 1
 '@BASEBOARD_FAB2_LIB.BASEBOARD_FAB2(SCH_1):PAGE154_I99@MSTR_TTL.TTL1G32_A(CHIPS)':
 C_PATH='@baseboard_fab2_lib.baseboard_fab2(sch_1):page154_i99@mstr_ttl.ttl1g32_~
a(chips)',
 P_PATH='@baseboard_fab2_lib.baseboard_fab2(sch_1):page154_i99@mstr_ttl.ttl1g32_~
a(chips)',
 PATH='I99',
 DRAWING='@BASEBOARD_FAB2_LIB.BASEBOARD_FAB2(SCH_1):PAGE154',
 POWER_GROUP='GND=GND;VCC=P3V3_STBY',
 SEC_TYPE='SOT',
 MATERIAL='IC',
 BOM_COST='MIO_BIOS_MEM',
 PHYS_PAGE='154',
 XY='(-2275,1875)',
 ROT='0',
 VER='1',
 VALUE='74LVC1G32',
 PACK_TYPE='SOT',
 PART_NUMBER='E60229-001',
 LOCATION='U2T3',
 ROOM='SB_BMC_SPI_MUX',
 GROUP='NI_BIOS_ROM2',
 SEC='1',
 CDS_LIB='mstr_ttl',
 CDS_PART_NAME='TTL1G32_A_SOT-74LVC1G32,IC,E60B',
 PRIM_FILE='./archive_libs/mstr_ttl/ttl1g32_a/chips/chips.prt';

PART_NAME
 U2T4 'GTL2014_SM-IC,D66151-001':
 ROOM='PROC_SIDEBAND';

SECTION_NUMBER 1
 '@BASEBOARD_FAB2_LIB.BASEBOARD_FAB2(SCH_1):PAGE93_I30@MSTR_DIGITAL.GTL2014(CHIPS)':
 C_PATH='@baseboard_fab2_lib.baseboard_fab2(sch_1):page93_i30@mstr_digital.gtl20~
14(chips)',
 P_PATH='@baseboard_fab2_lib.baseboard_fab2(sch_1):page93_i30@mstr_digital.gtl20~
14(chips)',
 PATH='I30',
 DRAWING='@BASEBOARD_FAB2_LIB.BASEBOARD_FAB2(SCH_1):PAGE93',
 SEC_TYPE='SM',
 MATERIAL='IC',
 BOM_COST='PROC',
 PHYS_PAGE='93',
 XY='(425,3350)',
 ROT='2',
 VER='1',
 PACK_TYPE='SM',
 PART_NUMBER='D66151-001',
 LOCATION='U2T4',
 ROOM='PROC_SIDEBAND',
 SEC='1',
 CDS_LIB='mstr_digital',
 CDS_PART_NAME='GTL2014_SM-IC,D66151-001',
 PRIM_FILE='./archive_libs/mstr_digital/gtl2014/chips/chips.prt';

PART_NAME
 U3B1 'PCA9617_SSOP-IC,G81764-001-GNDA':
 ROOM='MEM';

SECTION_NUMBER 1
 '@BASEBOARD_FAB2_LIB.BASEBOARD_FAB2(SCH_1):PAGE99_I75@MSTR_DIGITAL.PCA9617(CHIPS)':
 C_PATH='@baseboard_fab2_lib.baseboard_fab2(sch_1):page99_i75@mstr_digital.pca96~
17(chips)',
 P_PATH='@baseboard_fab2_lib.baseboard_fab2(sch_1):page99_i75@mstr_digital.pca96~
17(chips)',
 PATH='I75',
 DRAWING='@BASEBOARD_FAB2_LIB.BASEBOARD_FAB2(SCH_1):PAGE99',
 POWER_GROUP='GND=GND',
 MATERIAL='IC',
 BOM_COST='SM_CONTROLLER',
 PHYS_PAGE='99',
 XY='(150,900)',
 ROT='0',
 VER='1',
 PACK_TYPE='SSOP',
 PART_NUMBER='G81764-001',
 LOCATION='U3B1',
 ROOM='MEM',
 CDS_LIB='mstr_digital',
 CDS_PART_NAME='PCA9617_SSOP-IC,G81764-001',
 PRIM_FILE='./archive_libs/mstr_digital/pca9617/chips/chips.prt';

PART_NAME
 U3P1 'GTL2014_SM-IC,D66151-001':
 ROOM='PROC_RSTS_PGOODS';

SECTION_NUMBER 1
 '@BASEBOARD_FAB2_LIB.BASEBOARD_FAB2(SCH_1):PAGE96_I42@MSTR_DIGITAL.GTL2014(CHIPS)':
 C_PATH='@baseboard_fab2_lib.baseboard_fab2(sch_1):page96_i42@mstr_digital.gtl20~
14(chips)',
 P_PATH='@baseboard_fab2_lib.baseboard_fab2(sch_1):page96_i42@mstr_digital.gtl20~
14(chips)',
 PATH='I42',
 DRAWING='@BASEBOARD_FAB2_LIB.BASEBOARD_FAB2(SCH_1):PAGE96',
 MATERIAL='IC',
 BOM_COST='PROC_SIDEBAND',
 PHYS_PAGE='96',
 XY='(-875,4100)',
 ROT='0',
 VER='1',
 PACK_TYPE='SM',
 PART_NUMBER='D66151-001',
 LOCATION='U3P1',
 ROOM='PROC_RSTS_PGOODS',
 CDS_LIB='mstr_digital',
 CDS_PART_NAME='GTL2014_SM-IC,D66151-001',
 PRIM_FILE='./archive_libs/mstr_digital/gtl2014/chips/chips.prt';

PART_NAME
 U3P2 'GTL2014_SM-IC,D66151-001':
 ROOM='PROC_SIDEBAND';

SECTION_NUMBER 1
 '@BASEBOARD_FAB2_LIB.BASEBOARD_FAB2(SCH_1):PAGE92_I1@MSTR_DIGITAL.GTL2014(CHIPS)':
 C_PATH='@baseboard_fab2_lib.baseboard_fab2(sch_1):page92_i1@mstr_digital.gtl201~
4(chips)',
 P_PATH='@baseboard_fab2_lib.baseboard_fab2(sch_1):page92_i1@mstr_digital.gtl201~
4(chips)',
 PATH='I1',
 DRAWING='@BASEBOARD_FAB2_LIB.BASEBOARD_FAB2(SCH_1):PAGE92',
 SEC_TYPE='SM',
 MATERIAL='IC',
 BOM_COST='PROC_SIDEBAND',
 PHYS_PAGE='92',
 XY='(-1825,4250)',
 ROT='2',
 VER='1',
 PACK_TYPE='SM',
 PART_NUMBER='D66151-001',
 LOCATION='U3P2',
 ROOM='PROC_SIDEBAND',
 SEC='1',
 CDS_LIB='mstr_digital',
 CDS_PART_NAME='GTL2014_SM-IC,D66151-001',
 PRIM_FILE='./archive_libs/mstr_digital/gtl2014/chips/chips.prt';

PART_NAME
 U3T1 'W25Q256FVFIG-GP_MEMORY-G4-W25QA':
 GROUP='NI_BIOS_ROM2';

SECTION_NUMBER 1
 '@BASEBOARD_FAB2_LIB.BASEBOARD_FAB2(SCH_1):PAGE153_I185@W_HDL.W25Q256FVFIG-GP(CHIPS)':
 C_PATH='@baseboard_fab2_lib.baseboard_fab2(sch_1):page153_i185@w_hdl.\w25q256fv~
fig-gp\(chips)',
 P_PATH='@baseboard_fab2_lib.baseboard_fab2(sch_1):page153_i185@w_hdl.\w25q256fv~
fig-gp\(chips)',
 PATH='I185',
 DRAWING='@BASEBOARD_FAB2_LIB.BASEBOARD_FAB2(SCH_1):PAGE153',
 SEC_TYPE='MEMORY-G4',
 PHYS_PAGE='153',
 XY='(-4950,1800)',
 ROT='0',
 VER='1',
 VALUE='W25Q256FVFIG-GP',
 PACK_TYPE='MEMORY-G4',
 PART_NUMBER='72.25256.H01',
 LOCATION='U3T1',
 GROUP='NI_BIOS_ROM2',
 SEC='1',
 CDS_LIB='w_hdl',
 CDS_PART_NAME='W25Q256FVFIG-GP_MEMORY-G4-W25QA',
 PRIM_FILE='C:/<user>/w_hdl/w25q256fvfig#2dgp/chips/chips.prt';

PART_NAME
 U4C2 'GTL2014_SM-IC,D66151-001':
 ROOM='PROC_RSTS_PGOODS';

SECTION_NUMBER 1
 '@BASEBOARD_FAB2_LIB.BASEBOARD_FAB2(SCH_1):PAGE96_I46@MSTR_DIGITAL.GTL2014(CHIPS)':
 C_PATH='@baseboard_fab2_lib.baseboard_fab2(sch_1):page96_i46@mstr_digital.gtl20~
14(chips)',
 P_PATH='@baseboard_fab2_lib.baseboard_fab2(sch_1):page96_i46@mstr_digital.gtl20~
14(chips)',
 PATH='I46',
 DRAWING='@BASEBOARD_FAB2_LIB.BASEBOARD_FAB2(SCH_1):PAGE96',
 MATERIAL='IC',
 BOM_COST='PROC_SIDEBAND',
 PHYS_PAGE='96',
 XY='(-875,1800)',
 ROT='0',
 VER='1',
 PACK_TYPE='SM',
 PART_NUMBER='D66151-001',
 LOCATION='U4C2',
 ROOM='PROC_RSTS_PGOODS',
 CDS_LIB='mstr_digital',
 CDS_PART_NAME='GTL2014_SM-IC,D66151-001',
 PRIM_FILE='./archive_libs/mstr_digital/gtl2014/chips/chips.prt';

PART_NAME
 U4G1 'PCA9617_SSOP-IC,G81764-001-GNDA':
 ROOM='MEM';

SECTION_NUMBER 1
 '@BASEBOARD_FAB2_LIB.BASEBOARD_FAB2(SCH_1):PAGE99_I63@MSTR_DIGITAL.PCA9617(CHIPS)':
 C_PATH='@baseboard_fab2_lib.baseboard_fab2(sch_1):page99_i63@mstr_digital.pca96~
17(chips)',
 P_PATH='@baseboard_fab2_lib.baseboard_fab2(sch_1):page99_i63@mstr_digital.pca96~
17(chips)',
 PATH='I63',
 DRAWING='@BASEBOARD_FAB2_LIB.BASEBOARD_FAB2(SCH_1):PAGE99',
 POWER_GROUP='GND=GND',
 MATERIAL='IC',
 BOM_COST='SM_CONTROLLER',
 PHYS_PAGE='99',
 XY='(150,2100)',
 ROT='0',
 VER='1',
 PACK_TYPE='SSOP',
 PART_NUMBER='G81764-001',
 LOCATION='U4G1',
 ROOM='MEM',
 CDS_LIB='mstr_digital',
 CDS_PART_NAME='PCA9617_SSOP-IC,G81764-001',
 PRIM_FILE='./archive_libs/mstr_digital/pca9617/chips/chips.prt';

PART_NAME
 U4R1 '74CBTLV1G125_SMLF-IC,C88177-00A':
 ROOM='DEBUG';

SECTION_NUMBER 1
 '@BASEBOARD_FAB2_LIB.BASEBOARD_FAB2(SCH_1):PAGE113_I206@MSTR_TTL.74CBTLV1G125(CHIPS)':
 C_PATH='@baseboard_fab2_lib.baseboard_fab2(sch_1):page113_i206@mstr_ttl.\74cbtl~
v1g125\(chips)',
 P_PATH='@baseboard_fab2_lib.baseboard_fab2(sch_1):page113_i206@mstr_ttl.\74cbtl~
v1g125\(chips)',
 PATH='I206',
 DRAWING='@BASEBOARD_FAB2_LIB.BASEBOARD_FAB2(SCH_1):PAGE113',
 POWER_GROUP='GND=GND;VCC=P3V3_STBY',
 POP='NOPOP',
 SEC_TYPE='SMLF',
 MATERIAL='IC',
 BOM_COST='DEBUG',
 PHYS_PAGE='113',
 XY='(1625,3375)',
 ROT='0',
 VER='1',
 PACK_TYPE='SMLF',
 PART_NUMBER='C88177-001',
 LOCATION='U4R1',
 ROOM='DEBUG',
 SEC='1',
 CDS_LIB='mstr_ttl',
 CDS_PART_NAME='74CBTLV1G125_SMLF-IC,C88177-00A',
 PRIM_FILE='./archive_libs/mstr_ttl/74cbtlv1g125/chips/chips.prt';

PART_NAME
 U5D1 'SKX_EXT_B_BGA1-IC,TBD':
 ROOM='CPU0';

SECTION_NUMBER 1
 '@BASEBOARD_FAB2_LIB.BASEBOARD_FAB2(SCH_1):PAGE21_I259@CHPSET_LIB.SKX_EXT_B(CHIPS)':
 C_PATH='@baseboard_fab2_lib.baseboard_fab2(sch_1):page21_i259@chpset_lib.skx_ex~
t_b(chips)',
 P_PATH='@baseboard_fab2_lib.baseboard_fab2(sch_1):page21_i259@chpset_lib.skx_ex~
t_b(chips)',
 PATH='I259',
 DRAWING='@BASEBOARD_FAB2_LIB.BASEBOARD_FAB2(SCH_1):PAGE21',
 SEC_TYPE='BGA1',
 MATERIAL='IC',
 PHYS_PAGE='21',
 XY='(-4075,2850)',
 ROT='0',
 VER='1',
 PACK_TYPE='BGA1',
 PART_NUMBER='TBD',
 LOCATION='U5D1',
 ROOM='CPU0',
 SEC='1',
 CDS_LIB='chpset_lib',
 CDS_PART_NAME='SKX_EXT_B_BGA1-IC,TBD',
 PRIM_FILE='./archive_libs/logical/skx_ext_b/chips/chips.prt';

SECTION_NUMBER 2
 '@BASEBOARD_FAB2_LIB.BASEBOARD_FAB2(SCH_1):PAGE22_I204@CHPSET_LIB.SKX_EXT_B(CHIPS)':
 C_PATH='@baseboard_fab2_lib.baseboard_fab2(sch_1):page22_i204@chpset_lib.skx_ex~
t_b(chips)',
 P_PATH='@baseboard_fab2_lib.baseboard_fab2(sch_1):page22_i204@chpset_lib.skx_ex~
t_b(chips)',
 PATH='I204',
 DRAWING='@BASEBOARD_FAB2_LIB.BASEBOARD_FAB2(SCH_1):PAGE22',
 SEC_TYPE='BGA1',
 MATERIAL='IC',
 PHYS_PAGE='22',
 XY='(-4150,2550)',
 ROT='0',
 VER='2',
 PACK_TYPE='BGA1',
 PART_NUMBER='TBD',
 LOCATION='U5D1',
 ROOM='CPU0',
 SEC='2',
 CDS_LIB='chpset_lib',
 CDS_PART_NAME='SKX_EXT_B_BGA1-IC,TBD',
 PRIM_FILE='./archive_libs/logical/skx_ext_b/chips/chips.prt';

SECTION_NUMBER 3
 '@BASEBOARD_FAB2_LIB.BASEBOARD_FAB2(SCH_1):PAGE23_I172@CHPSET_LIB.SKX_EXT_B(CHIPS)':
 C_PATH='@baseboard_fab2_lib.baseboard_fab2(sch_1):page23_i172@chpset_lib.skx_ex~
t_b(chips)',
 P_PATH='@baseboard_fab2_lib.baseboard_fab2(sch_1):page23_i172@chpset_lib.skx_ex~
t_b(chips)',
 PATH='I172',
 DRAWING='@BASEBOARD_FAB2_LIB.BASEBOARD_FAB2(SCH_1):PAGE23',
 SEC_TYPE='BGA1',
 MATERIAL='IC',
 PHYS_PAGE='23',
 XY='(-4200,2600)',
 ROT='0',
 VER='3',
 PACK_TYPE='BGA1',
 PART_NUMBER='TBD',
 LOCATION='U5D1',
 ROOM='CPU0',
 SEC='3',
 CDS_LIB='chpset_lib',
 CDS_PART_NAME='SKX_EXT_B_BGA1-IC,TBD',
 PRIM_FILE='./archive_libs/logical/skx_ext_b/chips/chips.prt';

SECTION_NUMBER 4
 '@BASEBOARD_FAB2_LIB.BASEBOARD_FAB2(SCH_1):PAGE24_I172@CHPSET_LIB.SKX_EXT_B(CHIPS)':
 C_PATH='@baseboard_fab2_lib.baseboard_fab2(sch_1):page24_i172@chpset_lib.skx_ex~
t_b(chips)',
 P_PATH='@baseboard_fab2_lib.baseboard_fab2(sch_1):page24_i172@chpset_lib.skx_ex~
t_b(chips)',
 PATH='I172',
 DRAWING='@BASEBOARD_FAB2_LIB.BASEBOARD_FAB2(SCH_1):PAGE24',
 SEC_TYPE='BGA1',
 MATERIAL='IC',
 PHYS_PAGE='24',
 XY='(-4125,2550)',
 ROT='0',
 VER='4',
 PACK_TYPE='BGA1',
 PART_NUMBER='TBD',
 LOCATION='U5D1',
 ROOM='CPU0',
 SEC='4',
 CDS_LIB='chpset_lib',
 CDS_PART_NAME='SKX_EXT_B_BGA1-IC,TBD',
 PRIM_FILE='./archive_libs/logical/skx_ext_b/chips/chips.prt';

SECTION_NUMBER 5
 '@BASEBOARD_FAB2_LIB.BASEBOARD_FAB2(SCH_1):PAGE25_I172@CHPSET_LIB.SKX_EXT_B(CHIPS)':
 C_PATH='@baseboard_fab2_lib.baseboard_fab2(sch_1):page25_i172@chpset_lib.skx_ex~
t_b(chips)',
 P_PATH='@baseboard_fab2_lib.baseboard_fab2(sch_1):page25_i172@chpset_lib.skx_ex~
t_b(chips)',
 PATH='I172',
 DRAWING='@BASEBOARD_FAB2_LIB.BASEBOARD_FAB2(SCH_1):PAGE25',
 SEC_TYPE='BGA1',
 MATERIAL='IC',
 PHYS_PAGE='25',
 XY='(-4175,2600)',
 ROT='0',
 VER='5',
 PACK_TYPE='BGA1',
 PART_NUMBER='TBD',
 LOCATION='U5D1',
 ROOM='CPU0',
 SEC='5',
 CDS_LIB='chpset_lib',
 CDS_PART_NAME='SKX_EXT_B_BGA1-IC,TBD',
 PRIM_FILE='./archive_libs/logical/skx_ext_b/chips/chips.prt';

SECTION_NUMBER 6
 '@BASEBOARD_FAB2_LIB.BASEBOARD_FAB2(SCH_1):PAGE26_I172@CHPSET_LIB.SKX_EXT_B(CHIPS)':
 C_PATH='@baseboard_fab2_lib.baseboard_fab2(sch_1):page26_i172@chpset_lib.skx_ex~
t_b(chips)',
 P_PATH='@baseboard_fab2_lib.baseboard_fab2(sch_1):page26_i172@chpset_lib.skx_ex~
t_b(chips)',
 PATH='I172',
 DRAWING='@BASEBOARD_FAB2_LIB.BASEBOARD_FAB2(SCH_1):PAGE26',
 SEC_TYPE='BGA1',
 MATERIAL='IC',
 PHYS_PAGE='26',
 XY='(-4100,2575)',
 ROT='0',
 VER='6',
 PACK_TYPE='BGA1',
 PART_NUMBER='TBD',
 LOCATION='U5D1',
 ROOM='CPU0',
 SEC='6',
 CDS_LIB='chpset_lib',
 CDS_PART_NAME='SKX_EXT_B_BGA1-IC,TBD',
 PRIM_FILE='./archive_libs/logical/skx_ext_b/chips/chips.prt';

SECTION_NUMBER 7
 '@BASEBOARD_FAB2_LIB.BASEBOARD_FAB2(SCH_1):PAGE27_I172@CHPSET_LIB.SKX_EXT_B(CHIPS)':
 C_PATH='@baseboard_fab2_lib.baseboard_fab2(sch_1):page27_i172@chpset_lib.skx_ex~
t_b(chips)',
 P_PATH='@baseboard_fab2_lib.baseboard_fab2(sch_1):page27_i172@chpset_lib.skx_ex~
t_b(chips)',
 PATH='I172',
 DRAWING='@BASEBOARD_FAB2_LIB.BASEBOARD_FAB2(SCH_1):PAGE27',
 SEC_TYPE='BGA1',
 MATERIAL='IC',
 PHYS_PAGE='27',
 XY='(-4175,2550)',
 ROT='0',
 VER='7',
 PACK_TYPE='BGA1',
 PART_NUMBER='TBD',
 LOCATION='U5D1',
 ROOM='CPU0',
 SEC='7',
 CDS_LIB='chpset_lib',
 CDS_PART_NAME='SKX_EXT_B_BGA1-IC,TBD',
 PRIM_FILE='./archive_libs/logical/skx_ext_b/chips/chips.prt';

SECTION_NUMBER 8
 '@BASEBOARD_FAB2_LIB.BASEBOARD_FAB2(SCH_1):PAGE28_I172@CHPSET_LIB.SKX_EXT_B(CHIPS)':
 C_PATH='@baseboard_fab2_lib.baseboard_fab2(sch_1):page28_i172@chpset_lib.skx_ex~
t_b(chips)',
 P_PATH='@baseboard_fab2_lib.baseboard_fab2(sch_1):page28_i172@chpset_lib.skx_ex~
t_b(chips)',
 PATH='I172',
 DRAWING='@BASEBOARD_FAB2_LIB.BASEBOARD_FAB2(SCH_1):PAGE28',
 SEC_TYPE='BGA1',
 MATERIAL='IC',
 PHYS_PAGE='28',
 XY='(-4175,2575)',
 ROT='0',
 VER='8',
 PACK_TYPE='BGA1',
 PART_NUMBER='TBD',
 LOCATION='U5D1',
 ROOM='CPU0',
 SEC='8',
 CDS_LIB='chpset_lib',
 CDS_PART_NAME='SKX_EXT_B_BGA1-IC,TBD',
 PRIM_FILE='./archive_libs/logical/skx_ext_b/chips/chips.prt';

SECTION_NUMBER 9
 '@BASEBOARD_FAB2_LIB.BASEBOARD_FAB2(SCH_1):PAGE29_I61@CHPSET_LIB.SKX_EXT_B(CHIPS)':
 C_PATH='@baseboard_fab2_lib.baseboard_fab2(sch_1):page29_i61@chpset_lib.skx_ext~
_b(chips)',
 P_PATH='@baseboard_fab2_lib.baseboard_fab2(sch_1):page29_i61@chpset_lib.skx_ext~
_b(chips)',
 PATH='I61',
 DRAWING='@BASEBOARD_FAB2_LIB.BASEBOARD_FAB2(SCH_1):PAGE29',
 SEC_TYPE='BGA1',
 MATERIAL='IC',
 PHYS_PAGE='29',
 XY='(-3900,2550)',
 ROT='0',
 VER='9',
 PACK_TYPE='BGA1',
 PART_NUMBER='TBD',
 LOCATION='U5D1',
 ROOM='CPU0',
 SEC='9',
 CDS_LIB='chpset_lib',
 CDS_PART_NAME='SKX_EXT_B_BGA1-IC,TBD',
 PRIM_FILE='./archive_libs/logical/skx_ext_b/chips/chips.prt';

SECTION_NUMBER 10
 '@BASEBOARD_FAB2_LIB.BASEBOARD_FAB2(SCH_1):PAGE30_I84@CHPSET_LIB.SKX_EXT_B(CHIPS)':
 C_PATH='@baseboard_fab2_lib.baseboard_fab2(sch_1):page30_i84@chpset_lib.skx_ext~
_b(chips)',
 P_PATH='@baseboard_fab2_lib.baseboard_fab2(sch_1):page30_i84@chpset_lib.skx_ext~
_b(chips)',
 PATH='I84',
 DRAWING='@BASEBOARD_FAB2_LIB.BASEBOARD_FAB2(SCH_1):PAGE30',
 SEC_TYPE='BGA1',
 MATERIAL='IC',
 PHYS_PAGE='30',
 XY='(-4100,2550)',
 ROT='0',
 VER='10',
 PACK_TYPE='BGA1',
 PART_NUMBER='TBD',
 LOCATION='U5D1',
 ROOM='CPU0',
 SEC='10',
 CDS_LIB='chpset_lib',
 CDS_PART_NAME='SKX_EXT_B_BGA1-IC,TBD',
 PRIM_FILE='./archive_libs/logical/skx_ext_b/chips/chips.prt';

SECTION_NUMBER 11
 '@BASEBOARD_FAB2_LIB.BASEBOARD_FAB2(SCH_1):PAGE31_I106@CHPSET_LIB.SKX_EXT_B(CHIPS)':
 C_PATH='@baseboard_fab2_lib.baseboard_fab2(sch_1):page31_i106@chpset_lib.skx_ex~
t_b(chips)',
 P_PATH='@baseboard_fab2_lib.baseboard_fab2(sch_1):page31_i106@chpset_lib.skx_ex~
t_b(chips)',
 PATH='I106',
 DRAWING='@BASEBOARD_FAB2_LIB.BASEBOARD_FAB2(SCH_1):PAGE31',
 SEC_TYPE='BGA1',
 MATERIAL='IC',
 PHYS_PAGE='31',
 XY='(-4025,2600)',
 ROT='0',
 VER='11',
 PACK_TYPE='BGA1',
 PART_NUMBER='TBD',
 LOCATION='U5D1',
 ROOM='CPU0',
 SEC='11',
 CDS_LIB='chpset_lib',
 CDS_PART_NAME='SKX_EXT_B_BGA1-IC,TBD',
 PRIM_FILE='./archive_libs/logical/skx_ext_b/chips/chips.prt';

SECTION_NUMBER 12
 '@BASEBOARD_FAB2_LIB.BASEBOARD_FAB2(SCH_1):PAGE32_I89@CHPSET_LIB.SKX_EXT_B(CHIPS)':
 C_PATH='@baseboard_fab2_lib.baseboard_fab2(sch_1):page32_i89@chpset_lib.skx_ext~
_b(chips)',
 P_PATH='@baseboard_fab2_lib.baseboard_fab2(sch_1):page32_i89@chpset_lib.skx_ext~
_b(chips)',
 PATH='I89',
 DRAWING='@BASEBOARD_FAB2_LIB.BASEBOARD_FAB2(SCH_1):PAGE32',
 SEC_TYPE='BGA1',
 MATERIAL='IC',
 PHYS_PAGE='32',
 XY='(-4200,2575)',
 ROT='0',
 VER='12',
 PACK_TYPE='BGA1',
 PART_NUMBER='TBD',
 LOCATION='U5D1',
 SEC='12',
 CDS_LIB='chpset_lib',
 CDS_PART_NAME='SKX_EXT_B_BGA1-IC,TBD',
 PRIM_FILE='./archive_libs/logical/skx_ext_b/chips/chips.prt';

SECTION_NUMBER 13
 '@BASEBOARD_FAB2_LIB.BASEBOARD_FAB2(SCH_1):PAGE33_I86@CHPSET_LIB.SKX_EXT_B(CHIPS)':
 C_PATH='@baseboard_fab2_lib.baseboard_fab2(sch_1):page33_i86@chpset_lib.skx_ext~
_b(chips)',
 P_PATH='@baseboard_fab2_lib.baseboard_fab2(sch_1):page33_i86@chpset_lib.skx_ext~
_b(chips)',
 PATH='I86',
 DRAWING='@BASEBOARD_FAB2_LIB.BASEBOARD_FAB2(SCH_1):PAGE33',
 SEC_TYPE='BGA1',
 MATERIAL='IC',
 PHYS_PAGE='33',
 XY='(-4075,2600)',
 ROT='0',
 VER='13',
 PACK_TYPE='BGA1',
 PART_NUMBER='TBD',
 LOCATION='U5D1',
 ROOM='CPU0',
 SEC='13',
 CDS_LIB='chpset_lib',
 CDS_PART_NAME='SKX_EXT_B_BGA1-IC,TBD',
 PRIM_FILE='./archive_libs/logical/skx_ext_b/chips/chips.prt';

SECTION_NUMBER 14
 '@BASEBOARD_FAB2_LIB.BASEBOARD_FAB2(SCH_1):PAGE34_I86@CHPSET_LIB.SKX_EXT_B(CHIPS)':
 C_PATH='@baseboard_fab2_lib.baseboard_fab2(sch_1):page34_i86@chpset_lib.skx_ext~
_b(chips)',
 P_PATH='@baseboard_fab2_lib.baseboard_fab2(sch_1):page34_i86@chpset_lib.skx_ext~
_b(chips)',
 PATH='I86',
 DRAWING='@BASEBOARD_FAB2_LIB.BASEBOARD_FAB2(SCH_1):PAGE34',
 SEC_TYPE='BGA1',
 MATERIAL='IC',
 PHYS_PAGE='34',
 XY='(-4100,2575)',
 ROT='0',
 VER='14',
 PACK_TYPE='BGA1',
 PART_NUMBER='TBD',
 LOCATION='U5D1',
 ROOM='CPU0',
 SEC='14',
 CDS_LIB='chpset_lib',
 CDS_PART_NAME='SKX_EXT_B_BGA1-IC,TBD',
 PRIM_FILE='./archive_libs/logical/skx_ext_b/chips/chips.prt';

SECTION_NUMBER 15
 '@BASEBOARD_FAB2_LIB.BASEBOARD_FAB2(SCH_1):PAGE35_I3@CHPSET_LIB.SKX_EXT_B(CHIPS)':
 C_PATH='@baseboard_fab2_lib.baseboard_fab2(sch_1):page35_i3@chpset_lib.skx_ext_~
b(chips)',
 P_PATH='@baseboard_fab2_lib.baseboard_fab2(sch_1):page35_i3@chpset_lib.skx_ext_~
b(chips)',
 PATH='I3',
 DRAWING='@BASEBOARD_FAB2_LIB.BASEBOARD_FAB2(SCH_1):PAGE35',
 SEC_TYPE='BGA1',
 MATERIAL='IC',
 PHYS_PAGE='35',
 XY='(-4225,2625)',
 ROT='0',
 VER='15',
 PACK_TYPE='BGA1',
 PART_NUMBER='TBD',
 LOCATION='U5D1',
 ROOM='CPU0',
 SEC='15',
 CDS_LIB='chpset_lib',
 CDS_PART_NAME='SKX_EXT_B_BGA1-IC,TBD',
 PRIM_FILE='./archive_libs/logical/skx_ext_b/chips/chips.prt';

SECTION_NUMBER 16
 '@BASEBOARD_FAB2_LIB.BASEBOARD_FAB2(SCH_1):PAGE36_I15@CHPSET_LIB.SKX_EXT_B(CHIPS)':
 C_PATH='@baseboard_fab2_lib.baseboard_fab2(sch_1):page36_i15@chpset_lib.skx_ext~
_b(chips)',
 P_PATH='@baseboard_fab2_lib.baseboard_fab2(sch_1):page36_i15@chpset_lib.skx_ext~
_b(chips)',
 PATH='I15',
 DRAWING='@BASEBOARD_FAB2_LIB.BASEBOARD_FAB2(SCH_1):PAGE36',
 SEC_TYPE='BGA1',
 MATERIAL='IC',
 PHYS_PAGE='36',
 XY='(-6075,2550)',
 ROT='0',
 VER='16',
 PACK_TYPE='BGA1',
 PART_NUMBER='TBD',
 LOCATION='U5D1',
 ROOM='CPU0',
 SEC='16',
 CDS_LIB='chpset_lib',
 CDS_PART_NAME='SKX_EXT_B_BGA1-IC,TBD',
 PRIM_FILE='./archive_libs/logical/skx_ext_b/chips/chips.prt';

SECTION_NUMBER 17
 '@BASEBOARD_FAB2_LIB.BASEBOARD_FAB2(SCH_1):PAGE36_I16@CHPSET_LIB.SKX_EXT_B(CHIPS)':
 C_PATH='@baseboard_fab2_lib.baseboard_fab2(sch_1):page36_i16@chpset_lib.skx_ext~
_b(chips)',
 P_PATH='@baseboard_fab2_lib.baseboard_fab2(sch_1):page36_i16@chpset_lib.skx_ext~
_b(chips)',
 PATH='I16',
 DRAWING='@BASEBOARD_FAB2_LIB.BASEBOARD_FAB2(SCH_1):PAGE36',
 SEC_TYPE='BGA1',
 MATERIAL='IC',
 PHYS_PAGE='36',
 XY='(-2550,2525)',
 ROT='0',
 VER='17',
 PACK_TYPE='BGA1',
 PART_NUMBER='TBD',
 LOCATION='U5D1',
 ROOM='CPU0',
 SEC='17',
 CDS_LIB='chpset_lib',
 CDS_PART_NAME='SKX_EXT_B_BGA1-IC,TBD',
 PRIM_FILE='./archive_libs/logical/skx_ext_b/chips/chips.prt';

SECTION_NUMBER 18
 '@BASEBOARD_FAB2_LIB.BASEBOARD_FAB2(SCH_1):PAGE37_I310@CHPSET_LIB.SKX_EXT_B(CHIPS)':
 C_PATH='@baseboard_fab2_lib.baseboard_fab2(sch_1):page37_i310@chpset_lib.skx_ex~
t_b(chips)',
 P_PATH='@baseboard_fab2_lib.baseboard_fab2(sch_1):page37_i310@chpset_lib.skx_ex~
t_b(chips)',
 PATH='I310',
 DRAWING='@BASEBOARD_FAB2_LIB.BASEBOARD_FAB2(SCH_1):PAGE37',
 SEC_TYPE='BGA1',
 MATERIAL='IC',
 PHYS_PAGE='37',
 XY='(-6200,2475)',
 ROT='0',
 VER='18',
 PACK_TYPE='BGA1',
 PART_NUMBER='TBD',
 LOCATION='U5D1',
 ROOM='CPU0',
 SEC='18',
 CDS_LIB='chpset_lib',
 CDS_PART_NAME='SKX_EXT_B_BGA1-IC,TBD',
 PRIM_FILE='./archive_libs/logical/skx_ext_b/chips/chips.prt';

SECTION_NUMBER 19
 '@BASEBOARD_FAB2_LIB.BASEBOARD_FAB2(SCH_1):PAGE37_I311@CHPSET_LIB.SKX_EXT_B(CHIPS)':
 C_PATH='@baseboard_fab2_lib.baseboard_fab2(sch_1):page37_i311@chpset_lib.skx_ex~
t_b(chips)',
 P_PATH='@baseboard_fab2_lib.baseboard_fab2(sch_1):page37_i311@chpset_lib.skx_ex~
t_b(chips)',
 PATH='I311',
 DRAWING='@BASEBOARD_FAB2_LIB.BASEBOARD_FAB2(SCH_1):PAGE37',
 SEC_TYPE='BGA1',
 MATERIAL='IC',
 PHYS_PAGE='37',
 XY='(-2425,2475)',
 ROT='0',
 VER='19',
 PACK_TYPE='BGA1',
 PART_NUMBER='TBD',
 LOCATION='U5D1',
 ROOM='CPU0',
 SEC='19',
 CDS_LIB='chpset_lib',
 CDS_PART_NAME='SKX_EXT_B_BGA1-IC,TBD',
 PRIM_FILE='./archive_libs/logical/skx_ext_b/chips/chips.prt';

SECTION_NUMBER 20
 '@BASEBOARD_FAB2_LIB.BASEBOARD_FAB2(SCH_1):PAGE38_I33@CHPSET_LIB.SKX_EXT_B(CHIPS)':
 C_PATH='@baseboard_fab2_lib.baseboard_fab2(sch_1):page38_i33@chpset_lib.skx_ext~
_b(chips)',
 P_PATH='@baseboard_fab2_lib.baseboard_fab2(sch_1):page38_i33@chpset_lib.skx_ext~
_b(chips)',
 PATH='I33',
 DRAWING='@BASEBOARD_FAB2_LIB.BASEBOARD_FAB2(SCH_1):PAGE38',
 SEC_TYPE='BGA1',
 MATERIAL='IC',
 PHYS_PAGE='38',
 XY='(-1950,2650)',
 ROT='0',
 VER='20',
 PACK_TYPE='BGA1',
 PART_NUMBER='TBD',
 LOCATION='U5D1',
 ROOM='CPU0',
 SEC='20',
 CDS_LIB='chpset_lib',
 CDS_PART_NAME='SKX_EXT_B_BGA1-IC,TBD',
 PRIM_FILE='./archive_libs/logical/skx_ext_b/chips/chips.prt';

SECTION_NUMBER 21
 '@BASEBOARD_FAB2_LIB.BASEBOARD_FAB2(SCH_1):PAGE38_I34@CHPSET_LIB.SKX_EXT_B(CHIPS)':
 C_PATH='@baseboard_fab2_lib.baseboard_fab2(sch_1):page38_i34@chpset_lib.skx_ext~
_b(chips)',
 P_PATH='@baseboard_fab2_lib.baseboard_fab2(sch_1):page38_i34@chpset_lib.skx_ext~
_b(chips)',
 PATH='I34',
 DRAWING='@BASEBOARD_FAB2_LIB.BASEBOARD_FAB2(SCH_1):PAGE38',
 SEC_TYPE='BGA1',
 MATERIAL='IC',
 PHYS_PAGE='38',
 XY='(1050,2725)',
 ROT='0',
 VER='21',
 PACK_TYPE='BGA1',
 PART_NUMBER='TBD',
 LOCATION='U5D1',
 ROOM='CPU0',
 SEC='21',
 CDS_LIB='chpset_lib',
 CDS_PART_NAME='SKX_EXT_B_BGA1-IC,TBD',
 PRIM_FILE='./archive_libs/logical/skx_ext_b/chips/chips.prt';

SECTION_NUMBER 22
 '@BASEBOARD_FAB2_LIB.BASEBOARD_FAB2(SCH_1):PAGE39_I127@CHPSET_LIB.SKX_EXT_B(CHIPS)':
 C_PATH='@baseboard_fab2_lib.baseboard_fab2(sch_1):page39_i127@chpset_lib.skx_ex~
t_b(chips)',
 P_PATH='@baseboard_fab2_lib.baseboard_fab2(sch_1):page39_i127@chpset_lib.skx_ex~
t_b(chips)',
 PATH='I127',
 DRAWING='@BASEBOARD_FAB2_LIB.BASEBOARD_FAB2(SCH_1):PAGE39',
 SEC_TYPE='BGA1',
 MATERIAL='IC',
 PHYS_PAGE='39',
 XY='(-4250,2550)',
 ROT='0',
 VER='22',
 PACK_TYPE='BGA1',
 PART_NUMBER='TBD',
 LOCATION='U5D1',
 ROOM='CPU0',
 SEC='22',
 CDS_LIB='chpset_lib',
 CDS_PART_NAME='SKX_EXT_B_BGA1-IC,TBD',
 PRIM_FILE='./archive_libs/logical/skx_ext_b/chips/chips.prt';

SECTION_NUMBER 23
 '@BASEBOARD_FAB2_LIB.BASEBOARD_FAB2(SCH_1):PAGE40_I20@CHPSET_LIB.SKX_EXT_B(CHIPS)':
 C_PATH='@baseboard_fab2_lib.baseboard_fab2(sch_1):page40_i20@chpset_lib.skx_ext~
_b(chips)',
 P_PATH='@baseboard_fab2_lib.baseboard_fab2(sch_1):page40_i20@chpset_lib.skx_ext~
_b(chips)',
 PATH='I20',
 DRAWING='@BASEBOARD_FAB2_LIB.BASEBOARD_FAB2(SCH_1):PAGE40',
 SEC_TYPE='BGA1',
 MATERIAL='IC',
 PHYS_PAGE='40',
 XY='(-7050,2575)',
 ROT='0',
 VER='23',
 PACK_TYPE='BGA1',
 PART_NUMBER='TBD',
 LOCATION='U5D1',
 ROOM='CPU0',
 SEC='23',
 CDS_LIB='chpset_lib',
 CDS_PART_NAME='SKX_EXT_B_BGA1-IC,TBD',
 PRIM_FILE='./archive_libs/logical/skx_ext_b/chips/chips.prt';

SECTION_NUMBER 24
 '@BASEBOARD_FAB2_LIB.BASEBOARD_FAB2(SCH_1):PAGE40_I21@CHPSET_LIB.SKX_EXT_B(CHIPS)':
 C_PATH='@baseboard_fab2_lib.baseboard_fab2(sch_1):page40_i21@chpset_lib.skx_ext~
_b(chips)',
 P_PATH='@baseboard_fab2_lib.baseboard_fab2(sch_1):page40_i21@chpset_lib.skx_ext~
_b(chips)',
 PATH='I21',
 DRAWING='@BASEBOARD_FAB2_LIB.BASEBOARD_FAB2(SCH_1):PAGE40',
 SEC_TYPE='BGA1',
 MATERIAL='IC',
 PHYS_PAGE='40',
 XY='(-5225,2575)',
 ROT='0',
 VER='24',
 PACK_TYPE='BGA1',
 PART_NUMBER='TBD',
 LOCATION='U5D1',
 ROOM='CPU0',
 SEC='24',
 CDS_LIB='chpset_lib',
 CDS_PART_NAME='SKX_EXT_B_BGA1-IC,TBD',
 PRIM_FILE='./archive_libs/logical/skx_ext_b/chips/chips.prt';

SECTION_NUMBER 25
 '@BASEBOARD_FAB2_LIB.BASEBOARD_FAB2(SCH_1):PAGE40_I22@CHPSET_LIB.SKX_EXT_B(CHIPS)':
 C_PATH='@baseboard_fab2_lib.baseboard_fab2(sch_1):page40_i22@chpset_lib.skx_ext~
_b(chips)',
 P_PATH='@baseboard_fab2_lib.baseboard_fab2(sch_1):page40_i22@chpset_lib.skx_ext~
_b(chips)',
 PATH='I22',
 DRAWING='@BASEBOARD_FAB2_LIB.BASEBOARD_FAB2(SCH_1):PAGE40',
 SEC_TYPE='BGA1',
 MATERIAL='IC',
 PHYS_PAGE='40',
 XY='(-3400,2575)',
 ROT='0',
 VER='25',
 PACK_TYPE='BGA1',
 PART_NUMBER='TBD',
 LOCATION='U5D1',
 ROOM='CPU0',
 SEC='25',
 CDS_LIB='chpset_lib',
 CDS_PART_NAME='SKX_EXT_B_BGA1-IC,TBD',
 PRIM_FILE='./archive_libs/logical/skx_ext_b/chips/chips.prt';

SECTION_NUMBER 26
 '@BASEBOARD_FAB2_LIB.BASEBOARD_FAB2(SCH_1):PAGE40_I23@CHPSET_LIB.SKX_EXT_B(CHIPS)':
 C_PATH='@baseboard_fab2_lib.baseboard_fab2(sch_1):page40_i23@chpset_lib.skx_ext~
_b(chips)',
 P_PATH='@baseboard_fab2_lib.baseboard_fab2(sch_1):page40_i23@chpset_lib.skx_ext~
_b(chips)',
 PATH='I23',
 DRAWING='@BASEBOARD_FAB2_LIB.BASEBOARD_FAB2(SCH_1):PAGE40',
 SEC_TYPE='BGA1',
 MATERIAL='IC',
 PHYS_PAGE='40',
 XY='(-1550,2575)',
 ROT='0',
 VER='26',
 PACK_TYPE='BGA1',
 PART_NUMBER='TBD',
 LOCATION='U5D1',
 ROOM='CPU0',
 SEC='26',
 CDS_LIB='chpset_lib',
 CDS_PART_NAME='SKX_EXT_B_BGA1-IC,TBD',
 PRIM_FILE='./archive_libs/logical/skx_ext_b/chips/chips.prt';

SECTION_NUMBER 27
 '@BASEBOARD_FAB2_LIB.BASEBOARD_FAB2(SCH_1):PAGE41_I283@CHPSET_LIB.SKX_EXT_B(CHIPS)':
 C_PATH='@baseboard_fab2_lib.baseboard_fab2(sch_1):page41_i283@chpset_lib.skx_ex~
t_b(chips)',
 P_PATH='@baseboard_fab2_lib.baseboard_fab2(sch_1):page41_i283@chpset_lib.skx_ex~
t_b(chips)',
 PATH='I283',
 DRAWING='@BASEBOARD_FAB2_LIB.BASEBOARD_FAB2(SCH_1):PAGE41',
 SEC_TYPE='BGA1',
 MATERIAL='IC',
 PHYS_PAGE='41',
 XY='(-5275,2650)',
 ROT='0',
 VER='27',
 PACK_TYPE='BGA1',
 PART_NUMBER='TBD',
 LOCATION='U5D1',
 ROOM='CPU0',
 SEC='27',
 CDS_LIB='chpset_lib',
 CDS_PART_NAME='SKX_EXT_B_BGA1-IC,TBD',
 PRIM_FILE='./archive_libs/logical/skx_ext_b/chips/chips.prt';

SECTION_NUMBER 28
 '@BASEBOARD_FAB2_LIB.BASEBOARD_FAB2(SCH_1):PAGE41_I284@CHPSET_LIB.SKX_EXT_B(CHIPS)':
 C_PATH='@baseboard_fab2_lib.baseboard_fab2(sch_1):page41_i284@chpset_lib.skx_ex~
t_b(chips)',
 P_PATH='@baseboard_fab2_lib.baseboard_fab2(sch_1):page41_i284@chpset_lib.skx_ex~
t_b(chips)',
 PATH='I284',
 DRAWING='@BASEBOARD_FAB2_LIB.BASEBOARD_FAB2(SCH_1):PAGE41',
 SEC_TYPE='BGA1',
 MATERIAL='IC',
 PHYS_PAGE='41',
 XY='(-3575,2650)',
 ROT='0',
 VER='28',
 PACK_TYPE='BGA1',
 PART_NUMBER='TBD',
 LOCATION='U5D1',
 ROOM='CPU0',
 SEC='28',
 CDS_LIB='chpset_lib',
 CDS_PART_NAME='SKX_EXT_B_BGA1-IC,TBD',
 PRIM_FILE='./archive_libs/logical/skx_ext_b/chips/chips.prt';

SECTION_NUMBER 29
 '@BASEBOARD_FAB2_LIB.BASEBOARD_FAB2(SCH_1):PAGE41_I285@CHPSET_LIB.SKX_EXT_B(CHIPS)':
 C_PATH='@baseboard_fab2_lib.baseboard_fab2(sch_1):page41_i285@chpset_lib.skx_ex~
t_b(chips)',
 P_PATH='@baseboard_fab2_lib.baseboard_fab2(sch_1):page41_i285@chpset_lib.skx_ex~
t_b(chips)',
 PATH='I285',
 DRAWING='@BASEBOARD_FAB2_LIB.BASEBOARD_FAB2(SCH_1):PAGE41',
 SEC_TYPE='BGA1',
 MATERIAL='IC',
 PHYS_PAGE='41',
 XY='(-1850,2600)',
 ROT='0',
 VER='29',
 PACK_TYPE='BGA1',
 PART_NUMBER='TBD',
 LOCATION='U5D1',
 ROOM='CPU0',
 SEC='29',
 CDS_LIB='chpset_lib',
 CDS_PART_NAME='SKX_EXT_B_BGA1-IC,TBD',
 PRIM_FILE='./archive_libs/logical/skx_ext_b/chips/chips.prt';

SECTION_NUMBER 30
 '@BASEBOARD_FAB2_LIB.BASEBOARD_FAB2(SCH_1):PAGE41_I286@CHPSET_LIB.SKX_EXT_B(CHIPS)':
 C_PATH='@baseboard_fab2_lib.baseboard_fab2(sch_1):page41_i286@chpset_lib.skx_ex~
t_b(chips)',
 P_PATH='@baseboard_fab2_lib.baseboard_fab2(sch_1):page41_i286@chpset_lib.skx_ex~
t_b(chips)',
 PATH='I286',
 DRAWING='@BASEBOARD_FAB2_LIB.BASEBOARD_FAB2(SCH_1):PAGE41',
 SEC_TYPE='BGA1',
 MATERIAL='IC',
 PHYS_PAGE='41',
 XY='(-175,2650)',
 ROT='0',
 VER='30',
 PACK_TYPE='BGA1',
 PART_NUMBER='TBD',
 LOCATION='U5D1',
 ROOM='CPU0',
 SEC='30',
 CDS_LIB='chpset_lib',
 CDS_PART_NAME='SKX_EXT_B_BGA1-IC,TBD',
 PRIM_FILE='./archive_libs/logical/skx_ext_b/chips/chips.prt';

PART_NAME
 U6F1 'PCA9617_SSOP-IC,G81764-001-GNDA':
 ROOM='MEM';

SECTION_NUMBER 1
 '@BASEBOARD_FAB2_LIB.BASEBOARD_FAB2(SCH_1):PAGE99_I15@MSTR_DIGITAL.PCA9617(CHIPS)':
 C_PATH='@baseboard_fab2_lib.baseboard_fab2(sch_1):page99_i15@mstr_digital.pca96~
17(chips)',
 P_PATH='@baseboard_fab2_lib.baseboard_fab2(sch_1):page99_i15@mstr_digital.pca96~
17(chips)',
 PATH='I15',
 DRAWING='@BASEBOARD_FAB2_LIB.BASEBOARD_FAB2(SCH_1):PAGE99',
 POWER_GROUP='GND=GND',
 MATERIAL='IC',
 BOM_COST='SM_CONTROLLER',
 PHYS_PAGE='99',
 XY='(150,4300)',
 ROT='0',
 VER='1',
 PACK_TYPE='SSOP',
 PART_NUMBER='G81764-001',
 LOCATION='U6F1',
 ROOM='MEM',
 CDS_LIB='mstr_digital',
 CDS_PART_NAME='PCA9617_SSOP-IC,G81764-001',
 PRIM_FILE='./archive_libs/mstr_digital/pca9617/chips/chips.prt';

PART_NAME
 U6M1 '74CBTLV1G125_SMLF-IC,C88177-00A':
 ROOM='DEBUG';

SECTION_NUMBER 1
 '@BASEBOARD_FAB2_LIB.BASEBOARD_FAB2(SCH_1):PAGE113_I190@MSTR_TTL.74CBTLV1G125(CHIPS)':
 C_PATH='@baseboard_fab2_lib.baseboard_fab2(sch_1):page113_i190@mstr_ttl.\74cbtl~
v1g125\(chips)',
 P_PATH='@baseboard_fab2_lib.baseboard_fab2(sch_1):page113_i190@mstr_ttl.\74cbtl~
v1g125\(chips)',
 PATH='I190',
 DRAWING='@BASEBOARD_FAB2_LIB.BASEBOARD_FAB2(SCH_1):PAGE113',
 POWER_GROUP='GND=GND;VCC=P3V3_STBY',
 POP='NOPOP',
 SEC_TYPE='SMLF',
 MATERIAL='IC',
 BOM_COST='DEBUG',
 PHYS_PAGE='113',
 XY='(1600,2000)',
 ROT='0',
 VER='1',
 PACK_TYPE='SMLF',
 PART_NUMBER='C88177-001',
 LOCATION='U6M1',
 ROOM='DEBUG',
 SEC='1',
 CDS_LIB='mstr_ttl',
 CDS_PART_NAME='74CBTLV1G125_SMLF-IC,C88177-00A',
 PRIM_FILE='./archive_libs/mstr_ttl/74cbtlv1g125/chips/chips.prt';

PART_NAME
 U6W1 'TCA9555PWR-GP_DISCRET-GC1-TCA9A':;

SECTION_NUMBER 1
 '@BASEBOARD_FAB2_LIB.BASEBOARD_FAB2(SCH_1):PAGE247_I120@W_HDL.TCA9555PWR-GP(CHIPS)':
 C_PATH='@baseboard_fab2_lib.baseboard_fab2(sch_1):page247_i120@w_hdl.\tca9555pw~
r-gp\(chips)',
 P_PATH='@baseboard_fab2_lib.baseboard_fab2(sch_1):page247_i120@w_hdl.\tca9555pw~
r-gp\(chips)',
 PATH='I120',
 DRAWING='@BASEBOARD_FAB2_LIB.BASEBOARD_FAB2(SCH_1):PAGE247',
 SEC_TYPE='DISCRET-GC1',
 PHYS_PAGE='247',
 XY='(-3950,3675)',
 ROT='0',
 VER='1',
 VALUE='TCA9555PWR-GP',
 PACK_TYPE='DISCRET-GC1',
 PART_NUMBER='071.09555.000W',
 LOCATION='U6W1',
 SEC='1',
 CDS_LIB='w_hdl',
 CDS_PART_NAME='TCA9555PWR-GP_DISCRET-GC1-TCA9A',
 PRIM_FILE='C:/<user>/w_hdl/tca9555pwr#2dgp/chips/chips.prt';

PART_NAME
 U6W2 'TCA9517DGKR-GP_DISCRET-G8-TCA9A':;

SECTION_NUMBER 1
 '@BASEBOARD_FAB2_LIB.BASEBOARD_FAB2(SCH_1):PAGE247_I118@W_HDL.TCA9517DGKR-GP(CHIPS)':
 C_PATH='@baseboard_fab2_lib.baseboard_fab2(sch_1):page247_i118@w_hdl.\tca9517dg~
kr-gp\(chips)',
 P_PATH='@baseboard_fab2_lib.baseboard_fab2(sch_1):page247_i118@w_hdl.\tca9517dg~
kr-gp\(chips)',
 PATH='I118',
 DRAWING='@BASEBOARD_FAB2_LIB.BASEBOARD_FAB2(SCH_1):PAGE247',
 SEC_TYPE='DISCRET-G8',
 PHYS_PAGE='247',
 XY='(-6375,925)',
 ROT='0',
 VER='1',
 VALUE='TCA9517DGKR-GP',
 PACK_TYPE='DISCRET-G8',
 PART_NUMBER='071.09517.0009',
 LOCATION='U6W2',
 SEC='1',
 CDS_LIB='w_hdl',
 CDS_PART_NAME='TCA9517DGKR-GP_DISCRET-G8-TCA9A',
 PRIM_FILE='C:/<user>/w_hdl/tca9517dgkr#2dgp/chips/chips.prt';

PART_NAME
 U6W3 'AT24C64_SOICLF-IC,C47049-001-GA':
 ROOM='TEMP_SENSORS';

SECTION_NUMBER 1
 '@BASEBOARD_FAB2_LIB.BASEBOARD_FAB2(SCH_1):PAGE247_I89@MSTR_MEMORY.AT24C64(CHIPS)':
 C_PATH='@baseboard_fab2_lib.baseboard_fab2(sch_1):page247_i89@mstr_memory.at24c~
64(chips)',
 P_PATH='@baseboard_fab2_lib.baseboard_fab2(sch_1):page247_i89@mstr_memory.at24c~
64(chips)',
 PATH='I89',
 DRAWING='@BASEBOARD_FAB2_LIB.BASEBOARD_FAB2(SCH_1):PAGE247',
 POWER_GROUP='GND=GND;VCC=P3V3_STBY',
 SEC_TYPE='SOICLF',
 MATERIAL='IC',
 BOM_COST='SM_THERM',
 PHYS_PAGE='247',
 XY='(-2200,1850)',
 ROT='0',
 VER='1',
 PACK_TYPE='SOICLF',
 PART_NUMBER='C47049-001',
 LOCATION='U6W3',
 ROOM='TEMP_SENSORS',
 SEC='1',
 CDS_LIB='mstr_memory',
 CDS_PART_NAME='AT24C64_SOICLF-IC,C47049-001-VA',
 PRIM_FILE='./archive_libs/mstr_memory/at24c64/chips/chips.prt';

PART_NAME
 U6W4 'TTL1G126_A_SOT-74HC1G126,IC,A7B':
 ROOM='SB';

SECTION_NUMBER 1
 '@BASEBOARD_FAB2_LIB.BASEBOARD_FAB2(SCH_1):PAGE176_I146@MSTR_TTL.TTL1G126_A(CHIPS)':
 C_PATH='@baseboard_fab2_lib.baseboard_fab2(sch_1):page176_i146@mstr_ttl.ttl1g12~
6_a(chips)',
 P_PATH='@baseboard_fab2_lib.baseboard_fab2(sch_1):page176_i146@mstr_ttl.ttl1g12~
6_a(chips)',
 PATH='I146',
 DRAWING='@BASEBOARD_FAB2_LIB.BASEBOARD_FAB2(SCH_1):PAGE176',
 POWER_GROUP='GND=GND;VCC=P3V3_STBY',
 SEC_TYPE='SOT',
 MATERIAL='IC',
 BOM_COST='SB',
 PHYS_PAGE='176',
 XY='(-2500,1400)',
 ROT='6',
 VER='1',
 VALUE='74HC1G126',
 PACK_TYPE='SOT',
 PART_NUMBER='A79322-001',
 LOCATION='U6W4',
 ROOM='SB',
 SEC='1',
 CDS_LIB='mstr_ttl',
 CDS_PART_NAME='TTL1G126_A_SOT-74HC1G126,IC,A7B',
 PRIM_FILE='./archive_libs/mstr_ttl/ttl1g126_a/chips/chips.prt';

PART_NAME
 U6W5 'TTL1G126_A_SOT-74HC1G126,IC,A7B':
 ROOM='SB';

SECTION_NUMBER 1
 '@BASEBOARD_FAB2_LIB.BASEBOARD_FAB2(SCH_1):PAGE176_I148@MSTR_TTL.TTL1G126_A(CHIPS)':
 C_PATH='@baseboard_fab2_lib.baseboard_fab2(sch_1):page176_i148@mstr_ttl.ttl1g12~
6_a(chips)',
 P_PATH='@baseboard_fab2_lib.baseboard_fab2(sch_1):page176_i148@mstr_ttl.ttl1g12~
6_a(chips)',
 PATH='I148',
 DRAWING='@BASEBOARD_FAB2_LIB.BASEBOARD_FAB2(SCH_1):PAGE176',
 POWER_GROUP='GND=GND;VCC=P3V3_STBY',
 SEC_TYPE='SOT',
 MATERIAL='IC',
 BOM_COST='SB',
 PHYS_PAGE='176',
 XY='(-1550,3150)',
 ROT='6',
 VER='1',
 VALUE='74HC1G126',
 PACK_TYPE='SOT',
 PART_NUMBER='A79322-001',
 LOCATION='U6W5',
 ROOM='SB',
 SEC='1',
 CDS_LIB='mstr_ttl',
 CDS_PART_NAME='TTL1G126_A_SOT-74HC1G126,IC,A7B',
 PRIM_FILE='./archive_libs/mstr_ttl/ttl1g126_a/chips/chips.prt';

PART_NAME
 U6W6 'TTL1G126_A_SOT-74HC1G126,IC,A7B':
 ROOM='SB';

SECTION_NUMBER 1
 '@BASEBOARD_FAB2_LIB.BASEBOARD_FAB2(SCH_1):PAGE176_I157@MSTR_TTL.TTL1G126_A(CHIPS)':
 C_PATH='@baseboard_fab2_lib.baseboard_fab2(sch_1):page176_i157@mstr_ttl.ttl1g12~
6_a(chips)',
 P_PATH='@baseboard_fab2_lib.baseboard_fab2(sch_1):page176_i157@mstr_ttl.ttl1g12~
6_a(chips)',
 PATH='I157',
 DRAWING='@BASEBOARD_FAB2_LIB.BASEBOARD_FAB2(SCH_1):PAGE176',
 POWER_GROUP='GND=GND;VCC=P3V3_STBY',
 SEC_TYPE='SOT',
 MATERIAL='IC',
 BOM_COST='SB',
 PHYS_PAGE='176',
 XY='(-1550,2600)',
 ROT='6',
 VER='1',
 VALUE='74HC1G126',
 PACK_TYPE='SOT',
 PART_NUMBER='A79322-001',
 LOCATION='U6W6',
 ROOM='SB',
 SEC='1',
 CDS_LIB='mstr_ttl',
 CDS_PART_NAME='TTL1G126_A_SOT-74HC1G126,IC,A7B',
 PRIM_FILE='./archive_libs/mstr_ttl/ttl1g126_a/chips/chips.prt';

PART_NAME
 U6W11 'PCA9554PWR-GP_DISCRET-G1-PCA95A':;

SECTION_NUMBER 1
 '@BASEBOARD_FAB2_LIB.BASEBOARD_FAB2(SCH_1):PAGE164_I97@W_HDL.PCA9554PWR-GP(CHIPS)':
 C_PATH='@baseboard_fab2_lib.baseboard_fab2(sch_1):page164_i97@w_hdl.\pca9554pwr~
-gp\(chips)',
 P_PATH='@baseboard_fab2_lib.baseboard_fab2(sch_1):page164_i97@w_hdl.\pca9554pwr~
-gp\(chips)',
 PATH='I97',
 DRAWING='@BASEBOARD_FAB2_LIB.BASEBOARD_FAB2(SCH_1):PAGE164',
 SEC_TYPE='DISCRET-G1',
 PHYS_PAGE='164',
 XY='(-2150,3500)',
 ROT='0',
 VER='1',
 VALUE='PCA9554PWR-GP',
 PACK_TYPE='DISCRET-G1',
 PART_NUMBER='71.09554.C0W',
 LOCATION='U6W11',
 SEC='1',
 CDS_LIB='w_hdl',
 CDS_PART_NAME='PCA9554PWR-GP_DISCRET-G1-PCA95A',
 PRIM_FILE='C:/<user>/w_hdl/pca9554pwr#2dgp/chips/chips.prt';

PART_NAME
 U6W12 'NC7SB3157_SMLF-IC,C99406-001':
 ROOM='DEBUG';

SECTION_NUMBER 1
 '@BASEBOARD_FAB2_LIB.BASEBOARD_FAB2(SCH_1):PAGE176_I182@MSTR_ANALOG.NC7SB3157(CHIPS)':
 C_PATH='@baseboard_fab2_lib.baseboard_fab2(sch_1):page176_i182@mstr_analog.nc7s~
b3157(chips)',
 P_PATH='@baseboard_fab2_lib.baseboard_fab2(sch_1):page176_i182@mstr_analog.nc7s~
b3157(chips)',
 PATH='I182',
 DRAWING='@BASEBOARD_FAB2_LIB.BASEBOARD_FAB2(SCH_1):PAGE176',
 MATERIAL='IC',
 BOM_COST='DEBUG',
 PHYS_PAGE='176',
 XY='(-750,1850)',
 ROT='0',
 VER='1',
 PACK_TYPE='SMLF',
 PART_NUMBER='C99406-001',
 LOCATION='U6W12',
 ROOM='DEBUG',
 CDS_LIB='mstr_analog',
 CDS_PART_NAME='NC7SB3157_SMLF-IC,C99406-001',
 PRIM_FILE='./archive_libs/mstr_analog/nc7sb3157/chips/chips.prt';

PART_NAME
 U7C1 'LBG_CORE_QAT_EXT_D_BGA1-IC,H91A':
 ROOM='SB';

SECTION_NUMBER 1
 '@BASEBOARD_FAB2_LIB.BASEBOARD_FAB2(SCH_1):PAGE114_I40@MSTR_U_PROC.LBG_CORE_QAT_EXT_D(CHIPS)':
 C_PATH='@baseboard_fab2_lib.baseboard_fab2(sch_1):page114_i40@mstr_u_proc.lbg_c~
ore_qat_ext_d(chips)',
 P_PATH='@baseboard_fab2_lib.baseboard_fab2(sch_1):page114_i40@mstr_u_proc.lbg_c~
ore_qat_ext_d(chips)',
 PATH='I40',
 DRAWING='@BASEBOARD_FAB2_LIB.BASEBOARD_FAB2(SCH_1):PAGE114',
 SEC_TYPE='BGA1',
 MATERIAL='IC',
 BOM_COST='SB',
 PHYS_PAGE='114',
 XY='(525,2150)',
 ROT='0',
 VER='1',
 PACK_TYPE='BGA1',
 PART_NUMBER='H91415-002',
 LOCATION='U7C1',
 ROOM='SB',
 SEC='1',
 CDS_LIB='mstr_u_proc',
 CDS_PART_NAME='LBG_CORE_QAT_EXT_D_BGA1-IC,H91A',
 PRIM_FILE='./archive_libs/mstr_u_proc/lbg_core_qat_ext_d/chips/chips.prt';

SECTION_NUMBER 2
 '@BASEBOARD_FAB2_LIB.BASEBOARD_FAB2(SCH_1):PAGE115_I74@MSTR_U_PROC.LBG_CORE_QAT_EXT_D(CHIPS)':
 C_PATH='@baseboard_fab2_lib.baseboard_fab2(sch_1):page115_i74@mstr_u_proc.lbg_c~
ore_qat_ext_d(chips)',
 P_PATH='@baseboard_fab2_lib.baseboard_fab2(sch_1):page115_i74@mstr_u_proc.lbg_c~
ore_qat_ext_d(chips)',
 PATH='I74',
 DRAWING='@BASEBOARD_FAB2_LIB.BASEBOARD_FAB2(SCH_1):PAGE115',
 SEC_TYPE='BGA1',
 MATERIAL='IC',
 BOM_COST='SB',
 PHYS_PAGE='115',
 XY='(-4000,2500)',
 ROT='0',
 VER='2',
 PACK_TYPE='BGA1',
 PART_NUMBER='H91415-002',
 LOCATION='U7C1',
 ROOM='SB',
 SEC='2',
 CDS_LIB='mstr_u_proc',
 CDS_PART_NAME='LBG_CORE_QAT_EXT_D_BGA1-IC,H91A',
 PRIM_FILE='./archive_libs/mstr_u_proc/lbg_core_qat_ext_d/chips/chips.prt';

SECTION_NUMBER 3
 '@BASEBOARD_FAB2_LIB.BASEBOARD_FAB2(SCH_1):PAGE116_I220@MSTR_U_PROC.LBG_CORE_QAT_EXT_D(CHIPS)':
 C_PATH='@baseboard_fab2_lib.baseboard_fab2(sch_1):page116_i220@mstr_u_proc.lbg_~
core_qat_ext_d(chips)',
 P_PATH='@baseboard_fab2_lib.baseboard_fab2(sch_1):page116_i220@mstr_u_proc.lbg_~
core_qat_ext_d(chips)',
 PATH='I220',
 DRAWING='@BASEBOARD_FAB2_LIB.BASEBOARD_FAB2(SCH_1):PAGE116',
 SEC_TYPE='BGA1',
 MATERIAL='IC',
 BOM_COST='SB',
 PHYS_PAGE='116',
 XY='(-4025,2850)',
 ROT='0',
 VER='3',
 PACK_TYPE='BGA1',
 PART_NUMBER='H91415-002',
 LOCATION='U7C1',
 ROOM='SB',
 SEC='3',
 CDS_LIB='mstr_u_proc',
 CDS_PART_NAME='LBG_CORE_QAT_EXT_D_BGA1-IC,H91A',
 PRIM_FILE='./archive_libs/mstr_u_proc/lbg_core_qat_ext_d/chips/chips.prt';

SECTION_NUMBER 4
 '@BASEBOARD_FAB2_LIB.BASEBOARD_FAB2(SCH_1):PAGE117_I9@MSTR_U_PROC.LBG_CORE_QAT_EXT_D(CHIPS)':
 C_PATH='@baseboard_fab2_lib.baseboard_fab2(sch_1):page117_i9@mstr_u_proc.lbg_co~
re_qat_ext_d(chips)',
 P_PATH='@baseboard_fab2_lib.baseboard_fab2(sch_1):page117_i9@mstr_u_proc.lbg_co~
re_qat_ext_d(chips)',
 PATH='I9',
 DRAWING='@BASEBOARD_FAB2_LIB.BASEBOARD_FAB2(SCH_1):PAGE117',
 SEC_TYPE='BGA1',
 MATERIAL='IC',
 BOM_COST='SB',
 PHYS_PAGE='117',
 XY='(-3925,2150)',
 ROT='0',
 VER='4',
 PACK_TYPE='BGA1',
 PART_NUMBER='H91415-002',
 LOCATION='U7C1',
 ROOM='SB',
 SEC='4',
 CDS_LIB='mstr_u_proc',
 CDS_PART_NAME='LBG_CORE_QAT_EXT_D_BGA1-IC,H91A',
 PRIM_FILE='./archive_libs/mstr_u_proc/lbg_core_qat_ext_d/chips/chips.prt';

SECTION_NUMBER 5
 '@BASEBOARD_FAB2_LIB.BASEBOARD_FAB2(SCH_1):PAGE118_I73@MSTR_U_PROC.LBG_CORE_QAT_EXT_D(CHIPS)':
 C_PATH='@baseboard_fab2_lib.baseboard_fab2(sch_1):page118_i73@mstr_u_proc.lbg_c~
ore_qat_ext_d(chips)',
 P_PATH='@baseboard_fab2_lib.baseboard_fab2(sch_1):page118_i73@mstr_u_proc.lbg_c~
ore_qat_ext_d(chips)',
 PATH='I73',
 DRAWING='@BASEBOARD_FAB2_LIB.BASEBOARD_FAB2(SCH_1):PAGE118',
 SEC_TYPE='BGA1',
 MATERIAL='IC',
 BOM_COST='SB',
 PHYS_PAGE='118',
 XY='(-4025,3025)',
 ROT='0',
 VER='5',
 PACK_TYPE='BGA1',
 PART_NUMBER='H91415-002',
 LOCATION='U7C1',
 ROOM='SB',
 SEC='5',
 CDS_LIB='mstr_u_proc',
 CDS_PART_NAME='LBG_CORE_QAT_EXT_D_BGA1-IC,H91A',
 PRIM_FILE='./archive_libs/mstr_u_proc/lbg_core_qat_ext_d/chips/chips.prt';

SECTION_NUMBER 6
 '@BASEBOARD_FAB2_LIB.BASEBOARD_FAB2(SCH_1):PAGE119_I115@MSTR_U_PROC.LBG_CORE_QAT_EXT_D(CHIPS)':
 C_PATH='@baseboard_fab2_lib.baseboard_fab2(sch_1):page119_i115@mstr_u_proc.lbg_~
core_qat_ext_d(chips)',
 P_PATH='@baseboard_fab2_lib.baseboard_fab2(sch_1):page119_i115@mstr_u_proc.lbg_~
core_qat_ext_d(chips)',
 PATH='I115',
 DRAWING='@BASEBOARD_FAB2_LIB.BASEBOARD_FAB2(SCH_1):PAGE119',
 SEC_TYPE='BGA1',
 MATERIAL='IC',
 BOM_COST='SB',
 PHYS_PAGE='119',
 XY='(-4100,3200)',
 ROT='0',
 VER='6',
 PACK_TYPE='BGA1',
 PART_NUMBER='H91415-002',
 LOCATION='U7C1',
 ROOM='SB',
 SEC='6',
 CDS_LIB='mstr_u_proc',
 CDS_PART_NAME='LBG_CORE_QAT_EXT_D_BGA1-IC,H91A',
 PRIM_FILE='./archive_libs/mstr_u_proc/lbg_core_qat_ext_d/chips/chips.prt';

SECTION_NUMBER 7
 '@BASEBOARD_FAB2_LIB.BASEBOARD_FAB2(SCH_1):PAGE120_I147@MSTR_U_PROC.LBG_CORE_QAT_EXT_D(CHIPS)':
 C_PATH='@baseboard_fab2_lib.baseboard_fab2(sch_1):page120_i147@mstr_u_proc.lbg_~
core_qat_ext_d(chips)',
 P_PATH='@baseboard_fab2_lib.baseboard_fab2(sch_1):page120_i147@mstr_u_proc.lbg_~
core_qat_ext_d(chips)',
 PATH='I147',
 DRAWING='@BASEBOARD_FAB2_LIB.BASEBOARD_FAB2(SCH_1):PAGE120',
 SEC_TYPE='BGA1',
 MATERIAL='IC',
 BOM_COST='SB',
 PHYS_PAGE='120',
 XY='(-3750,2800)',
 ROT='0',
 VER='7',
 PACK_TYPE='BGA1',
 PART_NUMBER='H91415-002',
 LOCATION='U7C1',
 ROOM='SB',
 SEC='7',
 CDS_LIB='mstr_u_proc',
 CDS_PART_NAME='LBG_CORE_QAT_EXT_D_BGA1-IC,H91A',
 PRIM_FILE='./archive_libs/mstr_u_proc/lbg_core_qat_ext_d/chips/chips.prt';

SECTION_NUMBER 8
 '@BASEBOARD_FAB2_LIB.BASEBOARD_FAB2(SCH_1):PAGE121_I34@MSTR_U_PROC.LBG_CORE_QAT_EXT_D(CHIPS)':
 C_PATH='@baseboard_fab2_lib.baseboard_fab2(sch_1):page121_i34@mstr_u_proc.lbg_c~
ore_qat_ext_d(chips)',
 P_PATH='@baseboard_fab2_lib.baseboard_fab2(sch_1):page121_i34@mstr_u_proc.lbg_c~
ore_qat_ext_d(chips)',
 PATH='I34',
 DRAWING='@BASEBOARD_FAB2_LIB.BASEBOARD_FAB2(SCH_1):PAGE121',
 SEC_TYPE='BGA1',
 MATERIAL='IC',
 BOM_COST='SB',
 PHYS_PAGE='121',
 XY='(-4050,2800)',
 ROT='0',
 VER='8',
 PACK_TYPE='BGA1',
 PART_NUMBER='H91415-002',
 LOCATION='U7C1',
 ROOM='SB',
 SEC='8',
 CDS_LIB='mstr_u_proc',
 CDS_PART_NAME='LBG_CORE_QAT_EXT_D_BGA1-IC,H91A',
 PRIM_FILE='./archive_libs/mstr_u_proc/lbg_core_qat_ext_d/chips/chips.prt';

SECTION_NUMBER 9
 '@BASEBOARD_FAB2_LIB.BASEBOARD_FAB2(SCH_1):PAGE122_I63@MSTR_U_PROC.LBG_CORE_QAT_EXT_D(CHIPS)':
 C_PATH='@baseboard_fab2_lib.baseboard_fab2(sch_1):page122_i63@mstr_u_proc.lbg_c~
ore_qat_ext_d(chips)',
 P_PATH='@baseboard_fab2_lib.baseboard_fab2(sch_1):page122_i63@mstr_u_proc.lbg_c~
ore_qat_ext_d(chips)',
 PATH='I63',
 DRAWING='@BASEBOARD_FAB2_LIB.BASEBOARD_FAB2(SCH_1):PAGE122',
 SEC_TYPE='BGA1',
 MATERIAL='IC',
 BOM_COST='SB',
 PHYS_PAGE='122',
 XY='(-3900,3075)',
 ROT='0',
 VER='9',
 PACK_TYPE='BGA1',
 PART_NUMBER='H91415-002',
 LOCATION='U7C1',
 ROOM='SB',
 SEC='9',
 CDS_LIB='mstr_u_proc',
 CDS_PART_NAME='LBG_CORE_QAT_EXT_D_BGA1-IC,H91A',
 PRIM_FILE='./archive_libs/mstr_u_proc/lbg_core_qat_ext_d/chips/chips.prt';

SECTION_NUMBER 10
 '@BASEBOARD_FAB2_LIB.BASEBOARD_FAB2(SCH_1):PAGE123_I21@MSTR_U_PROC.LBG_CORE_QAT_EXT_D(CHIPS)':
 C_PATH='@baseboard_fab2_lib.baseboard_fab2(sch_1):page123_i21@mstr_u_proc.lbg_c~
ore_qat_ext_d(chips)',
 P_PATH='@baseboard_fab2_lib.baseboard_fab2(sch_1):page123_i21@mstr_u_proc.lbg_c~
ore_qat_ext_d(chips)',
 PATH='I21',
 DRAWING='@BASEBOARD_FAB2_LIB.BASEBOARD_FAB2(SCH_1):PAGE123',
 SEC_TYPE='BGA1',
 MATERIAL='IC',
 BOM_COST='SB',
 PHYS_PAGE='123',
 XY='(-5375,2600)',
 ROT='0',
 VER='10',
 PACK_TYPE='BGA1',
 PART_NUMBER='H91415-002',
 LOCATION='U7C1',
 ROOM='SB',
 SEC='10',
 CDS_LIB='mstr_u_proc',
 CDS_PART_NAME='LBG_CORE_QAT_EXT_D_BGA1-IC,H91A',
 PRIM_FILE='./archive_libs/mstr_u_proc/lbg_core_qat_ext_d/chips/chips.prt';

SECTION_NUMBER 11
 '@BASEBOARD_FAB2_LIB.BASEBOARD_FAB2(SCH_1):PAGE123_I13@MSTR_U_PROC.LBG_CORE_QAT_EXT_D(CHIPS)':
 C_PATH='@baseboard_fab2_lib.baseboard_fab2(sch_1):page123_i13@mstr_u_proc.lbg_c~
ore_qat_ext_d(chips)',
 P_PATH='@baseboard_fab2_lib.baseboard_fab2(sch_1):page123_i13@mstr_u_proc.lbg_c~
ore_qat_ext_d(chips)',
 PATH='I13',
 DRAWING='@BASEBOARD_FAB2_LIB.BASEBOARD_FAB2(SCH_1):PAGE123',
 SEC_TYPE='BGA1',
 MATERIAL='IC',
 BOM_COST='SB',
 PHYS_PAGE='123',
 XY='(-1625,2575)',
 ROT='0',
 VER='11',
 PACK_TYPE='BGA1',
 PART_NUMBER='H91415-002',
 LOCATION='U7C1',
 ROOM='SB',
 SEC='11',
 CDS_LIB='mstr_u_proc',
 CDS_PART_NAME='LBG_CORE_QAT_EXT_D_BGA1-IC,H91A',
 PRIM_FILE='./archive_libs/mstr_u_proc/lbg_core_qat_ext_d/chips/chips.prt';

SECTION_NUMBER 12
 '@BASEBOARD_FAB2_LIB.BASEBOARD_FAB2(SCH_1):PAGE124_I17@MSTR_U_PROC.LBG_CORE_QAT_EXT_D(CHIPS)':
 C_PATH='@baseboard_fab2_lib.baseboard_fab2(sch_1):page124_i17@mstr_u_proc.lbg_c~
ore_qat_ext_d(chips)',
 P_PATH='@baseboard_fab2_lib.baseboard_fab2(sch_1):page124_i17@mstr_u_proc.lbg_c~
ore_qat_ext_d(chips)',
 PATH='I17',
 DRAWING='@BASEBOARD_FAB2_LIB.BASEBOARD_FAB2(SCH_1):PAGE124',
 SEC_TYPE='BGA1',
 MATERIAL='IC',
 BOM_COST='SB',
 PHYS_PAGE='124',
 XY='(-4000,2700)',
 ROT='0',
 VER='12',
 PACK_TYPE='BGA1',
 PART_NUMBER='H91415-002',
 LOCATION='U7C1',
 ROOM='SB',
 SEC='12',
 CDS_LIB='mstr_u_proc',
 CDS_PART_NAME='LBG_CORE_QAT_EXT_D_BGA1-IC,H91A',
 PRIM_FILE='./archive_libs/mstr_u_proc/lbg_core_qat_ext_d/chips/chips.prt';

SECTION_NUMBER 13
 '@BASEBOARD_FAB2_LIB.BASEBOARD_FAB2(SCH_1):PAGE124_I16@MSTR_U_PROC.LBG_CORE_QAT_EXT_D(CHIPS)':
 C_PATH='@baseboard_fab2_lib.baseboard_fab2(sch_1):page124_i16@mstr_u_proc.lbg_c~
ore_qat_ext_d(chips)',
 P_PATH='@baseboard_fab2_lib.baseboard_fab2(sch_1):page124_i16@mstr_u_proc.lbg_c~
ore_qat_ext_d(chips)',
 PATH='I16',
 DRAWING='@BASEBOARD_FAB2_LIB.BASEBOARD_FAB2(SCH_1):PAGE124',
 SEC_TYPE='BGA1',
 MATERIAL='IC',
 BOM_COST='SB',
 PHYS_PAGE='124',
 XY='(-1475,2725)',
 ROT='0',
 VER='13',
 PACK_TYPE='BGA1',
 PART_NUMBER='H91415-002',
 LOCATION='U7C1',
 ROOM='SB',
 SEC='13',
 CDS_LIB='mstr_u_proc',
 CDS_PART_NAME='LBG_CORE_QAT_EXT_D_BGA1-IC,H91A',
 PRIM_FILE='./archive_libs/mstr_u_proc/lbg_core_qat_ext_d/chips/chips.prt';

SECTION_NUMBER 14
 '@BASEBOARD_FAB2_LIB.BASEBOARD_FAB2(SCH_1):PAGE124_I15@MSTR_U_PROC.LBG_CORE_QAT_EXT_D(CHIPS)':
 C_PATH='@baseboard_fab2_lib.baseboard_fab2(sch_1):page124_i15@mstr_u_proc.lbg_c~
ore_qat_ext_d(chips)',
 P_PATH='@baseboard_fab2_lib.baseboard_fab2(sch_1):page124_i15@mstr_u_proc.lbg_c~
ore_qat_ext_d(chips)',
 PATH='I15',
 DRAWING='@BASEBOARD_FAB2_LIB.BASEBOARD_FAB2(SCH_1):PAGE124',
 SEC_TYPE='BGA1',
 MATERIAL='IC',
 BOM_COST='SB',
 PHYS_PAGE='124',
 XY='(1200,2700)',
 ROT='0',
 VER='14',
 PACK_TYPE='BGA1',
 PART_NUMBER='H91415-002',
 LOCATION='U7C1',
 ROOM='SB',
 SEC='14',
 CDS_LIB='mstr_u_proc',
 CDS_PART_NAME='LBG_CORE_QAT_EXT_D_BGA1-IC,H91A',
 PRIM_FILE='./archive_libs/mstr_u_proc/lbg_core_qat_ext_d/chips/chips.prt';

PART_NAME
 U7D1 '74CBTLV1G125_SMLF-IC,C88177-00A':
 ROOM='DEBUG';

SECTION_NUMBER 1
 '@BASEBOARD_FAB2_LIB.BASEBOARD_FAB2(SCH_1):PAGE118_I142@MSTR_TTL.74CBTLV1G125(CHIPS)':
 C_PATH='@baseboard_fab2_lib.baseboard_fab2(sch_1):page118_i142@mstr_ttl.\74cbtl~
v1g125\(chips)',
 P_PATH='@baseboard_fab2_lib.baseboard_fab2(sch_1):page118_i142@mstr_ttl.\74cbtl~
v1g125\(chips)',
 PATH='I142',
 DRAWING='@BASEBOARD_FAB2_LIB.BASEBOARD_FAB2(SCH_1):PAGE118',
 POWER_GROUP='GND=GND;VCC=P3V3_STBY',
 MATERIAL='IC',
 BOM_COST='DEBUG',
 PHYS_PAGE='118',
 XY='(-4575,1075)',
 ROT='0',
 VER='1',
 PACK_TYPE='SMLF',
 PART_NUMBER='C88177-001',
 LOCATION='U7D1',
 ROOM='DEBUG',
 CDS_LIB='mstr_ttl',
 CDS_PART_NAME='74CBTLV1G125_SMLF-IC,C88177-00A',
 PRIM_FILE='./archive_libs/mstr_ttl/74cbtlv1g125/chips/chips.prt';

PART_NAME
 U7D2 'GTL2014_SM-IC,D66151-001':
 ROOM='PROC_SIDEBAND';

SECTION_NUMBER 1
 '@BASEBOARD_FAB2_LIB.BASEBOARD_FAB2(SCH_1):PAGE92_I32@MSTR_DIGITAL.GTL2014(CHIPS)':
 C_PATH='@baseboard_fab2_lib.baseboard_fab2(sch_1):page92_i32@mstr_digital.gtl20~
14(chips)',
 P_PATH='@baseboard_fab2_lib.baseboard_fab2(sch_1):page92_i32@mstr_digital.gtl20~
14(chips)',
 PATH='I32',
 DRAWING='@BASEBOARD_FAB2_LIB.BASEBOARD_FAB2(SCH_1):PAGE92',
 SEC_TYPE='SM',
 MATERIAL='IC',
 BOM_COST='PROC_SIDEBAND',
 PHYS_PAGE='92',
 XY='(-1750,2050)',
 ROT='2',
 VER='1',
 PACK_TYPE='SM',
 PART_NUMBER='D66151-001',
 LOCATION='U7D2',
 ROOM='PROC_SIDEBAND',
 SEC='1',
 CDS_LIB='mstr_digital',
 CDS_PART_NAME='GTL2014_SM-IC,D66151-001',
 PRIM_FILE='./archive_libs/mstr_digital/gtl2014/chips/chips.prt';

PART_NAME
 U7D3 'ADM1085_SMT-IC,H46130-001':
 ROOM='V_SUPER';

SECTION_NUMBER 1
 '@BASEBOARD_FAB2_LIB.BASEBOARD_FAB2(SCH_1):PAGE196_I70@MSTR_ANALOG.ADM1085(CHIPS)':
 C_PATH='@baseboard_fab2_lib.baseboard_fab2(sch_1):page196_i70@mstr_analog.adm10~
85(chips)',
 P_PATH='@baseboard_fab2_lib.baseboard_fab2(sch_1):page196_i70@mstr_analog.adm10~
85(chips)',
 PATH='I70',
 DRAWING='@BASEBOARD_FAB2_LIB.BASEBOARD_FAB2(SCH_1):PAGE196',
 SEC_TYPE='SMT',
 MATERIAL='IC',
 PHYS_PAGE='196',
 XY='(725,4400)',
 ROT='0',
 VER='1',
 PACK_TYPE='SMT',
 PART_NUMBER='H46130-001',
 LOCATION='U7D3',
 ROOM='V_SUPER',
 SEC='1',
 CDS_LIB='mstr_analog',
 CDS_PART_NAME='ADM1085_SMT-IC,H46130-001',
 PRIM_FILE='./archive_libs/mstr_analog/adm1085/chips/chips.prt';

PART_NAME
 U7E1 'PCA9617_SSOP-IC,G81764-001-GNDA':
 ROOM='MEM';

SECTION_NUMBER 1
 '@BASEBOARD_FAB2_LIB.BASEBOARD_FAB2(SCH_1):PAGE99_I61@MSTR_DIGITAL.PCA9617(CHIPS)':
 C_PATH='@baseboard_fab2_lib.baseboard_fab2(sch_1):page99_i61@mstr_digital.pca96~
17(chips)',
 P_PATH='@baseboard_fab2_lib.baseboard_fab2(sch_1):page99_i61@mstr_digital.pca96~
17(chips)',
 PATH='I61',
 DRAWING='@BASEBOARD_FAB2_LIB.BASEBOARD_FAB2(SCH_1):PAGE99',
 POWER_GROUP='GND=GND',
 MATERIAL='IC',
 BOM_COST='SM_CONTROLLER',
 PHYS_PAGE='99',
 XY='(150,3250)',
 ROT='0',
 VER='1',
 PACK_TYPE='SSOP',
 PART_NUMBER='G81764-001',
 LOCATION='U7E1',
 ROOM='MEM',
 CDS_LIB='mstr_digital',
 CDS_PART_NAME='PCA9617_SSOP-IC,G81764-001',
 PRIM_FILE='./archive_libs/mstr_digital/pca9617/chips/chips.prt';

PART_NAME
 U7E2 'TTL1G08_SOTLF-NC7SZ08,IC,D1032B':
 ROOM='CAT_ERR';

SECTION_NUMBER 1
 '@BASEBOARD_FAB2_LIB.BASEBOARD_FAB2(SCH_1):PAGE95_I117@MSTR_TTL.TTL1G08(CHIPS)':
 C_PATH='@baseboard_fab2_lib.baseboard_fab2(sch_1):page95_i117@mstr_ttl.ttl1g08(~
chips)',
 P_PATH='@baseboard_fab2_lib.baseboard_fab2(sch_1):page95_i117@mstr_ttl.ttl1g08(~
chips)',
 PATH='I117',
 DRAWING='@BASEBOARD_FAB2_LIB.BASEBOARD_FAB2(SCH_1):PAGE95',
 SIZE='1',
 POWER_GROUP='GND=GND;VCC=P3V3_STBY',
 SEC_TYPE='SOTLF',
 MATERIAL='IC',
 BOM_COST='PROC_SIDEBAND',
 PHYS_PAGE='95',
 XY='(1550,4225)',
 ROT='0',
 VER='1',
 VALUE='NC7SZ08',
 PACK_TYPE='SOTLF',
 PART_NUMBER='D10321-001',
 LOCATION='U7E2',
 ROOM='CAT_ERR',
 SEC='1',
 CDS_LIB='mstr_ttl',
 CDS_PART_NAME='TTL1G08_SOTLF-NC7SZ08,IC,D1032B',
 PRIM_FILE='./archive_libs/mstr_ttl/ttl1g08/chips/chips.prt';

PART_NAME
 U7E3 'TTL1G08_SOTLF-NC7SZ08,IC,D1032B':
 ROOM='CAT_ERR';

SECTION_NUMBER 1
 '@BASEBOARD_FAB2_LIB.BASEBOARD_FAB2(SCH_1):PAGE95_I118@MSTR_TTL.TTL1G08(CHIPS)':
 C_PATH='@baseboard_fab2_lib.baseboard_fab2(sch_1):page95_i118@mstr_ttl.ttl1g08(~
chips)',
 P_PATH='@baseboard_fab2_lib.baseboard_fab2(sch_1):page95_i118@mstr_ttl.ttl1g08(~
chips)',
 PATH='I118',
 DRAWING='@BASEBOARD_FAB2_LIB.BASEBOARD_FAB2(SCH_1):PAGE95',
 SIZE='1',
 POWER_GROUP='GND=GND;VCC=P3V3_STBY',
 SEC_TYPE='SOTLF',
 MATERIAL='IC',
 BOM_COST='PROC_SIDEBAND',
 PHYS_PAGE='95',
 XY='(1575,2775)',
 ROT='0',
 VER='1',
 VALUE='NC7SZ08',
 PACK_TYPE='SOTLF',
 PART_NUMBER='D10321-001',
 LOCATION='U7E3',
 ROOM='CAT_ERR',
 SEC='1',
 CDS_LIB='mstr_ttl',
 CDS_PART_NAME='TTL1G08_SOTLF-NC7SZ08,IC,D1032B',
 PRIM_FILE='./archive_libs/mstr_ttl/ttl1g08/chips/chips.prt';

PART_NAME
 U7F1 'W25Q256_XSOI-IC,H25002-001':
 ROOM='SB_SPI';

SECTION_NUMBER 1
 '@BASEBOARD_FAB2_LIB.BASEBOARD_FAB2(SCH_1):PAGE153_I146@MSTR_MEMORY.W25Q256(CHIPS)':
 C_PATH='@baseboard_fab2_lib.baseboard_fab2(sch_1):page153_i146@mstr_memory.w25q~
256(chips)',
 P_PATH='@baseboard_fab2_lib.baseboard_fab2(sch_1):page153_i146@mstr_memory.w25q~
256(chips)',
 PATH='I146',
 DRAWING='@BASEBOARD_FAB2_LIB.BASEBOARD_FAB2(SCH_1):PAGE153',
 SEC_TYPE='XSOI',
 MATERIAL='IC',
 BOM_COST='MIO_BIOS_MEM',
 PHYS_PAGE='153',
 XY='(-4700,3975)',
 ROT='0',
 VER='1',
 PACK_TYPE='XSOI',
 PART_NUMBER='H25002-001',
 LOCATION='U7F1',
 ROOM='SB_SPI',
 SEC='1',
 CDS_LIB='mstr_memory',
 CDS_PART_NAME='W25Q256_XSOI-IC,H25002-001',
 PRIM_FILE='./archive_libs/mstr_memory/w25q256/chips/chips.prt';

PART_NAME
 U7W1 'PI5A3157BC6E-GP_DISCRET-GC2-PIA':;

SECTION_NUMBER 1
 '@BASEBOARD_FAB2_LIB.BASEBOARD_FAB2(SCH_1):PAGE166_I34@W_HDL.PI5A3157BC6E-GP(CHIPS)':
 C_PATH='@baseboard_fab2_lib.baseboard_fab2(sch_1):page166_i34@w_hdl.\pi5a3157bc~
6e-gp\(chips)',
 P_PATH='@baseboard_fab2_lib.baseboard_fab2(sch_1):page166_i34@w_hdl.\pi5a3157bc~
6e-gp\(chips)',
 PATH='I34',
 DRAWING='@BASEBOARD_FAB2_LIB.BASEBOARD_FAB2(SCH_1):PAGE166',
 SEC_TYPE='DISCRET-GC2',
 PHYS_PAGE='166',
 XY='(-3400,2825)',
 ROT='0',
 VER='1',
 VALUE='PI5A3157BC6E-GP',
 PACK_TYPE='DISCRET-GC2',
 PART_NUMBER='073.53157.000J',
 LOCATION='U7W1',
 SEC='1',
 CDS_LIB='w_hdl',
 CDS_PART_NAME='PI5A3157BC6E-GP_DISCRET-GC2-PIA',
 PRIM_FILE='C:/<user>/w_hdl/pi5a3157bc6e#2dgp/chips/chips.prt';

PART_NAME
 U8D2 'TTL1G07_A_SOP-74LVC1G07,IC,C88B':;

SECTION_NUMBER 1
 '@BASEBOARD_FAB2_LIB.BASEBOARD_FAB2(SCH_1):PAGE157_I374@MSTR_TTL.TTL1G07_A(CHIPS)':
 C_PATH='@baseboard_fab2_lib.baseboard_fab2(sch_1):page157_i374@mstr_ttl.ttl1g07~
_a(chips)',
 P_PATH='@baseboard_fab2_lib.baseboard_fab2(sch_1):page157_i374@mstr_ttl.ttl1g07~
_a(chips)',
 PATH='I374',
 DRAWING='@BASEBOARD_FAB2_LIB.BASEBOARD_FAB2(SCH_1):PAGE157',
 POWER_GROUP='GND=GND;VCC=P3V3_STBY',
 SEC_TYPE='SOP',
 MATERIAL='IC',
 PHYS_PAGE='157',
 XY='(-2800,1150)',
 ROT='0',
 VER='1',
 VALUE='74LVC1G07',
 PACK_TYPE='SOP',
 PART_NUMBER='C88419-001',
 LOCATION='U8D2',
 SEC='1',
 CDS_LIB='mstr_ttl',
 CDS_PART_NAME='TTL1G07_A_SOP-74LVC1G07,IC,C88B',
 PRIM_FILE='./archive_libs/mstr_ttl/ttl1g07_a/chips/chips.prt';

PART_NAME
 U8D3 'TTL1G07_A_SOP-74LVC1G07,IC,C88B':
 ROOM='FAST_PROCHOT';

SECTION_NUMBER 1
 '@BASEBOARD_FAB2_LIB.BASEBOARD_FAB2(SCH_1):PAGE170_I4@MSTR_TTL.TTL1G07_A(CHIPS)':
 C_PATH='@baseboard_fab2_lib.baseboard_fab2(sch_1):page170_i4@mstr_ttl.ttl1g07_a~
(chips)',
 P_PATH='@baseboard_fab2_lib.baseboard_fab2(sch_1):page170_i4@mstr_ttl.ttl1g07_a~
(chips)',
 PATH='I4',
 DRAWING='@BASEBOARD_FAB2_LIB.BASEBOARD_FAB2(SCH_1):PAGE170',
 POWER_GROUP='GND=GND;VCC=P3V3_STBY',
 MATERIAL='IC',
 BOM_COST='FAST_PROCHOT',
 PHYS_PAGE='170',
 XY='(-2400,4775)',
 ROT='0',
 VER='1',
 VALUE='74LVC1G07',
 PACK_TYPE='SOP',
 PART_NUMBER='C88419-001',
 LOCATION='U8D3',
 ROOM='FAST_PROCHOT',
 CDS_LIB='mstr_ttl',
 CDS_PART_NAME='TTL1G07_A_SOP-74LVC1G07,IC,C88B',
 PRIM_FILE='./archive_libs/mstr_ttl/ttl1g07_a/chips/chips.prt';

PART_NAME
 U8D4 'AT24C64_SOICLF-IC,C47049-001-GA':
 ROOM='TEMP_SENSORS';

SECTION_NUMBER 1
 '@BASEBOARD_FAB2_LIB.BASEBOARD_FAB2(SCH_1):PAGE167_I49@MSTR_MEMORY.AT24C64(CHIPS)':
 C_PATH='@baseboard_fab2_lib.baseboard_fab2(sch_1):page167_i49@mstr_memory.at24c~
64(chips)',
 P_PATH='@baseboard_fab2_lib.baseboard_fab2(sch_1):page167_i49@mstr_memory.at24c~
64(chips)',
 PATH='I49',
 DRAWING='@BASEBOARD_FAB2_LIB.BASEBOARD_FAB2(SCH_1):PAGE167',
 POWER_GROUP='GND=GND;VCC=P3V3_STBY',
 SEC_TYPE='SOICLF',
 MATERIAL='IC',
 BOM_COST='SM_THERM',
 PHYS_PAGE='167',
 XY='(-2700,1650)',
 ROT='0',
 VER='1',
 PACK_TYPE='SOICLF',
 PART_NUMBER='C47049-001',
 LOCATION='U8D4',
 ROOM='TEMP_SENSORS',
 SEC='1',
 CDS_LIB='mstr_memory',
 CDS_PART_NAME='AT24C64_SOICLF-IC,C47049-001-VA',
 PRIM_FILE='./archive_libs/mstr_memory/at24c64/chips/chips.prt';

PART_NAME
 U8D5 'TTL1G126_A_SOT-74HC1G126,IC,A7B':
 ROOM='PROC_SIDEBAND';

SECTION_NUMBER 1
 '@BASEBOARD_FAB2_LIB.BASEBOARD_FAB2(SCH_1):PAGE170_I38@MSTR_TTL.TTL1G126_A(CHIPS)':
 C_PATH='@baseboard_fab2_lib.baseboard_fab2(sch_1):page170_i38@mstr_ttl.ttl1g126~
_a(chips)',
 P_PATH='@baseboard_fab2_lib.baseboard_fab2(sch_1):page170_i38@mstr_ttl.ttl1g126~
_a(chips)',
 PATH='I38',
 DRAWING='@BASEBOARD_FAB2_LIB.BASEBOARD_FAB2(SCH_1):PAGE170',
 POWER_GROUP='GND=GND;VCC=P3V3_STBY',
 SEC_TYPE='SOT',
 MATERIAL='IC',
 BOM_COST='PROC_SIDEBAND',
 PHYS_PAGE='170',
 XY='(-3500,4775)',
 ROT='0',
 VER='1',
 VALUE='74HC1G126',
 PACK_TYPE='SOT',
 PART_NUMBER='A79322-001',
 LOCATION='U8D5',
 ROOM='PROC_SIDEBAND',
 SEC='1',
 CDS_LIB='mstr_ttl',
 CDS_PART_NAME='TTL1G126_A_SOT-74HC1G126,IC,A7B',
 PRIM_FILE='./archive_libs/mstr_ttl/ttl1g126_a/chips/chips.prt';

PART_NAME
 U8D7 'LCMXO2_A_256BGA-IC,H63395-001':
 ROOM='CPLD';

SECTION_NUMBER 1
 '@BASEBOARD_FAB2_LIB.BASEBOARD_FAB2(SCH_1):PAGE190_I179@MSTR_MEMORY.LCMXO2_A(CHIPS)':
 C_PATH='@baseboard_fab2_lib.baseboard_fab2(sch_1):page190_i179@mstr_memory.lcmx~
o2_a(chips)',
 P_PATH='@baseboard_fab2_lib.baseboard_fab2(sch_1):page190_i179@mstr_memory.lcmx~
o2_a(chips)',
 PATH='I179',
 DRAWING='@BASEBOARD_FAB2_LIB.BASEBOARD_FAB2(SCH_1):PAGE190',
 SEC_TYPE='256BGA',
 MATERIAL='IC',
 BOM_COST='CPLD',
 PHYS_PAGE='190',
 XY='(-1950,2950)',
 ROT='0',
 VER='4',
 PACK_TYPE='256BGA',
 PART_NUMBER='H63395-001',
 LOCATION='U8D7',
 ROOM='CPLD',
 SEC='1',
 CDS_LIB='mstr_memory',
 CDS_PART_NAME='LCMXO2_A_256BGA-IC,H63395-001',
 PRIM_FILE='./archive_libs/mstr_memory/lcmxo2_a/chips/chips.prt';

SECTION_NUMBER 2
 '@BASEBOARD_FAB2_LIB.BASEBOARD_FAB2(SCH_1):PAGE191_I59@MSTR_MEMORY.LCMXO2_A(CHIPS)':
 C_PATH='@baseboard_fab2_lib.baseboard_fab2(sch_1):page191_i59@mstr_memory.lcmxo~
2_a(chips)',
 P_PATH='@baseboard_fab2_lib.baseboard_fab2(sch_1):page191_i59@mstr_memory.lcmxo~
2_a(chips)',
 PATH='I59',
 DRAWING='@BASEBOARD_FAB2_LIB.BASEBOARD_FAB2(SCH_1):PAGE191',
 SEC_TYPE='256BGA',
 MATERIAL='IC',
 BOM_COST='CPLD',
 PHYS_PAGE='191',
 XY='(-4475,2725)',
 ROT='0',
 VER='5',
 PACK_TYPE='256BGA',
 PART_NUMBER='H63395-001',
 LOCATION='U8D7',
 ROOM='CPLD',
 SEC='2',
 CDS_LIB='mstr_memory',
 CDS_PART_NAME='LCMXO2_A_256BGA-IC,H63395-001',
 PRIM_FILE='./archive_libs/mstr_memory/lcmxo2_a/chips/chips.prt';

SECTION_NUMBER 3
 '@BASEBOARD_FAB2_LIB.BASEBOARD_FAB2(SCH_1):PAGE192_I14@MSTR_MEMORY.LCMXO2_A(CHIPS)':
 C_PATH='@baseboard_fab2_lib.baseboard_fab2(sch_1):page192_i14@mstr_memory.lcmxo~
2_a(chips)',
 P_PATH='@baseboard_fab2_lib.baseboard_fab2(sch_1):page192_i14@mstr_memory.lcmxo~
2_a(chips)',
 PATH='I14',
 DRAWING='@BASEBOARD_FAB2_LIB.BASEBOARD_FAB2(SCH_1):PAGE192',
 SEC_TYPE='256BGA',
 MATERIAL='IC',
 BOM_COST='CPLD',
 PHYS_PAGE='192',
 XY='(-1850,3900)',
 ROT='0',
 VER='6',
 PACK_TYPE='256BGA',
 PART_NUMBER='H63395-001',
 LOCATION='U8D7',
 ROOM='CPLD',
 SEC='3',
 CDS_LIB='mstr_memory',
 CDS_PART_NAME='LCMXO2_A_256BGA-IC,H63395-001',
 PRIM_FILE='./archive_libs/mstr_memory/lcmxo2_a/chips/chips.prt';

PART_NAME
 U8D8 'TPS3700_SM-IC,H69492-001':
 ROOM='V_SUPER';

SECTION_NUMBER 1
 '@BASEBOARD_FAB2_LIB.BASEBOARD_FAB2(SCH_1):PAGE196_I104@MSTR_VREG.TPS3700(CHIPS)':
 C_PATH='@baseboard_fab2_lib.baseboard_fab2(sch_1):page196_i104@mstr_vreg.tps370~
0(chips)',
 P_PATH='@baseboard_fab2_lib.baseboard_fab2(sch_1):page196_i104@mstr_vreg.tps370~
0(chips)',
 PATH='I104',
 DRAWING='@BASEBOARD_FAB2_LIB.BASEBOARD_FAB2(SCH_1):PAGE196',
 MATERIAL='IC',
 PHYS_PAGE='196',
 XY='(-500,2300)',
 ROT='0',
 VER='1',
 PACK_TYPE='SM',
 PART_NUMBER='H69492-001',
 LOCATION='U8D8',
 ROOM='V_SUPER',
 CDS_LIB='mstr_vreg',
 CDS_PART_NAME='TPS3700_SM-IC,H69492-001',
 PRIM_FILE='./archive_libs/mstr_vreg/tps3700/chips/chips.prt';

PART_NAME
 U8E1 'TTL08_QFN15-74LVC08A,IC,D90404B':
 ROOM='FAST_PROCHOT';

SECTION_NUMBER 1
 '@BASEBOARD_FAB2_LIB.BASEBOARD_FAB2(SCH_1):PAGE170_I12@MSTR_TTL.TTL08(CHIPS)':
 C_PATH='@baseboard_fab2_lib.baseboard_fab2(sch_1):page170_i12@mstr_ttl.ttl08(ch~
ips)',
 P_PATH='@baseboard_fab2_lib.baseboard_fab2(sch_1):page170_i12@mstr_ttl.ttl08(ch~
ips)',
 PATH='I12',
 DRAWING='@BASEBOARD_FAB2_LIB.BASEBOARD_FAB2(SCH_1):PAGE170',
 SIZE='1',
 POWER_GROUP='GND=GND;VCC=P3V3_STBY;TH=GND',
 SEC_TYPE='QFN15',
 MATERIAL='IC',
 BOM_COST='FAST_PROCHOT',
 PHYS_PAGE='170',
 XY='(-25,4075)',
 ROT='0',
 VER='1',
 VALUE='74LVC08A',
 PACK_TYPE='QFN15',
 PART_NUMBER='D90404-001',
 LOCATION='U8E1',
 ROOM='FAST_PROCHOT',
 SEC='1',
 CDS_LIB='mstr_ttl',
 CDS_PART_NAME='TTL08_QFN15-74LVC08A,IC,D90404B',
 PRIM_FILE='./archive_libs/mstr_ttl/ttl08/chips/chips.prt';

SECTION_NUMBER 2
 '@BASEBOARD_FAB2_LIB.BASEBOARD_FAB2(SCH_1):PAGE181_I60@MSTR_TTL.TTL08(CHIPS)':
 C_PATH='@baseboard_fab2_lib.baseboard_fab2(sch_1):page181_i60@mstr_ttl.ttl08(ch~
ips)',
 P_PATH='@baseboard_fab2_lib.baseboard_fab2(sch_1):page181_i60@mstr_ttl.ttl08(ch~
ips)',
 PATH='I60',
 DRAWING='@BASEBOARD_FAB2_LIB.BASEBOARD_FAB2(SCH_1):PAGE181',
 SIZE='1',
 POWER_GROUP='GND=GND;VCC=P3V3_STBY;TH=GND',
 SEC_TYPE='QFN15',
 MATERIAL='IC',
 BOM_COST='FAST_PROCHOT',
 PHYS_PAGE='181',
 XY='(850,825)',
 ROT='0',
 VER='1',
 VALUE='74LVC08A',
 PACK_TYPE='QFN15',
 PART_NUMBER='D90404-001',
 LOCATION='U8E1',
 ROOM='FAST_PROCHOT',
 SEC='2',
 CDS_LIB='mstr_ttl',
 CDS_PART_NAME='TTL08_QFN15-74LVC08A,IC,D90404B',
 PRIM_FILE='./archive_libs/mstr_ttl/ttl08/chips/chips.prt';

SECTION_NUMBER 3
 '@BASEBOARD_FAB2_LIB.BASEBOARD_FAB2(SCH_1):PAGE170_I11@MSTR_TTL.TTL08(CHIPS)':
 C_PATH='@baseboard_fab2_lib.baseboard_fab2(sch_1):page170_i11@mstr_ttl.ttl08(ch~
ips)',
 P_PATH='@baseboard_fab2_lib.baseboard_fab2(sch_1):page170_i11@mstr_ttl.ttl08(ch~
ips)',
 PATH='I11',
 DRAWING='@BASEBOARD_FAB2_LIB.BASEBOARD_FAB2(SCH_1):PAGE170',
 SIZE='1',
 POWER_GROUP='GND=GND;VCC=P3V3_STBY;TH=GND',
 SEC_TYPE='QFN15',
 MATERIAL='IC',
 BOM_COST='FAST_PROCHOT',
 PHYS_PAGE='170',
 XY='(-1175,3650)',
 ROT='0',
 VER='1',
 VALUE='74LVC08A',
 PACK_TYPE='QFN15',
 PART_NUMBER='D90404-001',
 LOCATION='U8E1',
 ROOM='FAST_PROCHOT',
 SEC='3',
 CDS_LIB='mstr_ttl',
 CDS_PART_NAME='TTL08_QFN15-74LVC08A,IC,D90404B',
 PRIM_FILE='./archive_libs/mstr_ttl/ttl08/chips/chips.prt';

SECTION_NUMBER 4
 '@BASEBOARD_FAB2_LIB.BASEBOARD_FAB2(SCH_1):PAGE170_I10@MSTR_TTL.TTL08(CHIPS)':
 C_PATH='@baseboard_fab2_lib.baseboard_fab2(sch_1):page170_i10@mstr_ttl.ttl08(ch~
ips)',
 P_PATH='@baseboard_fab2_lib.baseboard_fab2(sch_1):page170_i10@mstr_ttl.ttl08(ch~
ips)',
 PATH='I10',
 DRAWING='@BASEBOARD_FAB2_LIB.BASEBOARD_FAB2(SCH_1):PAGE170',
 SIZE='1',
 POWER_GROUP='GND=GND;VCC=P3V3_STBY;TH=GND',
 SEC_TYPE='QFN15',
 MATERIAL='IC',
 BOM_COST='FAST_PROCHOT',
 PHYS_PAGE='170',
 XY='(-1175,4375)',
 ROT='0',
 VER='1',
 VALUE='74LVC08A',
 PACK_TYPE='QFN15',
 PART_NUMBER='D90404-001',
 LOCATION='U8E1',
 ROOM='FAST_PROCHOT',
 SEC='4',
 CDS_LIB='mstr_ttl',
 CDS_PART_NAME='TTL08_QFN15-74LVC08A,IC,D90404B',
 PRIM_FILE='./archive_libs/mstr_ttl/ttl08/chips/chips.prt';

PART_NAME
 U8E2 'ADM809_SMLF-IC,D23047-001-GND=A':
 ROOM='V_SUPER';

SECTION_NUMBER 1
 '@BASEBOARD_FAB2_LIB.BASEBOARD_FAB2(SCH_1):PAGE196_I89@MSTR_ANALOG.ADM809(CHIPS)':
 C_PATH='@baseboard_fab2_lib.baseboard_fab2(sch_1):page196_i89@mstr_analog.adm80~
9(chips)',
 P_PATH='@baseboard_fab2_lib.baseboard_fab2(sch_1):page196_i89@mstr_analog.adm80~
9(chips)',
 PATH='I89',
 DRAWING='@BASEBOARD_FAB2_LIB.BASEBOARD_FAB2(SCH_1):PAGE196',
 POWER_GROUP='GND=GND',
 MATERIAL='IC',
 PHYS_PAGE='196',
 XY='(400,3100)',
 ROT='0',
 VER='1',
 PACK_TYPE='SMLF',
 PART_NUMBER='D23047-001',
 LOCATION='U8E2',
 ROOM='V_SUPER',
 CDS_LIB='mstr_analog',
 CDS_PART_NAME='ADM809_SMLF-IC,D23047-001',
 PRIM_FILE='./archive_libs/mstr_analog/adm809/chips/chips.prt';

PART_NAME
 U8E3 'TTL1G126_A_SOT-74HC1G126,IC,A7B':
 ROOM='SB';

SECTION_NUMBER 1
 '@BASEBOARD_FAB2_LIB.BASEBOARD_FAB2(SCH_1):PAGE136_I130@MSTR_TTL.TTL1G126_A(CHIPS)':
 C_PATH='@baseboard_fab2_lib.baseboard_fab2(sch_1):page136_i130@mstr_ttl.ttl1g12~
6_a(chips)',
 P_PATH='@baseboard_fab2_lib.baseboard_fab2(sch_1):page136_i130@mstr_ttl.ttl1g12~
6_a(chips)',
 PATH='I130',
 DRAWING='@BASEBOARD_FAB2_LIB.BASEBOARD_FAB2(SCH_1):PAGE136',
 POWER_GROUP='GND=GND;VCC=P3V3_STBY',
 SEC_TYPE='SOT',
 MATERIAL='IC',
 BOM_COST='SB',
 PHYS_PAGE='136',
 XY='(0,2300)',
 ROT='0',
 VER='1',
 VALUE='74HC1G126',
 PACK_TYPE='SOT',
 PART_NUMBER='A79322-001',
 LOCATION='U8E3',
 ROOM='SB',
 SEC='1',
 CDS_LIB='mstr_ttl',
 CDS_PART_NAME='TTL1G126_A_SOT-74HC1G126,IC,A7B',
 PRIM_FILE='./archive_libs/mstr_ttl/ttl1g126_a/chips/chips.prt';

PART_NAME
 U8E4 'TTL1G126_A_SOT-74HC1G126,IC,A7B':
 ROOM='PCIE_WAKE_BUFFER';

SECTION_NUMBER 1
 '@BASEBOARD_FAB2_LIB.BASEBOARD_FAB2(SCH_1):PAGE142_I1@MSTR_TTL.TTL1G126_A(CHIPS)':
 C_PATH='@baseboard_fab2_lib.baseboard_fab2(sch_1):page142_i1@mstr_ttl.ttl1g126_~
a(chips)',
 P_PATH='@baseboard_fab2_lib.baseboard_fab2(sch_1):page142_i1@mstr_ttl.ttl1g126_~
a(chips)',
 PATH='I1',
 DRAWING='@BASEBOARD_FAB2_LIB.BASEBOARD_FAB2(SCH_1):PAGE142',
 POWER_GROUP='GND=GND;VCC=P3V3_STBY',
 SEC_TYPE='SOT',
 MATERIAL='IC',
 BOM_COST='SB',
 PHYS_PAGE='142',
 XY='(-3500,2250)',
 ROT='6',
 VER='1',
 VALUE='74HC1G126',
 PACK_TYPE='SOT',
 PART_NUMBER='A79322-001',
 LOCATION='U8E4',
 ROOM='PCIE_WAKE_BUFFER',
 SEC='1',
 CDS_LIB='mstr_ttl',
 CDS_PART_NAME='TTL1G126_A_SOT-74HC1G126,IC,A7B',
 PRIM_FILE='./archive_libs/mstr_ttl/ttl1g126_a/chips/chips.prt';

PART_NAME
 U8F1 'PI3B3257A_TSSOPLF-IC,E16801-001':
 ROOM='SB_BMC_SPI_MUX';

SECTION_NUMBER 1
 '@BASEBOARD_FAB2_LIB.BASEBOARD_FAB2(SCH_1):PAGE154_I74@MSTR_DIGITAL.PI3B3257A(CHIPS)':
 C_PATH='@baseboard_fab2_lib.baseboard_fab2(sch_1):page154_i74@mstr_digital.pi3b~
3257a(chips)',
 P_PATH='@baseboard_fab2_lib.baseboard_fab2(sch_1):page154_i74@mstr_digital.pi3b~
3257a(chips)',
 PATH='I74',
 DRAWING='@BASEBOARD_FAB2_LIB.BASEBOARD_FAB2(SCH_1):PAGE154',
 SEC_TYPE='TSSOPLF',
 MATERIAL='IC',
 BOM_COST='MIO_BIOS_MEM',
 PHYS_PAGE='154',
 XY='(-5900,3700)',
 ROT='2',
 VER='1',
 PACK_TYPE='TSSOPLF',
 PART_NUMBER='E16801-001',
 LOCATION='U8F1',
 ROOM='SB_BMC_SPI_MUX',
 SEC='1',
 CDS_LIB='mstr_digital',
 CDS_PART_NAME='PI3B3257A_TSSOPLF-IC,E16801-001',
 PRIM_FILE='./archive_libs/mstr_digital/pi3b3257a/chips/chips.prt';

PART_NAME
 U8F2 'W25Q128_SKT16-IC,H12709-001':
 ROOM='BMC_BOOT_SPI';

SECTION_NUMBER 1
 '@BASEBOARD_FAB2_LIB.BASEBOARD_FAB2(SCH_1):PAGE162_I32@MSTR_MEMORY.W25Q128(CHIPS)':
 C_PATH='@baseboard_fab2_lib.baseboard_fab2(sch_1):page162_i32@mstr_memory.w25q1~
28(chips)',
 P_PATH='@baseboard_fab2_lib.baseboard_fab2(sch_1):page162_i32@mstr_memory.w25q1~
28(chips)',
 PATH='I32',
 DRAWING='@BASEBOARD_FAB2_LIB.BASEBOARD_FAB2(SCH_1):PAGE162',
 SEC_TYPE='SKT16',
 MATERIAL='IC',
 BOM_COST='SM_MEM',
 PHYS_PAGE='162',
 XY='(6450,2800)',
 ROT='0',
 VER='3',
 PACK_TYPE='SKT16',
 PART_NUMBER='H12709-001',
 LOCATION='U8F2',
 ROOM='BMC_BOOT_SPI',
 SEC='1',
 CDS_LIB='mstr_memory',
 CDS_PART_NAME='W25Q128_SKT16-IC,H12709-001',
 PRIM_FILE='./archive_libs/mstr_memory/w25q128/chips/chips.prt';

PART_NAME
 U8F3 'SN74LVC2G07DCKR-GP_DISCRET-G4-A':;

SECTION_NUMBER 1
 '@BASEBOARD_FAB2_LIB.BASEBOARD_FAB2(SCH_1):PAGE156_I340@W_HDL.SN74LVC2G07DCKR-GP(CHIPS)':
 C_PATH='@baseboard_fab2_lib.baseboard_fab2(sch_1):page156_i340@w_hdl.\sn74lvc2g~
07dckr-gp\(chips)',
 P_PATH='@baseboard_fab2_lib.baseboard_fab2(sch_1):page156_i340@w_hdl.\sn74lvc2g~
07dckr-gp\(chips)',
 PATH='I340',
 DRAWING='@BASEBOARD_FAB2_LIB.BASEBOARD_FAB2(SCH_1):PAGE156',
 SEC_TYPE='DISCRET-G4',
 PHYS_PAGE='156',
 XY='(-3225,4150)',
 ROT='0',
 VER='1',
 VALUE='SN74LVC2G07DCKR-GP',
 PACK_TYPE='DISCRET-G4',
 PART_NUMBER='73.02G07.02J',
 LOCATION='U8F3',
 SEC='1',
 CDS_LIB='w_hdl',
 CDS_PART_NAME='SN74LVC2G07DCKR-GP_DISCRET-G4-A',
 PRIM_FILE='C:/<user>/w_hdl/sn74lvc2g07dckr#2dgp/chips/chips.prt';

PART_NAME
 U8G1 'SN74LVC2G07DCKR-GP_DISCRET-G4-A':;

SECTION_NUMBER 1
 '@BASEBOARD_FAB2_LIB.BASEBOARD_FAB2(SCH_1):PAGE156_I342@W_HDL.SN74LVC2G07DCKR-GP(CHIPS)':
 C_PATH='@baseboard_fab2_lib.baseboard_fab2(sch_1):page156_i342@w_hdl.\sn74lvc2g~
07dckr-gp\(chips)',
 P_PATH='@baseboard_fab2_lib.baseboard_fab2(sch_1):page156_i342@w_hdl.\sn74lvc2g~
07dckr-gp\(chips)',
 PATH='I342',
 DRAWING='@BASEBOARD_FAB2_LIB.BASEBOARD_FAB2(SCH_1):PAGE156',
 SEC_TYPE='DISCRET-G4',
 PHYS_PAGE='156',
 XY='(-3225,2950)',
 ROT='0',
 VER='1',
 VALUE='SN74LVC2G07DCKR-GP',
 PACK_TYPE='DISCRET-G4',
 PART_NUMBER='73.02G07.02J',
 LOCATION='U8G1',
 SEC='1',
 CDS_LIB='w_hdl',
 CDS_PART_NAME='SN74LVC2G07DCKR-GP_DISCRET-G4-A',
 PRIM_FILE='C:/<user>/w_hdl/sn74lvc2g07dckr#2dgp/chips/chips.prt';

PART_NAME
 U8G2 'TTL1G07_A_SOP-74LVC1G07,IC,C88B':
 ROOM='CPU_FANS';

SECTION_NUMBER 1
 '@BASEBOARD_FAB2_LIB.BASEBOARD_FAB2(SCH_1):PAGE161_I88@MSTR_TTL.TTL1G07_A(CHIPS)':
 C_PATH='@baseboard_fab2_lib.baseboard_fab2(sch_1):page161_i88@mstr_ttl.ttl1g07_~
a(chips)',
 P_PATH='@baseboard_fab2_lib.baseboard_fab2(sch_1):page161_i88@mstr_ttl.ttl1g07_~
a(chips)',
 PATH='I88',
 DRAWING='@BASEBOARD_FAB2_LIB.BASEBOARD_FAB2(SCH_1):PAGE161',
 POWER_GROUP='GND=GND;VCC=P3V3_STBY',
 SEC_TYPE='SOP',
 MATERIAL='IC',
 BOM_COST='SM_THERM',
 PHYS_PAGE='161',
 XY='(-6350,3850)',
 ROT='0',
 VER='1',
 VALUE='74LVC1G07',
 PACK_TYPE='SOP',
 PART_NUMBER='C88419-001',
 LOCATION='U8G2',
 ROOM='CPU_FANS',
 SEC='1',
 CDS_LIB='mstr_ttl',
 CDS_PART_NAME='TTL1G07_A_SOP-74LVC1G07,IC,C88B',
 PRIM_FILE='./archive_libs/mstr_ttl/ttl1g07_a/chips/chips.prt';

PART_NAME
 U8G3 'TTL1G07_A_SOP-74LVC1G07,IC,C88B':
 ROOM='CPU_FANS';

SECTION_NUMBER 1
 '@BASEBOARD_FAB2_LIB.BASEBOARD_FAB2(SCH_1):PAGE161_I92@MSTR_TTL.TTL1G07_A(CHIPS)':
 C_PATH='@baseboard_fab2_lib.baseboard_fab2(sch_1):page161_i92@mstr_ttl.ttl1g07_~
a(chips)',
 P_PATH='@baseboard_fab2_lib.baseboard_fab2(sch_1):page161_i92@mstr_ttl.ttl1g07_~
a(chips)',
 PATH='I92',
 DRAWING='@BASEBOARD_FAB2_LIB.BASEBOARD_FAB2(SCH_1):PAGE161',
 POWER_GROUP='GND=GND;VCC=P3V3_STBY',
 SEC_TYPE='SOP',
 MATERIAL='IC',
 BOM_COST='SM_THERM',
 PHYS_PAGE='161',
 XY='(-6425,1100)',
 ROT='0',
 VER='1',
 VALUE='74LVC1G07',
 PACK_TYPE='SOP',
 PART_NUMBER='C88419-001',
 LOCATION='U8G3',
 ROOM='CPU_FANS',
 SEC='1',
 CDS_LIB='mstr_ttl',
 CDS_PART_NAME='TTL1G07_A_SOP-74LVC1G07,IC,C88B',
 PRIM_FILE='./archive_libs/mstr_ttl/ttl1g07_a/chips/chips.prt';

PART_NAME
 U8W1 '74CBTLV1G125_SMLF-IC,C88177-00A':
 ROOM='DEBUG';

SECTION_NUMBER 1
 '@BASEBOARD_FAB2_LIB.BASEBOARD_FAB2(SCH_1):PAGE245_I64@MSTR_TTL.74CBTLV1G125(CHIPS)':
 C_PATH='@baseboard_fab2_lib.baseboard_fab2(sch_1):page245_i64@mstr_ttl.\74cbtlv~
1g125\(chips)',
 P_PATH='@baseboard_fab2_lib.baseboard_fab2(sch_1):page245_i64@mstr_ttl.\74cbtlv~
1g125\(chips)',
 PATH='I64',
 DRAWING='@BASEBOARD_FAB2_LIB.BASEBOARD_FAB2(SCH_1):PAGE245',
 POWER_GROUP='GND=GND;VCC=P3V3_STBY',
 SEC_TYPE='SMLF',
 MATERIAL='IC',
 BOM_COST='DEBUG',
 PHYS_PAGE='245',
 XY='(-3900,2000)',
 ROT='0',
 VER='1',
 PACK_TYPE='SMLF',
 PART_NUMBER='C88177-001',
 LOCATION='U8W1',
 ROOM='DEBUG',
 SEC='1',
 CDS_LIB='mstr_ttl',
 CDS_PART_NAME='74CBTLV1G125_SMLF-IC,C88177-00A',
 PRIM_FILE='./archive_libs/mstr_ttl/74cbtlv1g125/chips/chips.prt';

PART_NAME
 U8W2 'NC7SB3157_SMLF-IC,C99406-001':
 ROOM='DEBUG';

SECTION_NUMBER 1
 '@BASEBOARD_FAB2_LIB.BASEBOARD_FAB2(SCH_1):PAGE245_I66@MSTR_ANALOG.NC7SB3157(CHIPS)':
 C_PATH='@baseboard_fab2_lib.baseboard_fab2(sch_1):page245_i66@mstr_analog.nc7sb~
3157(chips)',
 P_PATH='@baseboard_fab2_lib.baseboard_fab2(sch_1):page245_i66@mstr_analog.nc7sb~
3157(chips)',
 PATH='I66',
 DRAWING='@BASEBOARD_FAB2_LIB.BASEBOARD_FAB2(SCH_1):PAGE245',
 MATERIAL='IC',
 BOM_COST='DEBUG',
 PHYS_PAGE='245',
 XY='(-5950,1500)',
 ROT='2',
 VER='1',
 PACK_TYPE='SMLF',
 PART_NUMBER='C99406-001',
 LOCATION='U8W2',
 ROOM='DEBUG',
 CDS_LIB='mstr_analog',
 CDS_PART_NAME='NC7SB3157_SMLF-IC,C99406-001',
 PRIM_FILE='./archive_libs/mstr_analog/nc7sb3157/chips/chips.prt';

PART_NAME
 U9A1 'TTL1G07_A_SOP-74LVC1G07,IC,C88B':
 ROOM='BMC_DEBUG_HEADER';

SECTION_NUMBER 1
 '@BASEBOARD_FAB2_LIB.BASEBOARD_FAB2(SCH_1):PAGE155_I178@MSTR_TTL.TTL1G07_A(CHIPS)':
 C_PATH='@baseboard_fab2_lib.baseboard_fab2(sch_1):page155_i178@mstr_ttl.ttl1g07~
_a(chips)',
 P_PATH='@baseboard_fab2_lib.baseboard_fab2(sch_1):page155_i178@mstr_ttl.ttl1g07~
_a(chips)',
 PATH='I178',
 DRAWING='@BASEBOARD_FAB2_LIB.BASEBOARD_FAB2(SCH_1):PAGE155',
 POWER_GROUP='GND=GND;VCC=P3V3_STBY',
 SEC_TYPE='SOP',
 MATERIAL='IC',
 BOM_COST='DEBUG',
 PHYS_PAGE='155',
 XY='(-2100,1400)',
 ROT='0',
 VER='1',
 VALUE='74LVC1G07',
 PACK_TYPE='SOP',
 PART_NUMBER='C88419-001',
 LOCATION='U9A1',
 ROOM='BMC_DEBUG_HEADER',
 SEC='1',
 CDS_LIB='mstr_ttl',
 CDS_PART_NAME='TTL1G07_A_SOP-74LVC1G07,IC,C88B',
 PRIM_FILE='./archive_libs/mstr_ttl/ttl1g07_a/chips/chips.prt';

PART_NAME
 U9A3 'TC7PZ14FU-GP_DISCRET-GA1-TC7PZA':;

SECTION_NUMBER 1
 '@BASEBOARD_FAB2_LIB.BASEBOARD_FAB2(SCH_1):PAGE175_I93@W_HDL.TC7PZ14FU-GP(CHIPS)':
 C_PATH='@baseboard_fab2_lib.baseboard_fab2(sch_1):page175_i93@w_hdl.\tc7pz14fu-~
gp\(chips)',
 P_PATH='@baseboard_fab2_lib.baseboard_fab2(sch_1):page175_i93@w_hdl.\tc7pz14fu-~
gp\(chips)',
 PATH='I93',
 DRAWING='@BASEBOARD_FAB2_LIB.BASEBOARD_FAB2(SCH_1):PAGE175',
 SEC_TYPE='DISCRET-GA1',
 PHYS_PAGE='175',
 XY='(-3725,2725)',
 ROT='0',
 VER='1',
 VALUE='TC7PZ14FU-GP',
 PACK_TYPE='DISCRET-GA1',
 PART_NUMBER='073.7PZ14.0007',
 LOCATION='U9A3',
 SEC='1',
 CDS_LIB='w_hdl',
 CDS_PART_NAME='TC7PZ14FU-GP_DISCRET-GA1-TC7PZA',
 PRIM_FILE='C:/<user>/w_hdl/tc7pz14fu#2dgp/chips/chips.prt';

PART_NAME
 U9A4 'TC7PZ14FU-GP_DISCRET-GA1-TC7PZA':;

SECTION_NUMBER 1
 '@BASEBOARD_FAB2_LIB.BASEBOARD_FAB2(SCH_1):PAGE175_I97@W_HDL.TC7PZ14FU-GP(CHIPS)':
 C_PATH='@baseboard_fab2_lib.baseboard_fab2(sch_1):page175_i97@w_hdl.\tc7pz14fu-~
gp\(chips)',
 P_PATH='@baseboard_fab2_lib.baseboard_fab2(sch_1):page175_i97@w_hdl.\tc7pz14fu-~
gp\(chips)',
 PATH='I97',
 DRAWING='@BASEBOARD_FAB2_LIB.BASEBOARD_FAB2(SCH_1):PAGE175',
 SEC_TYPE='DISCRET-GA1',
 PHYS_PAGE='175',
 XY='(-3675,4125)',
 ROT='0',
 VER='1',
 VALUE='TC7PZ14FU-GP',
 PACK_TYPE='DISCRET-GA1',
 PART_NUMBER='073.7PZ14.0007',
 LOCATION='U9A4',
 SEC='1',
 CDS_LIB='w_hdl',
 CDS_PART_NAME='TC7PZ14FU-GP_DISCRET-GA1-TC7PZA',
 PRIM_FILE='C:/<user>/w_hdl/tc7pz14fu#2dgp/chips/chips.prt';

PART_NAME
 U9A5 '74CBTLV1G125_SMLF-IC,C88177-00A':
 ROOM='DEBUG';

SECTION_NUMBER 1
 '@BASEBOARD_FAB2_LIB.BASEBOARD_FAB2(SCH_1):PAGE113_I185@MSTR_TTL.74CBTLV1G125(CHIPS)':
 C_PATH='@baseboard_fab2_lib.baseboard_fab2(sch_1):page113_i185@mstr_ttl.\74cbtl~
v1g125\(chips)',
 P_PATH='@baseboard_fab2_lib.baseboard_fab2(sch_1):page113_i185@mstr_ttl.\74cbtl~
v1g125\(chips)',
 PATH='I185',
 DRAWING='@BASEBOARD_FAB2_LIB.BASEBOARD_FAB2(SCH_1):PAGE113',
 POWER_GROUP='GND=GND;VCC=P3V3_STBY',
 POP='NOPOP',
 SEC_TYPE='SMLF',
 MATERIAL='IC',
 BOM_COST='DEBUG',
 PHYS_PAGE='113',
 XY='(3650,4400)',
 ROT='0',
 VER='1',
 PACK_TYPE='SMLF',
 PART_NUMBER='C88177-001',
 LOCATION='U9A5',
 ROOM='DEBUG',
 SEC='1',
 CDS_LIB='mstr_ttl',
 CDS_PART_NAME='74CBTLV1G125_SMLF-IC,C88177-00A',
 PRIM_FILE='./archive_libs/mstr_ttl/74cbtlv1g125/chips/chips.prt';

PART_NAME
 U9B4 'TMP421_TSSOP-IC,G62962-001':
 ROOM='TEMP_SENSORS';

SECTION_NUMBER 1
 '@BASEBOARD_FAB2_LIB.BASEBOARD_FAB2(SCH_1):PAGE167_I1@MSTR_ANALOG.TMP421(CHIPS)':
 C_PATH='@baseboard_fab2_lib.baseboard_fab2(sch_1):page167_i1@mstr_analog.tmp421~
(chips)',
 P_PATH='@baseboard_fab2_lib.baseboard_fab2(sch_1):page167_i1@mstr_analog.tmp421~
(chips)',
 PATH='I1',
 DRAWING='@BASEBOARD_FAB2_LIB.BASEBOARD_FAB2(SCH_1):PAGE167',
 SEC_TYPE='TSSOP',
 MATERIAL='IC',
 BOM_COST='SM_THERM',
 PHYS_PAGE='167',
 XY='(-4000,4450)',
 ROT='0',
 VER='1',
 PACK_TYPE='TSSOP',
 PART_NUMBER='G62962-001',
 LOCATION='U9B4',
 ROOM='TEMP_SENSORS',
 SEC='1',
 CDS_LIB='mstr_analog',
 CDS_PART_NAME='TMP421_TSSOP-IC,G62962-001',
 PRIM_FILE='./archive_libs/mstr_analog/tmp421/chips/chips.prt';

PART_NAME
 U9E1 'M25PE16_SM-IC,H77797-001':
 GROUP='NI_I210&RJ45',
 ROOM='NIC_SPRV';

SECTION_NUMBER 1
 '@BASEBOARD_FAB2_LIB.BASEBOARD_FAB2(SCH_1):PAGE140_I1@MSTR_MEMORY.M25PE16(CHIPS)':
 C_PATH='@baseboard_fab2_lib.baseboard_fab2(sch_1):page140_i1@mstr_memory.m25pe1~
6(chips)',
 P_PATH='@baseboard_fab2_lib.baseboard_fab2(sch_1):page140_i1@mstr_memory.m25pe1~
6(chips)',
 PATH='I1',
 DRAWING='@BASEBOARD_FAB2_LIB.BASEBOARD_FAB2(SCH_1):PAGE140',
 SEC_TYPE='SM',
 MATERIAL='IC',
 BOM_COST='NT_GBE_BASE',
 PHYS_PAGE='140',
 XY='(-2350,2700)',
 ROT='0',
 VER='1',
 PACK_TYPE='SM',
 PART_NUMBER='H77797-001',
 LOCATION='U9E1',
 ROOM='NIC_SPRV',
 GROUP='NI_I210&RJ45',
 SEC='1',
 CDS_LIB='mstr_memory',
 CDS_PART_NAME='M25PE16_SM-IC,H77797-001',
 PRIM_FILE='./archive_libs/mstr_memory/m25pe16/chips/chips.prt';

PART_NAME
 U9F1 'FSA3357_SM-IC,C63273-001':
 ROOM='UART_MUX';

SECTION_NUMBER 1
 '@BASEBOARD_FAB2_LIB.BASEBOARD_FAB2(SCH_1):PAGE158_I75@MSTR_ANALOG.FSA3357(CHIPS)':
 C_PATH='@baseboard_fab2_lib.baseboard_fab2(sch_1):page158_i75@mstr_analog.fsa33~
57(chips)',
 P_PATH='@baseboard_fab2_lib.baseboard_fab2(sch_1):page158_i75@mstr_analog.fsa33~
57(chips)',
 PATH='I75',
 DRAWING='@BASEBOARD_FAB2_LIB.BASEBOARD_FAB2(SCH_1):PAGE158',
 SEC_TYPE='SM',
 MATERIAL='IC',
 BOM_COST='DEBUG',
 PHYS_PAGE='158',
 XY='(-2650,850)',
 ROT='0',
 VER='1',
 PACK_TYPE='SM',
 PART_NUMBER='C63273-001',
 LOCATION='U9F1',
 ROOM='UART_MUX',
 SEC='1',
 CDS_LIB='mstr_analog',
 CDS_PART_NAME='FSA3357_SM-IC,C63273-001',
 PRIM_FILE='./archive_libs/mstr_analog/fsa3357/chips/chips.prt';

PART_NAME
 U9F2 'FSA3357_SM-IC,C63273-001':
 ROOM='UART_MUX';

SECTION_NUMBER 1
 '@BASEBOARD_FAB2_LIB.BASEBOARD_FAB2(SCH_1):PAGE158_I74@MSTR_ANALOG.FSA3357(CHIPS)':
 C_PATH='@baseboard_fab2_lib.baseboard_fab2(sch_1):page158_i74@mstr_analog.fsa33~
57(chips)',
 P_PATH='@baseboard_fab2_lib.baseboard_fab2(sch_1):page158_i74@mstr_analog.fsa33~
57(chips)',
 PATH='I74',
 DRAWING='@BASEBOARD_FAB2_LIB.BASEBOARD_FAB2(SCH_1):PAGE158',
 SEC_TYPE='SM',
 MATERIAL='IC',
 BOM_COST='DEBUG',
 PHYS_PAGE='158',
 XY='(-2175,2575)',
 ROT='2',
 VER='1',
 PACK_TYPE='SM',
 PART_NUMBER='C63273-001',
 LOCATION='U9F2',
 ROOM='UART_MUX',
 SEC='1',
 CDS_LIB='mstr_analog',
 CDS_PART_NAME='FSA3357_SM-IC,C63273-001',
 PRIM_FILE='./archive_libs/mstr_analog/fsa3357/chips/chips.prt';

PART_NAME
 U9F3 'TTL1G07_A_SOP-74LVC1G07,IC,C88B':
 ROOM='BMC_MEMORY';

SECTION_NUMBER 1
 '@BASEBOARD_FAB2_LIB.BASEBOARD_FAB2(SCH_1):PAGE151_I56@MSTR_TTL.TTL1G07_A(CHIPS)':
 C_PATH='@baseboard_fab2_lib.baseboard_fab2(sch_1):page151_i56@mstr_ttl.ttl1g07_~
a(chips)',
 P_PATH='@baseboard_fab2_lib.baseboard_fab2(sch_1):page151_i56@mstr_ttl.ttl1g07_~
a(chips)',
 PATH='I56',
 DRAWING='@BASEBOARD_FAB2_LIB.BASEBOARD_FAB2(SCH_1):PAGE151',
 POWER_GROUP='GND=GND;VCC=P3V3_STBY',
 POP='NOPOP',
 SEC_TYPE='SOP',
 MATERIAL='IC',
 PHYS_PAGE='151',
 XY='(2025,1975)',
 ROT='0',
 VER='1',
 VALUE='74LVC1G07',
 PACK_TYPE='SOP',
 PART_NUMBER='C88419-001',
 LOCATION='U9F3',
 ROOM='BMC_MEMORY',
 SEC='1',
 CDS_LIB='mstr_ttl',
 CDS_PART_NAME='TTL1G07_A_SOP-74LVC1G07,IC,C88B',
 PRIM_FILE='./archive_libs/mstr_ttl/ttl1g07_a/chips/chips.prt';

PART_NAME
 U9G1 'GTL2014_SM-IC,D66151-001':
 ROOM='PROC_SIDEBAND';

SECTION_NUMBER 1
 '@BASEBOARD_FAB2_LIB.BASEBOARD_FAB2(SCH_1):PAGE152_I1@MSTR_DIGITAL.GTL2014(CHIPS)':
 C_PATH='@baseboard_fab2_lib.baseboard_fab2(sch_1):page152_i1@mstr_digital.gtl20~
14(chips)',
 P_PATH='@baseboard_fab2_lib.baseboard_fab2(sch_1):page152_i1@mstr_digital.gtl20~
14(chips)',
 PATH='I1',
 DRAWING='@BASEBOARD_FAB2_LIB.BASEBOARD_FAB2(SCH_1):PAGE152',
 SEC_TYPE='SM',
 MATERIAL='IC',
 BOM_COST='PROC_SIDEBAND',
 PHYS_PAGE='152',
 XY='(-5400,4050)',
 ROT='2',
 VER='1',
 PACK_TYPE='SM',
 PART_NUMBER='D66151-001',
 LOCATION='U9G1',
 ROOM='PROC_SIDEBAND',
 SEC='1',
 CDS_LIB='mstr_digital',
 CDS_PART_NAME='GTL2014_SM-IC,D66151-001',
 PRIM_FILE='./archive_libs/mstr_digital/gtl2014/chips/chips.prt';

PART_NAME
 U9P1 'TPS3700_SM-IC,H69492-001':;

SECTION_NUMBER 1
 '@BASEBOARD_FAB2_LIB.BASEBOARD_FAB2(SCH_1):PAGE200_I163@MSTR_VREG.TPS3700(CHIPS)':
 C_PATH='@baseboard_fab2_lib.baseboard_fab2(sch_1):page200_i163@mstr_vreg.tps370~
0(chips)',
 P_PATH='@baseboard_fab2_lib.baseboard_fab2(sch_1):page200_i163@mstr_vreg.tps370~
0(chips)',
 PATH='I163',
 DRAWING='@BASEBOARD_FAB2_LIB.BASEBOARD_FAB2(SCH_1):PAGE200',
 SEC_TYPE='SM',
 MATERIAL='IC',
 PHYS_PAGE='200',
 XY='(-350,350)',
 ROT='0',
 VER='1',
 PACK_TYPE='SM',
 PART_NUMBER='H69492-001',
 LOCATION='U9P1',
 SEC='1',
 CDS_LIB='mstr_vreg',
 CDS_PART_NAME='TPS3700_SM-IC,H69492-001',
 PRIM_FILE='./archive_libs/mstr_vreg/tps3700/chips/chips.prt';

PART_NAME
 U9P2 'TPS3700_SM-IC,H69492-001':;

SECTION_NUMBER 1
 '@BASEBOARD_FAB2_LIB.BASEBOARD_FAB2(SCH_1):PAGE200_I200@MSTR_VREG.TPS3700(CHIPS)':
 C_PATH='@baseboard_fab2_lib.baseboard_fab2(sch_1):page200_i200@mstr_vreg.tps370~
0(chips)',
 P_PATH='@baseboard_fab2_lib.baseboard_fab2(sch_1):page200_i200@mstr_vreg.tps370~
0(chips)',
 PATH='I200',
 DRAWING='@BASEBOARD_FAB2_LIB.BASEBOARD_FAB2(SCH_1):PAGE200',
 MATERIAL='IC',
 PHYS_PAGE='200',
 XY='(-3425,-150)',
 ROT='0',
 VER='1',
 PACK_TYPE='SM',
 PART_NUMBER='H69492-001',
 LOCATION='U9P2',
 CDS_LIB='mstr_vreg',
 CDS_PART_NAME='TPS3700_SM-IC,H69492-001',
 PRIM_FILE='./archive_libs/mstr_vreg/tps3700/chips/chips.prt';

PART_NAME
 U10W1 'TTL1G07_A_SOP-74LVC1G07,IC,C88B':
 ROOM='CPU_FANS';

SECTION_NUMBER 1
 '@BASEBOARD_FAB2_LIB.BASEBOARD_FAB2(SCH_1):PAGE251_I19@MSTR_TTL.TTL1G07_A(CHIPS)':
 C_PATH='@baseboard_fab2_lib.baseboard_fab2(sch_1):page251_i19@mstr_ttl.ttl1g07_~
a(chips)',
 P_PATH='@baseboard_fab2_lib.baseboard_fab2(sch_1):page251_i19@mstr_ttl.ttl1g07_~
a(chips)',
 PATH='I19',
 DRAWING='@BASEBOARD_FAB2_LIB.BASEBOARD_FAB2(SCH_1):PAGE251',
 POWER_GROUP='GND=GND;VCC=P3V3_STBY',
 SEC_TYPE='SOP',
 MATERIAL='IC',
 BOM_COST='SM_THERM',
 PHYS_PAGE='251',
 XY='(-6325,4450)',
 ROT='0',
 VER='1',
 VALUE='74LVC1G07',
 PACK_TYPE='SOP',
 PART_NUMBER='C88419-001',
 LOCATION='U10W1',
 ROOM='CPU_FANS',
 SEC='1',
 CDS_LIB='mstr_ttl',
 CDS_PART_NAME='TTL1G07_A_SOP-74LVC1G07,IC,C88B',
 PRIM_FILE='./archive_libs/mstr_ttl/ttl1g07_a/chips/chips.prt';

PART_NAME
 U14E2 'TTL1G08_SOTLF-NC7SZ08,IC,D1032C':
 ROOM='MIO_CHASSIS';

SECTION_NUMBER 1
 '@BASEBOARD_FAB2_LIB.BASEBOARD_FAB2(SCH_1):PAGE248_I11@MSTR_TTL.TTL1G08(CHIPS)':
 C_PATH='@baseboard_fab2_lib.baseboard_fab2(sch_1):page248_i11@mstr_ttl.ttl1g08(~
chips)',
 P_PATH='@baseboard_fab2_lib.baseboard_fab2(sch_1):page248_i11@mstr_ttl.ttl1g08(~
chips)',
 PATH='I11',
 DRAWING='@BASEBOARD_FAB2_LIB.BASEBOARD_FAB2(SCH_1):PAGE248',
 SIZE='1',
 POWER_GROUP='GND=GND;VCC=P3V3',
 SEC_TYPE='SOTLF',
 MATERIAL='IC',
 BOM_COST='MIO_CHASSIS',
 PHYS_PAGE='248',
 XY='(-3175,1625)',
 ROT='0',
 VER='1',
 VALUE='NC7SZ08',
 PACK_TYPE='SOTLF',
 PART_NUMBER='D10321-001',
 LOCATION='U14E2',
 ROOM='MIO_CHASSIS',
 SEC='1',
 CDS_LIB='mstr_ttl',
 CDS_PART_NAME='TTL1G08_SOTLF-NC7SZ08,IC,D1032C',
 PRIM_FILE='./archive_libs/mstr_ttl/ttl1g08/chips/chips.prt';

PART_NAME
 U14E3 'TTL1G08_SOTLF-NC7SZ08,IC,D1032C':
 ROOM='MIO_CHASSIS';

SECTION_NUMBER 1
 '@BASEBOARD_FAB2_LIB.BASEBOARD_FAB2(SCH_1):PAGE248_I19@MSTR_TTL.TTL1G08(CHIPS)':
 C_PATH='@baseboard_fab2_lib.baseboard_fab2(sch_1):page248_i19@mstr_ttl.ttl1g08(~
chips)',
 P_PATH='@baseboard_fab2_lib.baseboard_fab2(sch_1):page248_i19@mstr_ttl.ttl1g08(~
chips)',
 PATH='I19',
 DRAWING='@BASEBOARD_FAB2_LIB.BASEBOARD_FAB2(SCH_1):PAGE248',
 SIZE='1',
 POWER_GROUP='GND=GND;VCC=P3V3',
 MATERIAL='IC',
 BOM_COST='MIO_CHASSIS',
 PHYS_PAGE='248',
 XY='(-4050,1275)',
 ROT='0',
 VER='1',
 VALUE='NC7SZ08',
 PACK_TYPE='SOTLF',
 PART_NUMBER='D10321-001',
 LOCATION='U14E3',
 ROOM='MIO_CHASSIS',
 CDS_LIB='mstr_ttl',
 CDS_PART_NAME='TTL1G08_SOTLF-NC7SZ08,IC,D1032C',
 PRIM_FILE='./archive_libs/mstr_ttl/ttl1g08/chips/chips.prt';

PART_NAME
 U25W4 'AST2520A1-GP-GP_ASIC2-GB1-AST2A':;

SECTION_NUMBER 1
 '@BASEBOARD_FAB2_LIB.BASEBOARD_FAB2(SCH_1):PAGE143_I63@W_HDL.AST2520A1-GP-GP(CHIPS)':
 C_PATH='@baseboard_fab2_lib.baseboard_fab2(sch_1):page143_i63@w_hdl.\ast2520a1-~
gp-gp\(chips)',
 P_PATH='@baseboard_fab2_lib.baseboard_fab2(sch_1):page143_i63@w_hdl.\ast2520a1-~
gp-gp\(chips)',
 PATH='I63',
 DRAWING='@BASEBOARD_FAB2_LIB.BASEBOARD_FAB2(SCH_1):PAGE143',
 PHYS_PAGE='143',
 XY='(-12850,-1850)',
 ROT='0',
 VER='1',
 VALUE='AST2520A1-GP-GP',
 PACK_TYPE='ASIC2-GB1',
 PART_NUMBER='071.2520A.M001',
 LOCATION='U25W4',
 CDS_LIB='w_hdl',
 CDS_PART_NAME='AST2520A1-GP-GP_ASIC2-GB1-AST2A',
 PRIM_FILE='C:/<user>/w_hdl/ast2520a1#2dgp#2dgp/chips/chips.prt';

SECTION_NUMBER 2
 '@BASEBOARD_FAB2_LIB.BASEBOARD_FAB2(SCH_1):PAGE144_I95@W_HDL.AST2520A1-GP-GP(CHIPS)':
 C_PATH='@baseboard_fab2_lib.baseboard_fab2(sch_1):page144_i95@w_hdl.\ast2520a1-~
gp-gp\(chips)',
 P_PATH='@baseboard_fab2_lib.baseboard_fab2(sch_1):page144_i95@w_hdl.\ast2520a1-~
gp-gp\(chips)',
 PATH='I95',
 DRAWING='@BASEBOARD_FAB2_LIB.BASEBOARD_FAB2(SCH_1):PAGE144',
 PHYS_PAGE='144',
 XY='(-4800,-2600)',
 ROT='0',
 VER='2',
 VALUE='AST2520A1-GP-GP',
 PACK_TYPE='ASIC2-GB1',
 PART_NUMBER='071.2520A.M001',
 LOCATION='U25W4',
 CDS_LIB='w_hdl',
 CDS_PART_NAME='AST2520A1-GP-GP_ASIC2-GB1-AST2A',
 PRIM_FILE='C:/<user>/w_hdl/ast2520a1#2dgp#2dgp/chips/chips.prt';

SECTION_NUMBER 3
 '@BASEBOARD_FAB2_LIB.BASEBOARD_FAB2(SCH_1):PAGE145_I117@W_HDL.AST2520A1-GP-GP(CHIPS)':
 C_PATH='@baseboard_fab2_lib.baseboard_fab2(sch_1):page145_i117@w_hdl.\ast2520a1~
-gp-gp\(chips)',
 P_PATH='@baseboard_fab2_lib.baseboard_fab2(sch_1):page145_i117@w_hdl.\ast2520a1~
-gp-gp\(chips)',
 PATH='I117',
 DRAWING='@BASEBOARD_FAB2_LIB.BASEBOARD_FAB2(SCH_1):PAGE145',
 SEC_TYPE='ASIC2-GB1',
 PHYS_PAGE='145',
 XY='(-3800,-2550)',
 ROT='0',
 VER='3',
 VALUE='AST2520A1-GP-GP',
 PACK_TYPE='ASIC2-GB1',
 PART_NUMBER='071.2520A.M001',
 LOCATION='U25W4',
 SEC='3',
 CDS_LIB='w_hdl',
 CDS_PART_NAME='AST2520A1-GP-GP_ASIC2-GB1-AST2A',
 PRIM_FILE='C:/<user>/w_hdl/ast2520a1#2dgp#2dgp/chips/chips.prt';

SECTION_NUMBER 4
 '@BASEBOARD_FAB2_LIB.BASEBOARD_FAB2(SCH_1):PAGE146_I104@W_HDL.AST2520A1-GP-GP(CHIPS)':
 C_PATH='@baseboard_fab2_lib.baseboard_fab2(sch_1):page146_i104@w_hdl.\ast2520a1~
-gp-gp\(chips)',
 P_PATH='@baseboard_fab2_lib.baseboard_fab2(sch_1):page146_i104@w_hdl.\ast2520a1~
-gp-gp\(chips)',
 PATH='I104',
 DRAWING='@BASEBOARD_FAB2_LIB.BASEBOARD_FAB2(SCH_1):PAGE146',
 PHYS_PAGE='146',
 XY='(-3875,4000)',
 ROT='0',
 VER='4',
 VALUE='AST2520A1-GP-GP',
 PACK_TYPE='ASIC2-GB1',
 PART_NUMBER='071.2520A.M001',
 LOCATION='U25W4',
 CDS_LIB='w_hdl',
 CDS_PART_NAME='AST2520A1-GP-GP_ASIC2-GB1-AST2A',
 PRIM_FILE='C:/<user>/w_hdl/ast2520a1#2dgp#2dgp/chips/chips.prt';

SECTION_NUMBER 5
 '@BASEBOARD_FAB2_LIB.BASEBOARD_FAB2(SCH_1):PAGE146_I105@W_HDL.AST2520A1-GP-GP(CHIPS)':
 C_PATH='@baseboard_fab2_lib.baseboard_fab2(sch_1):page146_i105@w_hdl.\ast2520a1~
-gp-gp\(chips)',
 P_PATH='@baseboard_fab2_lib.baseboard_fab2(sch_1):page146_i105@w_hdl.\ast2520a1~
-gp-gp\(chips)',
 PATH='I105',
 DRAWING='@BASEBOARD_FAB2_LIB.BASEBOARD_FAB2(SCH_1):PAGE146',
 PHYS_PAGE='146',
 XY='(-4025,1850)',
 ROT='0',
 VER='5',
 VALUE='AST2520A1-GP-GP',
 PACK_TYPE='ASIC2-GB1',
 PART_NUMBER='071.2520A.M001',
 LOCATION='U25W4',
 CDS_LIB='w_hdl',
 CDS_PART_NAME='AST2520A1-GP-GP_ASIC2-GB1-AST2A',
 PRIM_FILE='C:/<user>/w_hdl/ast2520a1#2dgp#2dgp/chips/chips.prt';

SECTION_NUMBER 6
 '@BASEBOARD_FAB2_LIB.BASEBOARD_FAB2(SCH_1):PAGE147_I106@W_HDL.AST2520A1-GP-GP(CHIPS)':
 C_PATH='@baseboard_fab2_lib.baseboard_fab2(sch_1):page147_i106@w_hdl.\ast2520a1~
-gp-gp\(chips)',
 P_PATH='@baseboard_fab2_lib.baseboard_fab2(sch_1):page147_i106@w_hdl.\ast2520a1~
-gp-gp\(chips)',
 PATH='I106',
 DRAWING='@BASEBOARD_FAB2_LIB.BASEBOARD_FAB2(SCH_1):PAGE147',
 SEC_TYPE='ASIC2-GB1',
 PHYS_PAGE='147',
 XY='(-1825,3400)',
 ROT='0',
 VER='6',
 VALUE='AST2520A1-GP-GP',
 PACK_TYPE='ASIC2-GB1',
 PART_NUMBER='071.2520A.M001',
 LOCATION='U25W4',
 SEC='6',
 CDS_LIB='w_hdl',
 CDS_PART_NAME='AST2520A1-GP-GP_ASIC2-GB1-AST2A',
 PRIM_FILE='C:/<user>/w_hdl/ast2520a1#2dgp#2dgp/chips/chips.prt';

SECTION_NUMBER 7
 '@BASEBOARD_FAB2_LIB.BASEBOARD_FAB2(SCH_1):PAGE148_I28@W_HDL.AST2520A1-GP-GP(CHIPS)':
 C_PATH='@baseboard_fab2_lib.baseboard_fab2(sch_1):page148_i28@w_hdl.\ast2520a1-~
gp-gp\(chips)',
 P_PATH='@baseboard_fab2_lib.baseboard_fab2(sch_1):page148_i28@w_hdl.\ast2520a1-~
gp-gp\(chips)',
 PATH='I28',
 DRAWING='@BASEBOARD_FAB2_LIB.BASEBOARD_FAB2(SCH_1):PAGE148',
 PHYS_PAGE='148',
 XY='(-3600,2600)',
 ROT='0',
 VER='7',
 VALUE='AST2520A1-GP-GP',
 PACK_TYPE='ASIC2-GB1',
 PART_NUMBER='071.2520A.M001',
 CDS_LIB='w_hdl',
 CDS_PART_NAME='AST2520A1-GP-GP_ASIC2-GB1-AST2A',
 PRIM_FILE='C:/<user>/w_hdl/ast2520a1#2dgp#2dgp/chips/chips.prt';

PART_NAME
 U25W5 'H5AN4G6NAFR-TFC-GP_MEMORY-G2-HA':;

SECTION_NUMBER 1
 '@BASEBOARD_FAB2_LIB.BASEBOARD_FAB2(SCH_1):PAGE151_I49@W_HDL.H5AN4G6NAFR-TFC-GP(CHIPS)':
 C_PATH='@baseboard_fab2_lib.baseboard_fab2(sch_1):page151_i49@w_hdl.\h5an4g6naf~
r-tfc-gp\(chips)',
 P_PATH='@baseboard_fab2_lib.baseboard_fab2(sch_1):page151_i49@w_hdl.\h5an4g6naf~
r-tfc-gp\(chips)',
 PATH='I49',
 DRAWING='@BASEBOARD_FAB2_LIB.BASEBOARD_FAB2(SCH_1):PAGE151',
 PHYS_PAGE='151',
 XY='(2650,25)',
 ROT='0',
 VER='1',
 VALUE='H5AN4G6NAFR-TFC-GP',
 PACK_TYPE='MEMORY-G2',
 PART_NUMBER='072.00546.0A0U',
 LOCATION='U25W5',
 CDS_LIB='w_hdl',
 CDS_PART_NAME='H5AN4G6NAFR-TFC-GP_MEMORY-G2-HA',
 PRIM_FILE='C:/<user>/w_hdl/h5an4g6nafr#2dtfc#2dgp/chips/chips.prt';

PART_NAME
 U25W7 'U74AHCT1G125G-AL5-R-GP-U_TTL-GA':
 GROUP='AST2500';

SECTION_NUMBER 1
 '@BASEBOARD_FAB2_LIB.BASEBOARD_FAB2(SCH_1):PAGE255_I111@W_HDL.U74AHCT1G125G-AL5-R-GP-U(CHIPS)':
 C_PATH='@baseboard_fab2_lib.baseboard_fab2(sch_1):page255_i111@w_hdl.\u74ahct1g~
125g-al5-r-gp-u\(chips)',
 P_PATH='@baseboard_fab2_lib.baseboard_fab2(sch_1):page252_i111@w_hdl.\u74ahct1g~
125g-al5-r-gp-u\(chips)',
 PATH='I111',
 DRAWING='@BASEBOARD_FAB2_LIB.BASEBOARD_FAB2(SCH_1):PAGE255',
 SEC_TYPE='TTL-G4',
 PHYS_PAGE='252',
 XY='(-4350,5100)',
 ROT='0',
 VER='1',
 VALUE='U74AHCT1G125G-AL5-R-GP-U',
 PACK_TYPE='TTL-G4',
 PART_NUMBER='73.1G125.D0G',
 LOCATION='U25W7',
 GROUP='AST2500',
 SEC='1',
 CDS_LIB='w_hdl',
 CDS_PART_NAME='U74AHCT1G125G-AL5-R-GP-U_TTL-GA',
 PRIM_FILE='C:/<user>/w_hdl/u74ahct1g125g#2dal5#2dr#2dgp#2du/chips/chips.prt~
';

PART_NAME
 U25W8 'U74AHCT1G125G-AL5-R-GP-U_TTL-GA':
 GROUP='AST2500';

SECTION_NUMBER 1
 '@BASEBOARD_FAB2_LIB.BASEBOARD_FAB2(SCH_1):PAGE255_I112@W_HDL.U74AHCT1G125G-AL5-R-GP-U(CHIPS)':
 C_PATH='@baseboard_fab2_lib.baseboard_fab2(sch_1):page255_i112@w_hdl.\u74ahct1g~
125g-al5-r-gp-u\(chips)',
 P_PATH='@baseboard_fab2_lib.baseboard_fab2(sch_1):page252_i112@w_hdl.\u74ahct1g~
125g-al5-r-gp-u\(chips)',
 PATH='I112',
 DRAWING='@BASEBOARD_FAB2_LIB.BASEBOARD_FAB2(SCH_1):PAGE255',
 SEC_TYPE='TTL-G4',
 PHYS_PAGE='252',
 XY='(-4350,4550)',
 ROT='0',
 VER='1',
 VALUE='U74AHCT1G125G-AL5-R-GP-U',
 PACK_TYPE='TTL-G4',
 PART_NUMBER='73.1G125.D0G',
 LOCATION='U25W8',
 GROUP='AST2500',
 SEC='1',
 CDS_LIB='w_hdl',
 CDS_PART_NAME='U74AHCT1G125G-AL5-R-GP-U_TTL-GA',
 PRIM_FILE='C:/<user>/w_hdl/u74ahct1g125g#2dal5#2dr#2dgp#2du/chips/chips.prt~
';

PART_NAME
 U25W9 'TTL1G07_A_SOP-74LVC1G07,IC,C88B':;

SECTION_NUMBER 1
 '@BASEBOARD_FAB2_LIB.BASEBOARD_FAB2(SCH_1):PAGE157_I394@MSTR_TTL.TTL1G07_A(CHIPS)':
 C_PATH='@baseboard_fab2_lib.baseboard_fab2(sch_1):page157_i394@mstr_ttl.ttl1g07~
_a(chips)',
 P_PATH='@baseboard_fab2_lib.baseboard_fab2(sch_1):page157_i394@mstr_ttl.ttl1g07~
_a(chips)',
 PATH='I394',
 DRAWING='@BASEBOARD_FAB2_LIB.BASEBOARD_FAB2(SCH_1):PAGE157',
 POWER_GROUP='GND=GND;VCC=P3V3_STBY',
 SEC_TYPE='SOP',
 MATERIAL='IC',
 PHYS_PAGE='157',
 XY='(-2800,500)',
 ROT='0',
 VER='1',
 VALUE='74LVC1G07',
 PACK_TYPE='SOP',
 PART_NUMBER='C88419-001',
 LOCATION='U25W9',
 SEC='1',
 CDS_LIB='mstr_ttl',
 CDS_PART_NAME='TTL1G07_A_SOP-74LVC1G07,IC,C88B',
 PRIM_FILE='./archive_libs/mstr_ttl/ttl1g07_a/chips/chips.prt';

PART_NAME
 U25W10 'GTL2014_SM-IC,D66151-001':
 ROOM='PROC_RSTS_PGOODS';

SECTION_NUMBER 1
 '@BASEBOARD_FAB2_LIB.BASEBOARD_FAB2(SCH_1):PAGE269_I49@MSTR_DIGITAL.GTL2014(CHIPS)':
 C_PATH='@baseboard_fab2_lib.baseboard_fab2(sch_1):page269_i49@mstr_digital.gtl2~
014(chips)',
 P_PATH='@baseboard_fab2_lib.baseboard_fab2(sch_1):page254_i49@mstr_digital.gtl2~
014(chips)',
 PATH='I49',
 DRAWING='@BASEBOARD_FAB2_LIB.BASEBOARD_FAB2(SCH_1):PAGE269',
 MATERIAL='IC',
 BOM_COST='PROC_SIDEBAND',
 PHYS_PAGE='254',
 XY='(-4950,5500)',
 ROT='0',
 VER='1',
 PACK_TYPE='SM',
 PART_NUMBER='D66151-001',
 LOCATION='U25W10',
 ROOM='PROC_RSTS_PGOODS',
 CDS_LIB='mstr_digital',
 CDS_PART_NAME='GTL2014_SM-IC,D66151-001',
 PRIM_FILE='./archive_libs/mstr_digital/gtl2014/chips/chips.prt';

PART_NAME
 U25W11 'GTL2014_SM-IC,D66151-001':
 ROOM='PROC_SIDEBAND';

SECTION_NUMBER 1
 '@BASEBOARD_FAB2_LIB.BASEBOARD_FAB2(SCH_1):PAGE268_I33@MSTR_DIGITAL.GTL2014(CHIPS)':
 C_PATH='@baseboard_fab2_lib.baseboard_fab2(sch_1):page268_i33@mstr_digital.gtl2~
014(chips)',
 P_PATH='@baseboard_fab2_lib.baseboard_fab2(sch_1):page255_i33@mstr_digital.gtl2~
014(chips)',
 PATH='I33',
 DRAWING='@BASEBOARD_FAB2_LIB.BASEBOARD_FAB2(SCH_1):PAGE268',
 SEC_TYPE='SM',
 MATERIAL='IC',
 BOM_COST='PROC_SIDEBAND',
 PHYS_PAGE='255',
 XY='(-7200,5300)',
 ROT='2',
 VER='1',
 PACK_TYPE='SM',
 PART_NUMBER='D66151-001',
 LOCATION='U25W11',
 ROOM='PROC_SIDEBAND',
 SEC='1',
 CDS_LIB='mstr_digital',
 CDS_PART_NAME='GTL2014_SM-IC,D66151-001',
 PRIM_FILE='./archive_libs/mstr_digital/gtl2014/chips/chips.prt';

PART_NAME
 U25W12 'TTL3126_QFNLF-74CBTLV3126,IC,DB':
 ROOM='DEBUG';

SECTION_NUMBER 1
 '@BASEBOARD_FAB2_LIB.BASEBOARD_FAB2(SCH_1):PAGE269_I33@MSTR_TTL.TTL3126(CHIPS)'(3):
 C_PATH='@baseboard_fab2_lib.baseboard_fab2(sch_1):page269_i33(3)@mstr_ttl.ttl31~
26(chips)',
 P_PATH='@baseboard_fab2_lib.baseboard_fab2(sch_1):page254_i33(3)@mstr_ttl.ttl31~
26(chips)',
 PATH='I33',
 DRAWING='@BASEBOARD_FAB2_LIB.BASEBOARD_FAB2(SCH_1):PAGE269',
 SIZE='4',
 POWER_GROUP='GND=GND;VCC=P3V3_STBY',
 MATERIAL='IC',
 PHYS_PAGE='254',
 XY='(-3700,3750)',
 ROT='0',
 VER='3',
 VALUE='74CBTLV3126',
 PACK_TYPE='QFNLF',
 PART_NUMBER='D18317-001',
 LOCATION='U25W12',
 HAS_FIXED_SIZE='4',
 ROOM='DEBUG',
 CDS_LIB='mstr_ttl',
 CDS_PART_NAME='TTL3126_QFNLF-74CBTLV3126,IC,DB',
 PRIM_FILE='./archive_libs/mstr_ttl/ttl3126/chips/chips.prt';

SECTION_NUMBER 2
 '@BASEBOARD_FAB2_LIB.BASEBOARD_FAB2(SCH_1):PAGE269_I33@MSTR_TTL.TTL3126(CHIPS)'(2):
 C_PATH='@baseboard_fab2_lib.baseboard_fab2(sch_1):page269_i33(2)@mstr_ttl.ttl31~
26(chips)',
 P_PATH='@baseboard_fab2_lib.baseboard_fab2(sch_1):page254_i33(2)@mstr_ttl.ttl31~
26(chips)',
 PATH='I33',
 DRAWING='@BASEBOARD_FAB2_LIB.BASEBOARD_FAB2(SCH_1):PAGE269',
 SIZE='4',
 POWER_GROUP='GND=GND;VCC=P3V3_STBY',
 MATERIAL='IC',
 PHYS_PAGE='254',
 XY='(-3700,3750)',
 ROT='0',
 VER='3',
 VALUE='74CBTLV3126',
 PACK_TYPE='QFNLF',
 PART_NUMBER='D18317-001',
 LOCATION='U25W12',
 HAS_FIXED_SIZE='4',
 ROOM='DEBUG',
 CDS_LIB='mstr_ttl',
 CDS_PART_NAME='TTL3126_QFNLF-74CBTLV3126,IC,DB',
 PRIM_FILE='./archive_libs/mstr_ttl/ttl3126/chips/chips.prt';

SECTION_NUMBER 3
 '@BASEBOARD_FAB2_LIB.BASEBOARD_FAB2(SCH_1):PAGE269_I33@MSTR_TTL.TTL3126(CHIPS)'(1):
 C_PATH='@baseboard_fab2_lib.baseboard_fab2(sch_1):page269_i33(1)@mstr_ttl.ttl31~
26(chips)',
 P_PATH='@baseboard_fab2_lib.baseboard_fab2(sch_1):page254_i33(1)@mstr_ttl.ttl31~
26(chips)',
 PATH='I33',
 DRAWING='@BASEBOARD_FAB2_LIB.BASEBOARD_FAB2(SCH_1):PAGE269',
 SIZE='4',
 POWER_GROUP='GND=GND;VCC=P3V3_STBY',
 MATERIAL='IC',
 PHYS_PAGE='254',
 XY='(-3700,3750)',
 ROT='0',
 VER='3',
 VALUE='74CBTLV3126',
 PACK_TYPE='QFNLF',
 PART_NUMBER='D18317-001',
 LOCATION='U25W12',
 HAS_FIXED_SIZE='4',
 ROOM='DEBUG',
 CDS_LIB='mstr_ttl',
 CDS_PART_NAME='TTL3126_QFNLF-74CBTLV3126,IC,DB',
 PRIM_FILE='./archive_libs/mstr_ttl/ttl3126/chips/chips.prt';

SECTION_NUMBER 4
 '@BASEBOARD_FAB2_LIB.BASEBOARD_FAB2(SCH_1):PAGE269_I33@MSTR_TTL.TTL3126(CHIPS)'(0):
 C_PATH='@baseboard_fab2_lib.baseboard_fab2(sch_1):page269_i33(0)@mstr_ttl.ttl31~
26(chips)',
 P_PATH='@baseboard_fab2_lib.baseboard_fab2(sch_1):page254_i33(0)@mstr_ttl.ttl31~
26(chips)',
 PATH='I33',
 DRAWING='@BASEBOARD_FAB2_LIB.BASEBOARD_FAB2(SCH_1):PAGE269',
 SIZE='4',
 POWER_GROUP='GND=GND;VCC=P3V3_STBY',
 MATERIAL='IC',
 PHYS_PAGE='254',
 XY='(-3700,3750)',
 ROT='0',
 VER='3',
 VALUE='74CBTLV3126',
 PACK_TYPE='QFNLF',
 PART_NUMBER='D18317-001',
 LOCATION='U25W12',
 HAS_FIXED_SIZE='4',
 ROOM='DEBUG',
 CDS_LIB='mstr_ttl',
 CDS_PART_NAME='TTL3126_QFNLF-74CBTLV3126,IC,DB',
 PRIM_FILE='./archive_libs/mstr_ttl/ttl3126/chips/chips.prt';

PART_NAME
 U25W13 'MAX4564EKA-GP_SCRET-GC1-MAX456A':;

SECTION_NUMBER 1
 '@BASEBOARD_FAB2_LIB.BASEBOARD_FAB2(SCH_1):PAGE269_I53@W_HDL.MAX4564EKA-GP(CHIPS)':
 C_PATH='@baseboard_fab2_lib.baseboard_fab2(sch_1):page269_i53@w_hdl.\max4564eka~
-gp\(chips)',
 P_PATH='@baseboard_fab2_lib.baseboard_fab2(sch_1):page254_i53@w_hdl.\max4564eka~
-gp\(chips)',
 PATH='I53',
 DRAWING='@BASEBOARD_FAB2_LIB.BASEBOARD_FAB2(SCH_1):PAGE269',
 SEC_TYPE='SCRET-GC1',
 PHYS_PAGE='254',
 XY='(-7075,3625)',
 ROT='0',
 VER='1',
 VALUE='MAX4564EKA-GP',
 PACK_TYPE='SCRET-GC1',
 PART_NUMBER='074.04564.0099',
 LOCATION='U25W13',
 SEC='1',
 CDS_LIB='w_hdl',
 CDS_PART_NAME='MAX4564EKA-GP_SCRET-GC1-MAX456A',
 PRIM_FILE='C:/<user>/w_hdl/max4564eka#2dgp/chips/chips.prt';

PART_NAME
 U25W14 'TTL1G07_A_SOP-74LVC1G07,IC,C88B':
 ROOM='CPU_FANS';

SECTION_NUMBER 1
 '@BASEBOARD_FAB2_LIB.BASEBOARD_FAB2(SCH_1):PAGE268_I13@MSTR_TTL.TTL1G07_A(CHIPS)':
 C_PATH='@baseboard_fab2_lib.baseboard_fab2(sch_1):page268_i13@mstr_ttl.ttl1g07_~
a(chips)',
 P_PATH='@baseboard_fab2_lib.baseboard_fab2(sch_1):page255_i13@mstr_ttl.ttl1g07_~
a(chips)',
 PATH='I13',
 DRAWING='@BASEBOARD_FAB2_LIB.BASEBOARD_FAB2(SCH_1):PAGE268',
 POWER_GROUP='GND=GND;VCC=P3V3_STBY',
 SEC_TYPE='SOP',
 MATERIAL='IC',
 BOM_COST='SM_THERM',
 PHYS_PAGE='255',
 XY='(-6300,3900)',
 ROT='0',
 VER='1',
 VALUE='74LVC1G07',
 PACK_TYPE='SOP',
 PART_NUMBER='C88419-001',
 LOCATION='U25W14',
 ROOM='CPU_FANS',
 SEC='1',
 CDS_LIB='mstr_ttl',
 CDS_PART_NAME='TTL1G07_A_SOP-74LVC1G07,IC,C88B',
 PRIM_FILE='./archive_libs/mstr_ttl/ttl1g07_a/chips/chips.prt';

PART_NAME
 U25W15 'TTL1G07_A_SOP-74LVC1G07,IC,C88B':
 ROOM='CPU_FANS';

SECTION_NUMBER 1
 '@BASEBOARD_FAB2_LIB.BASEBOARD_FAB2(SCH_1):PAGE268_I12@MSTR_TTL.TTL1G07_A(CHIPS)':
 C_PATH='@baseboard_fab2_lib.baseboard_fab2(sch_1):page268_i12@mstr_ttl.ttl1g07_~
a(chips)',
 P_PATH='@baseboard_fab2_lib.baseboard_fab2(sch_1):page255_i12@mstr_ttl.ttl1g07_~
a(chips)',
 PATH='I12',
 DRAWING='@BASEBOARD_FAB2_LIB.BASEBOARD_FAB2(SCH_1):PAGE268',
 POWER_GROUP='GND=GND;VCC=P3V3_STBY',
 SEC_TYPE='SOP',
 MATERIAL='IC',
 BOM_COST='SM_THERM',
 PHYS_PAGE='255',
 XY='(-6300,3100)',
 ROT='0',
 VER='1',
 VALUE='74LVC1G07',
 PACK_TYPE='SOP',
 PART_NUMBER='C88419-001',
 LOCATION='U25W15',
 ROOM='CPU_FANS',
 SEC='1',
 CDS_LIB='mstr_ttl',
 CDS_PART_NAME='TTL1G07_A_SOP-74LVC1G07,IC,C88B',
 PRIM_FILE='./archive_libs/mstr_ttl/ttl1g07_a/chips/chips.prt';

PART_NAME
 U25W16 'TTL3126_QFNLF-74CBTLV3126,IC,DB':
 ROOM='DEBUG';

SECTION_NUMBER 1
 '@BASEBOARD_FAB2_LIB.BASEBOARD_FAB2(SCH_1):PAGE268_I38@MSTR_TTL.TTL3126(CHIPS)'(3):
 C_PATH='@baseboard_fab2_lib.baseboard_fab2(sch_1):page268_i38(3)@mstr_ttl.ttl31~
26(chips)',
 P_PATH='@baseboard_fab2_lib.baseboard_fab2(sch_1):page255_i38(3)@mstr_ttl.ttl31~
26(chips)',
 PATH='I38',
 DRAWING='@BASEBOARD_FAB2_LIB.BASEBOARD_FAB2(SCH_1):PAGE268',
 SIZE='4',
 POWER_GROUP='GND=GND;VCC=P3V3_STBY',
 MATERIAL='IC',
 PHYS_PAGE='255',
 XY='(-2900,5000)',
 ROT='0',
 VER='3',
 VALUE='74CBTLV3126',
 PACK_TYPE='QFNLF',
 PART_NUMBER='D18317-001',
 LOCATION='U25W16',
 HAS_FIXED_SIZE='4',
 ROOM='DEBUG',
 CDS_LIB='mstr_ttl',
 CDS_PART_NAME='TTL3126_QFNLF-74CBTLV3126,IC,DB',
 PRIM_FILE='./archive_libs/mstr_ttl/ttl3126/chips/chips.prt';

SECTION_NUMBER 2
 '@BASEBOARD_FAB2_LIB.BASEBOARD_FAB2(SCH_1):PAGE268_I38@MSTR_TTL.TTL3126(CHIPS)'(2):
 C_PATH='@baseboard_fab2_lib.baseboard_fab2(sch_1):page268_i38(2)@mstr_ttl.ttl31~
26(chips)',
 P_PATH='@baseboard_fab2_lib.baseboard_fab2(sch_1):page255_i38(2)@mstr_ttl.ttl31~
26(chips)',
 PATH='I38',
 DRAWING='@BASEBOARD_FAB2_LIB.BASEBOARD_FAB2(SCH_1):PAGE268',
 SIZE='4',
 POWER_GROUP='GND=GND;VCC=P3V3_STBY',
 MATERIAL='IC',
 PHYS_PAGE='255',
 XY='(-2900,5000)',
 ROT='0',
 VER='3',
 VALUE='74CBTLV3126',
 PACK_TYPE='QFNLF',
 PART_NUMBER='D18317-001',
 LOCATION='U25W16',
 HAS_FIXED_SIZE='4',
 ROOM='DEBUG',
 CDS_LIB='mstr_ttl',
 CDS_PART_NAME='TTL3126_QFNLF-74CBTLV3126,IC,DB',
 PRIM_FILE='./archive_libs/mstr_ttl/ttl3126/chips/chips.prt';

SECTION_NUMBER 3
 '@BASEBOARD_FAB2_LIB.BASEBOARD_FAB2(SCH_1):PAGE268_I38@MSTR_TTL.TTL3126(CHIPS)'(1):
 C_PATH='@baseboard_fab2_lib.baseboard_fab2(sch_1):page268_i38(1)@mstr_ttl.ttl31~
26(chips)',
 P_PATH='@baseboard_fab2_lib.baseboard_fab2(sch_1):page255_i38(1)@mstr_ttl.ttl31~
26(chips)',
 PATH='I38',
 DRAWING='@BASEBOARD_FAB2_LIB.BASEBOARD_FAB2(SCH_1):PAGE268',
 SIZE='4',
 POWER_GROUP='GND=GND;VCC=P3V3_STBY',
 MATERIAL='IC',
 PHYS_PAGE='255',
 XY='(-2900,5000)',
 ROT='0',
 VER='3',
 VALUE='74CBTLV3126',
 PACK_TYPE='QFNLF',
 PART_NUMBER='D18317-001',
 LOCATION='U25W16',
 HAS_FIXED_SIZE='4',
 ROOM='DEBUG',
 CDS_LIB='mstr_ttl',
 CDS_PART_NAME='TTL3126_QFNLF-74CBTLV3126,IC,DB',
 PRIM_FILE='./archive_libs/mstr_ttl/ttl3126/chips/chips.prt';

SECTION_NUMBER 4
 '@BASEBOARD_FAB2_LIB.BASEBOARD_FAB2(SCH_1):PAGE268_I38@MSTR_TTL.TTL3126(CHIPS)'(0):
 C_PATH='@baseboard_fab2_lib.baseboard_fab2(sch_1):page268_i38(0)@mstr_ttl.ttl31~
26(chips)',
 P_PATH='@baseboard_fab2_lib.baseboard_fab2(sch_1):page255_i38(0)@mstr_ttl.ttl31~
26(chips)',
 PATH='I38',
 DRAWING='@BASEBOARD_FAB2_LIB.BASEBOARD_FAB2(SCH_1):PAGE268',
 SIZE='4',
 POWER_GROUP='GND=GND;VCC=P3V3_STBY',
 MATERIAL='IC',
 PHYS_PAGE='255',
 XY='(-2900,5000)',
 ROT='0',
 VER='3',
 VALUE='74CBTLV3126',
 PACK_TYPE='QFNLF',
 PART_NUMBER='D18317-001',
 LOCATION='U25W16',
 HAS_FIXED_SIZE='4',
 ROOM='DEBUG',
 CDS_LIB='mstr_ttl',
 CDS_PART_NAME='TTL3126_QFNLF-74CBTLV3126,IC,DB',
 PRIM_FILE='./archive_libs/mstr_ttl/ttl3126/chips/chips.prt';

PART_NAME
 U25W17 'TTL1G08_SOTLF-NC7SZ08,IC,D1032B':
 ROOM='CAT_ERR';

SECTION_NUMBER 1
 '@BASEBOARD_FAB2_LIB.BASEBOARD_FAB2(SCH_1):PAGE269_I61@MSTR_TTL.TTL1G08(CHIPS)':
 C_PATH='@baseboard_fab2_lib.baseboard_fab2(sch_1):page269_i61@mstr_ttl.ttl1g08(~
chips)',
 P_PATH='@baseboard_fab2_lib.baseboard_fab2(sch_1):page254_i61@mstr_ttl.ttl1g08(~
chips)',
 PATH='I61',
 DRAWING='@BASEBOARD_FAB2_LIB.BASEBOARD_FAB2(SCH_1):PAGE269',
 SIZE='1',
 POWER_GROUP='GND=GND;VCC=P3V3_STBY',
 SEC_TYPE='SOTLF',
 MATERIAL='IC',
 BOM_COST='PROC_SIDEBAND',
 PHYS_PAGE='254',
 XY='(-5100,4000)',
 ROT='0',
 VER='1',
 VALUE='NC7SZ08',
 PACK_TYPE='SOTLF',
 PART_NUMBER='D10321-001',
 LOCATION='U25W17',
 ROOM='CAT_ERR',
 SEC='1',
 CDS_LIB='mstr_ttl',
 CDS_PART_NAME='TTL1G08_SOTLF-NC7SZ08,IC,D1032B',
 PRIM_FILE='./archive_libs/mstr_ttl/ttl1g08/chips/chips.prt';

PART_NAME
 U25W18 'TTL1G08_SOTLF-NC7SZ08,IC,D1032B':
 ROOM='CAT_ERR';

SECTION_NUMBER 1
 '@BASEBOARD_FAB2_LIB.BASEBOARD_FAB2(SCH_1):PAGE268_I57@MSTR_TTL.TTL1G08(CHIPS)':
 C_PATH='@baseboard_fab2_lib.baseboard_fab2(sch_1):page268_i57@mstr_ttl.ttl1g08(~
chips)',
 P_PATH='@baseboard_fab2_lib.baseboard_fab2(sch_1):page255_i57@mstr_ttl.ttl1g08(~
chips)',
 PATH='I57',
 DRAWING='@BASEBOARD_FAB2_LIB.BASEBOARD_FAB2(SCH_1):PAGE268',
 SIZE='1',
 POWER_GROUP='GND=GND;VCC=P3V3_STBY',
 SEC_TYPE='SOTLF',
 MATERIAL='IC',
 BOM_COST='PROC_SIDEBAND',
 PHYS_PAGE='255',
 XY='(-3400,4200)',
 ROT='0',
 VER='1',
 VALUE='NC7SZ08',
 PACK_TYPE='SOTLF',
 PART_NUMBER='D10321-001',
 LOCATION='U25W18',
 ROOM='CAT_ERR',
 SEC='1',
 CDS_LIB='mstr_ttl',
 CDS_PART_NAME='TTL1G08_SOTLF-NC7SZ08,IC,D1032B',
 PRIM_FILE='./archive_libs/mstr_ttl/ttl1g08/chips/chips.prt';

PART_NAME
 U25W19 'TTL1G126_A_SOT-74HC1G126,IC,A7B':
 ROOM='SB';

SECTION_NUMBER 1
 '@BASEBOARD_FAB2_LIB.BASEBOARD_FAB2(SCH_1):PAGE269_I76@MSTR_TTL.TTL1G126_A(CHIPS)':
 C_PATH='@baseboard_fab2_lib.baseboard_fab2(sch_1):page269_i76@mstr_ttl.ttl1g126~
_a(chips)',
 P_PATH='@baseboard_fab2_lib.baseboard_fab2(sch_1):page254_i76@mstr_ttl.ttl1g126~
_a(chips)',
 PATH='I76',
 DRAWING='@BASEBOARD_FAB2_LIB.BASEBOARD_FAB2(SCH_1):PAGE269',
 POWER_GROUP='GND=GND;VCC=P3V3_STBY',
 SEC_TYPE='SOT',
 MATERIAL='IC',
 BOM_COST='SB',
 PHYS_PAGE='254',
 XY='(-7850,4750)',
 ROT='6',
 VER='1',
 VALUE='74HC1G126',
 PACK_TYPE='SOT',
 PART_NUMBER='A79322-001',
 LOCATION='U25W19',
 ROOM='SB',
 SEC='1',
 CDS_LIB='mstr_ttl',
 CDS_PART_NAME='TTL1G126_A_SOT-74HC1G126,IC,A7B',
 PRIM_FILE='./archive_libs/mstr_ttl/ttl1g126_a/chips/chips.prt';

PART_NAME
 U32W1 'TCA9517DGKR-GP_DISCRET-G8-TCA9A':;

SECTION_NUMBER 1
 '@BASEBOARD_FAB2_LIB.BASEBOARD_FAB2(SCH_1):PAGE185_I191@W_HDL.TCA9517DGKR-GP(CHIPS)':
 C_PATH='@baseboard_fab2_lib.baseboard_fab2(sch_1):page185_i191@w_hdl.\tca9517dg~
kr-gp\(chips)',
 P_PATH='@baseboard_fab2_lib.baseboard_fab2(sch_1):page185_i191@w_hdl.\tca9517dg~
kr-gp\(chips)',
 PATH='I191',
 DRAWING='@BASEBOARD_FAB2_LIB.BASEBOARD_FAB2(SCH_1):PAGE185',
 SEC_TYPE='DISCRET-G8',
 PHYS_PAGE='185',
 XY='(-1725,2900)',
 ROT='0',
 VER='1',
 VALUE='TCA9517DGKR-GP',
 PACK_TYPE='DISCRET-G8',
 PART_NUMBER='071.09517.0009',
 LOCATION='U32W1',
 SEC='1',
 CDS_LIB='w_hdl',
 CDS_PART_NAME='TCA9517DGKR-GP_DISCRET-G8-TCA9A',
 PRIM_FILE='C:/<user>/w_hdl/tca9517dgkr#2dgp/chips/chips.prt';

PART_NAME
 U32W2 'TCA9517DGKR-GP_DISCRET-G8-TCA9A':;

SECTION_NUMBER 1
 '@BASEBOARD_FAB2_LIB.BASEBOARD_FAB2(SCH_1):PAGE185_I204@W_HDL.TCA9517DGKR-GP(CHIPS)':
 C_PATH='@baseboard_fab2_lib.baseboard_fab2(sch_1):page185_i204@w_hdl.\tca9517dg~
kr-gp\(chips)',
 P_PATH='@baseboard_fab2_lib.baseboard_fab2(sch_1):page185_i204@w_hdl.\tca9517dg~
kr-gp\(chips)',
 PATH='I204',
 DRAWING='@BASEBOARD_FAB2_LIB.BASEBOARD_FAB2(SCH_1):PAGE185',
 SEC_TYPE='DISCRET-G8',
 PHYS_PAGE='185',
 XY='(-1725,3675)',
 ROT='0',
 VER='1',
 VALUE='TCA9517DGKR-GP',
 PACK_TYPE='DISCRET-G8',
 PART_NUMBER='071.09517.0009',
 LOCATION='U32W2',
 SEC='1',
 CDS_LIB='w_hdl',
 CDS_PART_NAME='TCA9517DGKR-GP_DISCRET-G8-TCA9A',
 PRIM_FILE='C:/<user>/w_hdl/tca9517dgkr#2dgp/chips/chips.prt';

PART_NAME
 UN8F2 'W25Q256_XSOI-IC,H25002-001':
 ROOM='BMC_BOOT_SPI';

SECTION_NUMBER 1
 '@BASEBOARD_FAB2_LIB.BASEBOARD_FAB2(SCH_1):PAGE246_I17@MSTR_MEMORY.W25Q256(CHIPS)':
 C_PATH='@baseboard_fab2_lib.baseboard_fab2(sch_1):page246_i17@mstr_memory.w25q2~
56(chips)',
 P_PATH='@baseboard_fab2_lib.baseboard_fab2(sch_1):page246_i17@mstr_memory.w25q2~
56(chips)',
 PATH='I17',
 DRAWING='@BASEBOARD_FAB2_LIB.BASEBOARD_FAB2(SCH_1):PAGE246',
 SEC_TYPE='XSOI',
 MATERIAL='IC',
 BOM_COST='SM_MEM',
 PHYS_PAGE='246',
 XY='(-3675,2750)',
 ROT='0',
 VER='1',
 PACK_TYPE='XSOI',
 PART_NUMBER='H25002-001',
 LOCATION='UN8F2',
 ROOM='BMC_BOOT_SPI',
 SEC='1',
 CDS_LIB='mstr_memory',
 CDS_PART_NAME='W25Q256_XSOI-IC,H25002-001',
 PRIM_FILE='./archive_libs/mstr_memory/w25q256/chips/chips.prt';

PART_NAME
 VR1D1 'ZENER_SM-13V,IC,H69095-001':;

SECTION_NUMBER 1
 '@BASEBOARD_FAB2_LIB.BASEBOARD_FAB2(SCH_1):PAGE199_I99@MSTR_DISCRETE.ZENER(CHIPS)':
 C_PATH='@baseboard_fab2_lib.baseboard_fab2(sch_1):page199_i99@mstr_discrete.zen~
er(chips)',
 P_PATH='@baseboard_fab2_lib.baseboard_fab2(sch_1):page199_i99@mstr_discrete.zen~
er(chips)',
 PATH='I99',
 DRAWING='@BASEBOARD_FAB2_LIB.BASEBOARD_FAB2(SCH_1):PAGE199',
 NEW_PN='083.01514.00AD',
 NEW_VALUE='14V',
 SEC_TYPE='SM',
 MATERIAL='IC',
 PHYS_PAGE='199',
 XY='(-5100,3875)',
 ROT='0',
 VER='4',
 VALUE='13V',
 PACK_TYPE='SM',
 PART_NUMBER='H69095-001',
 LOCATION='VR1D1',
 SEC='1',
 CDS_LIB='mstr_discrete',
 CDS_PART_NAME='ZENER_SM-13V,IC,H69095-001',
 PRIM_FILE='./archive_libs/mstr_discrete/zener/chips/chips.prt';

PART_NAME
 VR32W1 'LMV431AIMFX-GP_DISCRET-G5-LMV4A':;

SECTION_NUMBER 1
 '@BASEBOARD_FAB2_LIB.BASEBOARD_FAB2(SCH_1):PAGE185_I213@W_HDL.LMV431AIMFX-GP(CHIPS)':
 C_PATH='@baseboard_fab2_lib.baseboard_fab2(sch_1):page185_i213@w_hdl.\lmv431aim~
fx-gp\(chips)',
 P_PATH='@baseboard_fab2_lib.baseboard_fab2(sch_1):page185_i213@w_hdl.\lmv431aim~
fx-gp\(chips)',
 PATH='I213',
 DRAWING='@BASEBOARD_FAB2_LIB.BASEBOARD_FAB2(SCH_1):PAGE185',
 SEC_TYPE='DISCRET-G5',
 PHYS_PAGE='185',
 XY='(-6900,1400)',
 ROT='0',
 VER='1',
 VALUE='LMV431AIMFX-GP',
 PACK_TYPE='DISCRET-G5',
 PART_NUMBER='74.MV431.031',
 LOCATION='VR32W1',
 SEC='1',
 CDS_LIB='w_hdl',
 CDS_PART_NAME='LMV431AIMFX-GP_DISCRET-G5-LMV4A',
 PRIM_FILE='C:/<user>/w_hdl/lmv431aimfx#2dgp/chips/chips.prt';

PART_NAME
 WR8D30 'RES_0402-10.0K,1%,1/16W,CHIP,GA':
 ROOM='NV_DIMM';

SECTION_NUMBER 1
 '@BASEBOARD_FAB2_LIB.BASEBOARD_FAB2(SCH_1):PAGE89_I45@MSTR_DISCRETE.RES(CHIPS)':
 C_PATH='@baseboard_fab2_lib.baseboard_fab2(sch_1):page89_i45@mstr_discrete.res(~
chips)',
 P_PATH='@baseboard_fab2_lib.baseboard_fab2(sch_1):page89_i45@mstr_discrete.res(~
chips)',
 PATH='I45',
 DRAWING='@BASEBOARD_FAB2_LIB.BASEBOARD_FAB2(SCH_1):PAGE89',
 WATTAGE='1/16W',
 TOLERANCE='1%',
 SEC_TYPE='0402',
 MATERIAL='CHIP',
 BOM_COST='MEM_NV',
 PHYS_PAGE='89',
 XY='(1000,2500)',
 ROT='0',
 VER='1',
 VALUE='10.0K',
 PACK_TYPE='0402',
 PART_NUMBER='G21796-016',
 LOCATION='WR8D30',
 ROOM='NV_DIMM',
 SEC='1',
 CDS_LIB='mstr_discrete',
 CDS_PART_NAME='RES_0402-10.0K,1%,1/16W,CHIP,GA',
 PRIM_FILE='./archive_libs/mstr_discrete/res/chips/chips.prt';

PART_NAME
 XBT8G1 'VERT_BATT_3PIN_PIP-3PVERT,C686A':
 ROOM='SB_VRD';

SECTION_NUMBER 1
 '@BASEBOARD_FAB2_LIB.BASEBOARD_FAB2(SCH_1):PAGE196_I51@MSTR_DISCRETE.VERT_BATT_3PIN(CHIPS)':
 C_PATH='@baseboard_fab2_lib.baseboard_fab2(sch_1):page196_i51@mstr_discrete.ver~
t_batt_3pin(chips)',
 P_PATH='@baseboard_fab2_lib.baseboard_fab2(sch_1):page196_i51@mstr_discrete.ver~
t_batt_3pin(chips)',
 PATH='I51',
 DRAWING='@BASEBOARD_FAB2_LIB.BASEBOARD_FAB2(SCH_1):PAGE196',
 SEC_TYPE='PIP',
 MATERIAL='3PVERT',
 PHYS_PAGE='196',
 XY='(-4800,4550)',
 ROT='0',
 VER='1',
 PACK_TYPE='PIP',
 PART_NUMBER='C68619-005',
 LOCATION='XBT8G1',
 ROOM='SB_VRD',
 SEC='1',
 CDS_LIB='mstr_discrete',
 CDS_PART_NAME='VERT_BATT_3PIN_PIP-3PVERT,C686A',
 PRIM_FILE='./archive_libs/mstr_discrete/vert_batt_3pin/chips/chips.prt';

PART_NAME
 XLU1 'SOCKET_P_MECH_A_LEFT-P0,PLASTIA':
 ROOM='CPU0';

SECTION_NUMBER -1
 '@BASEBOARD_FAB2_LIB.BASEBOARD_FAB2(SCH_1):PAGE21_I217@CHPSET_LIB.SOCKET_P_MECH_A(CHIPS)':
 C_PATH='@baseboard_fab2_lib.baseboard_fab2(sch_1):page21_i217@chpset_lib.socket~
_p_mech_a(chips)',
 P_PATH='@baseboard_fab2_lib.baseboard_fab2(sch_1):page21_i217@chpset_lib.socket~
_p_mech_a(chips)',
 PATH='I217',
 DRAWING='@BASEBOARD_FAB2_LIB.BASEBOARD_FAB2(SCH_1):PAGE21',
 SKT_NUMBER='P0',
 MATERIAL='PLASTIC',
 BOM_COST='PROC_SOCKET',
 PHYS_PAGE='21',
 XY='(-7525,4150)',
 ROT='0',
 VER='1',
 PACK_TYPE='LEFT',
 PART_NUMBER='H37604-201',
 LOCATION='XLU1',
 ROOM='CPU0',
 CDS_LIB='chpset_lib',
 CDS_PART_NAME='SOCKET_P_MECH_A_LEFT-P0,PLASTIA',
 PRIM_FILE='./archive_libs/logical/socket_p_mech_a/chips/chips.prt';

PART_NAME
 XLU2 'SOCKET_P_MECH_A_LEFT-P0,PLASTIA':
 ROOM='CPU1';

SECTION_NUMBER -1
 '@BASEBOARD_FAB2_LIB.BASEBOARD_FAB2(SCH_1):PAGE55_I153@CHPSET_LIB.SOCKET_P_MECH_A(CHIPS)':
 C_PATH='@baseboard_fab2_lib.baseboard_fab2(sch_1):page55_i153@chpset_lib.socket~
_p_mech_a(chips)',
 P_PATH='@baseboard_fab2_lib.baseboard_fab2(sch_1):page55_i153@chpset_lib.socket~
_p_mech_a(chips)',
 PATH='I153',
 DRAWING='@BASEBOARD_FAB2_LIB.BASEBOARD_FAB2(SCH_1):PAGE55',
 SKT_NUMBER='P0',
 MATERIAL='PLASTIC',
 BOM_COST='PROC_SOCKET',
 PHYS_PAGE='55',
 XY='(6875,3725)',
 ROT='0',
 VER='1',
 PACK_TYPE='LEFT',
 PART_NUMBER='H37604-201',
 LOCATION='XLU2',
 ROOM='CPU1',
 CDS_LIB='chpset_lib',
 CDS_PART_NAME='SOCKET_P_MECH_A_LEFT-P0,PLASTIA',
 PRIM_FILE='./archive_libs/logical/socket_p_mech_a/chips/chips.prt';

PART_NAME
 XRU1 'SOCKET_P_MECH_A_RIGHT-P0,PLASTA':
 ROOM='CPU0';

SECTION_NUMBER -1
 '@BASEBOARD_FAB2_LIB.BASEBOARD_FAB2(SCH_1):PAGE21_I216@CHPSET_LIB.SOCKET_P_MECH_A(CHIPS)':
 C_PATH='@baseboard_fab2_lib.baseboard_fab2(sch_1):page21_i216@chpset_lib.socket~
_p_mech_a(chips)',
 P_PATH='@baseboard_fab2_lib.baseboard_fab2(sch_1):page21_i216@chpset_lib.socket~
_p_mech_a(chips)',
 PATH='I216',
 DRAWING='@BASEBOARD_FAB2_LIB.BASEBOARD_FAB2(SCH_1):PAGE21',
 SKT_NUMBER='P0',
 MATERIAL='PLASTIC',
 BOM_COST='PROC_SOCKET',
 PHYS_PAGE='21',
 XY='(-7525,4450)',
 ROT='0',
 VER='1',
 PACK_TYPE='RIGHT',
 PART_NUMBER='H37604-101',
 LOCATION='XRU1',
 ROOM='CPU0',
 CDS_LIB='chpset_lib',
 CDS_PART_NAME='SOCKET_P_MECH_A_RIGHT-P0,PLASTA',
 PRIM_FILE='./archive_libs/logical/socket_p_mech_a/chips/chips.prt';

PART_NAME
 XRU2 'SOCKET_P_MECH_A_RIGHT-P0,PLASTA':
 ROOM='CPU1';

SECTION_NUMBER -1
 '@BASEBOARD_FAB2_LIB.BASEBOARD_FAB2(SCH_1):PAGE55_I152@CHPSET_LIB.SOCKET_P_MECH_A(CHIPS)':
 C_PATH='@baseboard_fab2_lib.baseboard_fab2(sch_1):page55_i152@chpset_lib.socket~
_p_mech_a(chips)',
 P_PATH='@baseboard_fab2_lib.baseboard_fab2(sch_1):page55_i152@chpset_lib.socket~
_p_mech_a(chips)',
 PATH='I152',
 DRAWING='@BASEBOARD_FAB2_LIB.BASEBOARD_FAB2(SCH_1):PAGE55',
 SKT_NUMBER='P0',
 MATERIAL='PLASTIC',
 BOM_COST='PROC_SOCKET',
 PHYS_PAGE='55',
 XY='(6875,4000)',
 ROT='0',
 VER='1',
 PACK_TYPE='RIGHT',
 PART_NUMBER='H37604-101',
 LOCATION='XRU2',
 ROOM='CPU1',
 CDS_LIB='chpset_lib',
 CDS_PART_NAME='SOCKET_P_MECH_A_RIGHT-P0,PLASTA',
 PRIM_FILE='./archive_libs/logical/socket_p_mech_a/chips/chips.prt';

PART_NAME
 Y3F1 'OSC_C_6P10-156.25MHZ,OSC,G6383A':;

SECTION_NUMBER 1
 '@BASEBOARD_FAB2_LIB.BASEBOARD_FAB2(SCH_1):PAGE104_I72@MSTR_DISCRETE.OSC_C(CHIPS)':
 C_PATH='@baseboard_fab2_lib.baseboard_fab2(sch_1):page104_i72@mstr_discrete.osc~
_c(chips)',
 P_PATH='@baseboard_fab2_lib.baseboard_fab2(sch_1):page104_i72@mstr_discrete.osc~
_c(chips)',
 PATH='I72',
 DRAWING='@BASEBOARD_FAB2_LIB.BASEBOARD_FAB2(SCH_1):PAGE104',
 SEC_TYPE='6P10',
 MATERIAL='OSC',
 PHYS_PAGE='104',
 XY='(-3700,3925)',
 ROT='0',
 VER='17',
 VALUE='156.25MHZ',
 PACK_TYPE='6P10',
 PART_NUMBER='G63831-004',
 LOCATION='Y3F1',
 SEC='1',
 CDS_LIB='mstr_discrete',
 CDS_PART_NAME='OSC_C_6P10-156.25MHZ,OSC,G6383A',
 PRIM_FILE='./archive_libs/mstr_discrete/osc_c/chips/chips.prt';

PART_NAME
 Y6F1 'OSC_C_6P10-156.25MHZ,OSC,G6383A':;

SECTION_NUMBER 1
 '@BASEBOARD_FAB2_LIB.BASEBOARD_FAB2(SCH_1):PAGE104_I71@MSTR_DISCRETE.OSC_C(CHIPS)':
 C_PATH='@baseboard_fab2_lib.baseboard_fab2(sch_1):page104_i71@mstr_discrete.osc~
_c(chips)',
 P_PATH='@baseboard_fab2_lib.baseboard_fab2(sch_1):page104_i71@mstr_discrete.osc~
_c(chips)',
 PATH='I71',
 DRAWING='@BASEBOARD_FAB2_LIB.BASEBOARD_FAB2(SCH_1):PAGE104',
 SEC_TYPE='6P10',
 MATERIAL='OSC',
 PHYS_PAGE='104',
 XY='(-3400,4775)',
 ROT='0',
 VER='17',
 VALUE='156.25MHZ',
 PACK_TYPE='6P10',
 PART_NUMBER='G63831-004',
 LOCATION='Y6F1',
 SEC='1',
 CDS_LIB='mstr_discrete',
 CDS_PART_NAME='OSC_C_6P10-156.25MHZ,OSC,G6383A',
 PRIM_FILE='./archive_libs/mstr_discrete/osc_c/chips/chips.prt';

PART_NAME
 Y7C1 'CRYSTAL_2013-48.000MHZ,IC,D717A':
 ROOM='SB';

SECTION_NUMBER 1
 '@BASEBOARD_FAB2_LIB.BASEBOARD_FAB2(SCH_1):PAGE114_I49@MSTR_DISCRETE.CRYSTAL(CHIPS)':
 C_PATH='@baseboard_fab2_lib.baseboard_fab2(sch_1):page114_i49@mstr_discrete.cry~
stal(chips)',
 P_PATH='@baseboard_fab2_lib.baseboard_fab2(sch_1):page114_i49@mstr_discrete.cry~
stal(chips)',
 PATH='I49',
 DRAWING='@BASEBOARD_FAB2_LIB.BASEBOARD_FAB2(SCH_1):PAGE114',
 SEC_TYPE='2013',
 MATERIAL='IC',
 PHYS_PAGE='114',
 XY='(-1775,150)',
 ROT='0',
 VER='1',
 VALUE='48.000MHZ',
 PACK_TYPE='2013',
 PART_NUMBER='D71700-058',
 LOCATION='Y7C1',
 ROOM='SB',
 SEC='1',
 CDS_LIB='mstr_discrete',
 CDS_PART_NAME='CRYSTAL_2013-48.000MHZ,IC,D717A',
 PRIM_FILE='./archive_libs/mstr_discrete/crystal/chips/chips.prt';

PART_NAME
 Y7C2 'CRYSTAL_SM-32.768KHZ,IC,C13544A':
 ROOM='SB';

SECTION_NUMBER 1
 '@BASEBOARD_FAB2_LIB.BASEBOARD_FAB2(SCH_1):PAGE114_I55@MSTR_DISCRETE.CRYSTAL(CHIPS)':
 C_PATH='@baseboard_fab2_lib.baseboard_fab2(sch_1):page114_i55@mstr_discrete.cry~
stal(chips)',
 P_PATH='@baseboard_fab2_lib.baseboard_fab2(sch_1):page114_i55@mstr_discrete.cry~
stal(chips)',
 PATH='I55',
 DRAWING='@BASEBOARD_FAB2_LIB.BASEBOARD_FAB2(SCH_1):PAGE114',
 SEC_TYPE='SM',
 MATERIAL='IC',
 PHYS_PAGE='114',
 XY='(-25,125)',
 ROT='0',
 VER='1',
 VALUE='32.768KHZ',
 PACK_TYPE='SM',
 PART_NUMBER='C13544-023',
 LOCATION='Y7C2',
 ROOM='SB',
 SEC='1',
 CDS_LIB='mstr_discrete',
 CDS_PART_NAME='CRYSTAL_SM-32.768KHZ,IC,C13544A',
 PRIM_FILE='./archive_libs/mstr_discrete/crystal/chips/chips.prt';

PART_NAME
 Y8C1 'CRYSTAL_2013-25.000MHZ,IC,H196A':
 ROOM='SB';

SECTION_NUMBER 1
 '@BASEBOARD_FAB2_LIB.BASEBOARD_FAB2(SCH_1):PAGE118_I76@MSTR_DISCRETE.CRYSTAL(CHIPS)':
 C_PATH='@baseboard_fab2_lib.baseboard_fab2(sch_1):page118_i76@mstr_discrete.cry~
stal(chips)',
 P_PATH='@baseboard_fab2_lib.baseboard_fab2(sch_1):page118_i76@mstr_discrete.cry~
stal(chips)',
 PATH='I76',
 DRAWING='@BASEBOARD_FAB2_LIB.BASEBOARD_FAB2(SCH_1):PAGE118',
 SEC_TYPE='2013',
 MATERIAL='IC',
 BOM_COST='SB',
 PHYS_PAGE='118',
 XY='(-7400,850)',
 ROT='0',
 VER='1',
 VALUE='25.000MHZ',
 PACK_TYPE='2013',
 PART_NUMBER='H19611-001',
 LOCATION='Y8C1',
 ROOM='SB',
 SEC='1',
 CDS_LIB='mstr_discrete',
 CDS_PART_NAME='CRYSTAL_2013-25.000MHZ,IC,H196A',
 PRIM_FILE='./archive_libs/mstr_discrete/crystal/chips/chips.prt';

PART_NAME
 Y8F1 'CRYSTAL_2013LF-25.000MHZ,IC,D7B':
 ROOM='SYS_CLOCK';

SECTION_NUMBER 1
 '@BASEBOARD_FAB2_LIB.BASEBOARD_FAB2(SCH_1):PAGE101_I52@MSTR_DISCRETE.CRYSTAL(CHIPS)':
 C_PATH='@baseboard_fab2_lib.baseboard_fab2(sch_1):page101_i52@mstr_discrete.cry~
stal(chips)',
 P_PATH='@baseboard_fab2_lib.baseboard_fab2(sch_1):page101_i52@mstr_discrete.cry~
stal(chips)',
 PATH='I52',
 DRAWING='@BASEBOARD_FAB2_LIB.BASEBOARD_FAB2(SCH_1):PAGE101',
 POWER_GROUP='GND=GND',
 MATERIAL='IC',
 BOM_COST='SM_CONTROLLER',
 PHYS_PAGE='101',
 XY='(-7350,1050)',
 ROT='2',
 VER='3',
 VALUE='25.000MHZ',
 PACK_TYPE='2013LF',
 PART_NUMBER='D71700-033',
 LOCATION='Y8F1',
 ROOM='SYS_CLOCK',
 CDS_LIB='mstr_discrete',
 CDS_PART_NAME='CRYSTAL_2013LF-25.000MHZ,IC,D7A',
 PRIM_FILE='./archive_libs/mstr_discrete/crystal/chips/chips.prt';

PART_NAME
 Y9E1 'CRYSTAL_2013-25.000MHZ,IC,D717A':
 GROUP='NI_I210&RJ45',
 ROOM='NIC_SPRV';

SECTION_NUMBER 1
 '@BASEBOARD_FAB2_LIB.BASEBOARD_FAB2(SCH_1):PAGE139_I109@MSTR_DISCRETE.CRYSTAL(CHIPS)':
 C_PATH='@baseboard_fab2_lib.baseboard_fab2(sch_1):page139_i109@mstr_discrete.cr~
ystal(chips)',
 P_PATH='@baseboard_fab2_lib.baseboard_fab2(sch_1):page139_i109@mstr_discrete.cr~
ystal(chips)',
 PATH='I109',
 DRAWING='@BASEBOARD_FAB2_LIB.BASEBOARD_FAB2(SCH_1):PAGE139',
 SEC_TYPE='2013',
 MATERIAL='IC',
 BOM_COST='NT_GBE_BASE',
 PHYS_PAGE='139',
 XY='(-7525,1475)',
 ROT='0',
 VER='1',
 VALUE='25.000MHZ',
 PACK_TYPE='2013',
 PART_NUMBER='D71700-057',
 LOCATION='Y9E1',
 ROOM='NIC_SPRV',
 GROUP='NI_I210&RJ45',
 SEC='1',
 CDS_LIB='mstr_discrete',
 CDS_PART_NAME='CRYSTAL_2013-25.000MHZ,IC,D717A',
 PRIM_FILE='./archive_libs/mstr_discrete/crystal/chips/chips.prt';

PART_NAME
 Y9F2 'OSC_C_SM4-24MHZ,OSC,D34520-021':
 ROOM='BMC';

SECTION_NUMBER 1
 '@BASEBOARD_FAB2_LIB.BASEBOARD_FAB2(SCH_1):PAGE145_I8@MSTR_DISCRETE.OSC_C(CHIPS)':
 C_PATH='@baseboard_fab2_lib.baseboard_fab2(sch_1):page145_i8@mstr_discrete.osc_~
c(chips)',
 P_PATH='@baseboard_fab2_lib.baseboard_fab2(sch_1):page145_i8@mstr_discrete.osc_~
c(chips)',
 PATH='I8',
 DRAWING='@BASEBOARD_FAB2_LIB.BASEBOARD_FAB2(SCH_1):PAGE145',
 SEC_TYPE='SM4',
 MATERIAL='OSC',
 BOM_COST='SM_CONTROLLER',
 PHYS_PAGE='145',
 XY='(-5750,-650)',
 ROT='0',
 VER='11',
 VALUE='24MHZ',
 PACK_TYPE='SM4',
 PART_NUMBER='D34520-021',
 LOCATION='Y9F2',
 ROOM='BMC',
 SEC='1',
 CDS_LIB='mstr_discrete',
 CDS_PART_NAME='OSC_C_SM4-24MHZ,OSC,D34520-021',
 PRIM_FILE='./archive_libs/mstr_discrete/osc_c/chips/chips.prt';

END.
